G04 ================== begin FILE IDENTIFICATION RECORD ==================*
G04 Layout Name:  14545-sa.brd*
G04 Film Name:    NOTICE*
G04 File Format:  Gerber RS274X*
G04 File Origin:  Cadence Allegro 16.5-S056*
G04 Origin Date:  Fri Aug 01 17:58:32 2014*
G04 *
G04 Layer:  MANUFACTURING/THERMAL*
G04 *
G04 Offset:    (0.00 0.00)*
G04 Mirror:    No*
G04 Mode:      Positive*
G04 Rotation:  0*
G04 FullContactRelief:  No*
G04 UndefLineWidth:     6.00*
G04 ================== end FILE IDENTIFICATION RECORD ====================*
%FSLAX35Y35*MOIN*%
%IR0*IPPOS*OFA0.00000B0.00000*MIA0B0*SFA1.00000B1.00000*%
%ADD10C,.004*%
%ADD11C,.006*%
%ADD12C,.0033*%
%ADD13C,.0055*%
G75*
%LPD*%
G75*
G54D10*
G01X820594Y226868D02*
X808594Y228868D01*
G01X820594Y234868D02*
Y214868D01*
G01X808594Y228868D02*
Y224868D01*
G01D02*
X820594Y226868D01*
G01X796594D02*
X820594D01*
G01X850009Y308249D02*
X840009Y298249D01*
G01Y240889D02*
X890009D01*
G01X840009Y298249D02*
Y240889D01*
G01X810005Y307744D02*
X810009Y307740D01*
G01Y370889D02*
Y307740D01*
G01D02*
X820009Y297740D01*
G01D02*
Y240889D01*
G01X790009Y290889D02*
Y320889D01*
G01Y250889D02*
Y280889D01*
G01X770009Y290889D02*
X790009D01*
G01X770009Y280889D02*
Y290889D01*
G01X790009Y280889D02*
X770009D01*
G01Y250889D02*
X790009D01*
G01X820009Y240889D02*
X770009D01*
G01D02*
Y250889D01*
G01X838514Y392548D02*
Y388548D01*
G01X850514Y390548D02*
X838514Y392548D01*
G01Y388548D02*
X850514Y390548D01*
G01X810514Y402548D02*
Y382548D01*
G01X822514Y388548D02*
Y392548D01*
G01X810514Y390548D02*
X822514Y388548D01*
G01Y392548D02*
X810514Y390548D01*
G01D02*
X850514D01*
G01X790009Y330889D02*
Y360889D01*
G01X770009Y370889D02*
X810009D01*
G01X770009Y360889D02*
Y370889D01*
G01X790009Y360889D02*
X770009D01*
G01Y330889D02*
X790009D01*
G01X770009Y320889D02*
Y330889D01*
G01X790009Y320889D02*
X770009D01*
G01X852594Y224868D02*
Y228868D01*
G01X859454Y226868D02*
X840594D01*
G01X852594Y228868D02*
X840594Y226868D01*
G01Y214868D02*
Y234868D01*
G01Y226868D02*
X852594Y224868D01*
G01X895009Y290889D02*
X961000D01*
G01X845009Y298249D02*
X961000D01*
G01X890009Y280889D02*
X890000Y290800D01*
G01X890009Y240889D02*
Y250889D01*
G01X870009Y290889D02*
Y320889D01*
G01X890009Y290889D02*
X870009D01*
G01Y280889D02*
X890009D01*
G01X870009Y250889D02*
Y280889D01*
G01X890009Y250889D02*
X870009D01*
G01X850009Y370889D02*
Y308249D01*
G01X890009Y360889D02*
Y370889D01*
G01Y320889D02*
Y330889D01*
G01X870009Y360889D02*
X890009D01*
G01X870009Y330889D02*
Y360889D01*
G01X890009Y330889D02*
X870009D01*
G01Y320889D02*
X890009D01*
G01X850514Y402548D02*
Y382548D01*
G01Y390548D02*
X859374D01*
G01X890009Y370889D02*
X850009D01*
G01X954000Y310249D02*
X956000Y298249D01*
X958000Y310249D01*
X954000D01*
G01X956000Y322249D02*
Y298249D01*
G01X958000Y278889D02*
X956000Y290889D01*
X954000Y278889D01*
X958000D01*
G01X956000Y266889D02*
Y290889D01*
G01X1081654Y282388D02*
X1101654D01*
G01X1081654Y292388D02*
Y282388D01*
G01X1101654Y292388D02*
X1081654D01*
G01X1101654Y252388D02*
X1081654D01*
G01Y242388D02*
X1121654D01*
G01X1081654Y252388D02*
Y242388D01*
G01X1131654Y372388D02*
X1081654D01*
G01Y362388D02*
X1101654D01*
G01X1081654Y372388D02*
Y362388D01*
G01Y322388D02*
X1101654D01*
G01X1081654Y332388D02*
Y322388D01*
G01X1101654Y332388D02*
X1081654D01*
G01X1149654Y226388D02*
Y222388D01*
G01X1161654Y224388D02*
X1149654Y226388D01*
G01Y222388D02*
X1161654Y224388D01*
G01D02*
X1170514D01*
G01X1161654Y236388D02*
Y216388D01*
G01X1133654Y222388D02*
Y226388D01*
G01X1121654Y224388D02*
X1133654Y222388D01*
G01Y226388D02*
X1121654Y224388D01*
G01D02*
X1161654D01*
G01X1121654Y236388D02*
Y216388D01*
G01X1161658Y305533D02*
X1161654Y305537D01*
G01D02*
X1151654Y315537D01*
G01X1161654Y242388D02*
Y305537D01*
G01X1201654Y242388D02*
X1161654D01*
G01X1131654Y315028D02*
Y372388D01*
G01X1121654Y305028D02*
X1131654Y315028D01*
G01X1121654Y242388D02*
Y305028D01*
G01X1101654Y322388D02*
Y292388D01*
G01Y282388D02*
Y252388D01*
G01X1163654Y390388D02*
Y394388D01*
G01X1170514Y392388D02*
X1151654D01*
G01D02*
X1163654Y390388D01*
G01Y394388D02*
X1151654Y392388D01*
G01Y380388D02*
Y400388D01*
G01Y372388D02*
X1201654D01*
G01X1151654Y315537D02*
Y372388D01*
G01X1119654Y394388D02*
Y390388D01*
G01X1131654Y392388D02*
X1119654Y394388D01*
G01Y390388D02*
X1131654Y392388D01*
G01Y400388D02*
Y380388D01*
G01X1107654Y392388D02*
X1131654D01*
G01X1101654Y362388D02*
Y332388D01*
G01X1201654Y292388D02*
Y282388D01*
G01Y252388D02*
Y242388D01*
G01Y282388D02*
X1181654D01*
G01Y292388D02*
X1201654D01*
G01X1181654Y322388D02*
Y292388D01*
G01Y252388D02*
X1201654D01*
G01X1181654Y282388D02*
Y252388D01*
G01X1201654Y372388D02*
Y362388D01*
G01Y332388D02*
Y322388D01*
G01Y362388D02*
X1181654D01*
G01X1201654Y322388D02*
X1181654D01*
G01Y332388D02*
X1201654D01*
G01X1181654Y362388D02*
Y332388D01*
G54D11*
G01X4300Y539700D02*
X4250D01*
G01X54300Y770700D02*
X54250D01*
G01X518250Y-580300D02*
X518300D01*
G01X849500Y25549D02*
X821000Y25500D01*
G01X837503Y23528D02*
X849500Y25549D01*
X837497Y27528D01*
X837503Y23528D01*
G01X827500Y709629D02*
X830000Y694629D01*
X832500Y709629D01*
X827500D01*
G01X830000Y731875D02*
Y694629D01*
G01X931340D02*
X820000D01*
G01X832500Y780829D02*
X830000Y795829D01*
X827500Y780829D01*
X832500D01*
G01X830000Y763125D02*
Y795829D01*
G01X846340D02*
X820000D01*
G01X849500Y25500D02*
Y97500D01*
X893500D01*
Y25500D01*
X849500D01*
G01X903500D02*
X944500D01*
G01X903500Y97500D02*
X944500D01*
G01X878500Y110000D02*
X893500Y112500D01*
X878500Y115000D01*
Y110000D01*
G01X901475Y112500D02*
X893500D01*
G01X864500Y115000D02*
X849500Y112500D01*
X864500Y110000D01*
Y115000D01*
G01X893500Y112500D02*
X849500D01*
G01X893500Y107500D02*
Y122500D01*
G01X849500Y107500D02*
Y122500D01*
G01X932000Y40500D02*
X934500Y25500D01*
X937000Y40500D01*
X932000D01*
G01X934500Y49875D02*
Y25500D01*
G01X937000Y82500D02*
X934500Y97500D01*
X932000Y82500D01*
X937000D01*
G01X934500Y81125D02*
Y97500D01*
G01X1156654Y315537D02*
X1274500D01*
G01X1114953Y698479D02*
X1131500Y687000D01*
X1132500D01*
G01X1119916Y696861D02*
X1114953Y698479D01*
X1118206Y694397D01*
X1119916Y696861D01*
G01X1206654Y322388D02*
X1274500D01*
G01X1271500Y303537D02*
X1269500Y315537D01*
X1267500Y303537D01*
X1271500D01*
G01X1269500Y291537D02*
Y315537D01*
G01X1267500Y334388D02*
X1269500Y322388D01*
X1271500Y334388D01*
X1267500D01*
G01X1269500Y350200D02*
Y322388D01*
G01X11833Y34500D02*
Y39500D01*
X13917D01*
X14583Y39250D01*
X15000Y38917D01*
X15167Y38250D01*
X15000Y37583D01*
X14500Y37167D01*
X13917Y36917D01*
X11833D01*
G01X13917D02*
X15167Y34500D01*
G01X19100D02*
X18600Y34583D01*
X18100Y34917D01*
X17767Y35500D01*
X17600Y36167D01*
X17767Y36833D01*
X18100Y37417D01*
X18600Y37750D01*
X19100Y37833D01*
X19600Y37750D01*
X20100Y37417D01*
X20433Y36833D01*
X20517Y36167D01*
X20433Y35500D01*
X20100Y34917D01*
X19600Y34583D01*
X19100Y34500D01*
G01X23283Y37833D02*
Y35500D01*
X23617Y34917D01*
X24117Y34583D01*
X24700Y34500D01*
X25283Y34583D01*
X25783Y34917D01*
X26117Y35500D01*
G01Y34500D02*
Y37833D01*
G01X30300Y39500D02*
Y34500D01*
G01X29133Y37833D02*
X31467D01*
G01X35900D02*
Y34500D01*
G01Y39167D02*
X35733Y39250D01*
Y39417D01*
X35900Y39500D01*
X36067Y39417D01*
Y39250D01*
X35900Y39167D01*
G01X40083Y34500D02*
Y37833D01*
G01Y37000D02*
X40417Y37417D01*
X40917Y37750D01*
X41583Y37833D01*
X42167Y37750D01*
X42667Y37417D01*
X42917Y36833D01*
Y34500D01*
G01X45933Y33250D02*
X46517Y32917D01*
X47183Y32833D01*
X47767Y32917D01*
X48267Y33333D01*
X48600Y33917D01*
Y37833D01*
G01Y37167D02*
X48267Y37500D01*
X47767Y37750D01*
X47183Y37833D01*
X46517Y37667D01*
X46100Y37333D01*
X45767Y36750D01*
X45600Y36167D01*
X45683Y35667D01*
X46017Y35083D01*
X46517Y34667D01*
X47183Y34500D01*
X47683Y34583D01*
X48267Y34917D01*
X48600Y35250D01*
G01X0Y0D02*
X694500D01*
G01X0Y729000D02*
Y0D01*
G01X11750Y92667D02*
X12417Y92250D01*
X13167Y92000D01*
X13833D01*
X14500Y92250D01*
X15000Y92667D01*
X15250Y93250D01*
X15083Y93833D01*
X14667Y94333D01*
X13917Y94667D01*
X12917Y94833D01*
X12333Y95167D01*
X12083Y95750D01*
X12250Y96333D01*
X12667Y96750D01*
X13250Y97000D01*
X13833D01*
X14417Y96833D01*
X14917Y96417D01*
G01X19100Y95333D02*
Y92000D01*
G01Y96667D02*
X18933Y96750D01*
Y96917D01*
X19100Y97000D01*
X19267Y96917D01*
Y96750D01*
X19100Y96667D01*
G01X24700Y92000D02*
Y97000D01*
G01X28883Y92000D02*
Y97000D01*
G01X31550Y95333D02*
X28883Y93417D01*
G01X29967Y94167D02*
X31717Y92000D01*
G01X34650Y92583D02*
X35067Y92250D01*
X35650Y92000D01*
X36150D01*
X36650Y92167D01*
X36983Y92417D01*
X37150Y92750D01*
X37067Y93250D01*
X36733Y93500D01*
X35233Y94000D01*
X34900Y94583D01*
X35067Y95000D01*
X35400Y95250D01*
X35900Y95333D01*
X36400Y95250D01*
X36900Y95000D01*
G01X42833Y94917D02*
X42250Y95250D01*
X41750Y95333D01*
X41083Y95167D01*
X40583Y94833D01*
X40250Y94250D01*
X40167Y93667D01*
X40250Y93083D01*
X40583Y92583D01*
X41083Y92167D01*
X41750Y92000D01*
X42333Y92167D01*
X42833Y92500D01*
G01X45933Y92000D02*
Y95333D01*
G01Y94667D02*
X46350Y95000D01*
X46767Y95250D01*
X47350Y95333D01*
X47767Y95250D01*
X48267Y95000D01*
G01X51450Y94250D02*
X54117D01*
X53867Y94833D01*
X53450Y95167D01*
X52867Y95333D01*
X52283Y95250D01*
X51783Y95000D01*
X51450Y94417D01*
X51283Y93917D01*
Y93417D01*
X51450Y92917D01*
X51867Y92417D01*
X52367Y92083D01*
X52950Y92000D01*
X53533Y92167D01*
X54117Y92667D01*
G01X57050Y94250D02*
X59717D01*
X59467Y94833D01*
X59050Y95167D01*
X58467Y95333D01*
X57883Y95250D01*
X57383Y95000D01*
X57050Y94417D01*
X56883Y93917D01*
Y93417D01*
X57050Y92917D01*
X57467Y92417D01*
X57967Y92083D01*
X58550Y92000D01*
X59133Y92167D01*
X59717Y92667D01*
G01X62483Y92000D02*
Y95333D01*
G01Y94500D02*
X62817Y94917D01*
X63317Y95250D01*
X63983Y95333D01*
X64567Y95250D01*
X65067Y94917D01*
X65317Y94333D01*
Y92000D01*
G01X11750Y137667D02*
X12417Y137250D01*
X13167Y137000D01*
X13833D01*
X14500Y137250D01*
X15000Y137667D01*
X15250Y138250D01*
X15083Y138833D01*
X14667Y139333D01*
X13917Y139667D01*
X12917Y139833D01*
X12333Y140167D01*
X12083Y140750D01*
X12250Y141333D01*
X12667Y141750D01*
X13250Y142000D01*
X13833D01*
X14417Y141833D01*
X14917Y141417D01*
G01X19100Y137000D02*
X18600Y137083D01*
X18100Y137417D01*
X17767Y138000D01*
X17600Y138667D01*
X17767Y139333D01*
X18100Y139917D01*
X18600Y140250D01*
X19100Y140333D01*
X19600Y140250D01*
X20100Y139917D01*
X20433Y139333D01*
X20517Y138667D01*
X20433Y138000D01*
X20100Y137417D01*
X19600Y137083D01*
X19100Y137000D01*
G01X24700D02*
Y142000D01*
G01X31800D02*
Y137000D01*
G01Y137750D02*
X31467Y137333D01*
X30967Y137083D01*
X30383Y137000D01*
X29717Y137167D01*
X29217Y137583D01*
X28883Y138083D01*
X28800Y138667D01*
X28883Y139250D01*
X29217Y139750D01*
X29717Y140167D01*
X30383Y140333D01*
X30967Y140250D01*
X31383Y140083D01*
X31800Y139750D01*
G01X34650Y139250D02*
X37317D01*
X37067Y139833D01*
X36650Y140167D01*
X36067Y140333D01*
X35483Y140250D01*
X34983Y140000D01*
X34650Y139417D01*
X34483Y138917D01*
Y138417D01*
X34650Y137917D01*
X35067Y137417D01*
X35567Y137083D01*
X36150Y137000D01*
X36733Y137167D01*
X37317Y137667D01*
G01X40333Y137000D02*
Y140333D01*
G01Y139667D02*
X40750Y140000D01*
X41167Y140250D01*
X41750Y140333D01*
X42167Y140250D01*
X42667Y140000D01*
G01X50200Y137000D02*
Y140333D01*
G01Y139417D02*
X50450Y139833D01*
X50867Y140167D01*
X51450Y140333D01*
X52033Y140167D01*
X52450Y139833D01*
X52700Y139417D01*
Y137000D01*
G01Y139417D02*
X52950Y139833D01*
X53367Y140167D01*
X53950Y140333D01*
X54533Y140167D01*
X54950Y139833D01*
X55200Y139333D01*
Y137000D01*
G01X59800D02*
Y140333D01*
G01Y139750D02*
X59467Y140083D01*
X58967Y140250D01*
X58383Y140333D01*
X57800Y140167D01*
X57300Y139833D01*
X56967Y139333D01*
X56800Y138667D01*
X56967Y138000D01*
X57300Y137500D01*
X57800Y137167D01*
X58383Y137000D01*
X58967Y137083D01*
X59467Y137333D01*
X59800Y137667D01*
G01X62650Y137583D02*
X63067Y137250D01*
X63650Y137000D01*
X64150D01*
X64650Y137167D01*
X64983Y137417D01*
X65150Y137750D01*
X65067Y138250D01*
X64733Y138500D01*
X63233Y139000D01*
X62900Y139583D01*
X63067Y140000D01*
X63400Y140250D01*
X63900Y140333D01*
X64400Y140250D01*
X64900Y140000D01*
G01X68083Y137000D02*
Y142000D01*
G01X70750Y140333D02*
X68083Y138417D01*
G01X69167Y139167D02*
X70917Y137000D01*
G01X0Y117000D02*
X694500D01*
G01X0Y72000D02*
X694500D01*
G01X15167Y210500D02*
X11833D01*
Y215500D01*
X15167D01*
G01X13833Y213083D02*
X11833D01*
G01X19100Y215500D02*
Y210500D01*
G01X17933Y213833D02*
X20267D01*
G01X26033Y213417D02*
X25450Y213750D01*
X24950Y213833D01*
X24283Y213667D01*
X23783Y213333D01*
X23450Y212750D01*
X23367Y212167D01*
X23450Y211583D01*
X23783Y211083D01*
X24283Y210667D01*
X24950Y210500D01*
X25533Y210667D01*
X26033Y211000D01*
G01X28883Y210500D02*
Y215500D01*
G01Y213083D02*
X29300Y213500D01*
X29717Y213750D01*
X30383Y213833D01*
X30883Y213750D01*
X31467Y213417D01*
X31717Y212917D01*
Y210500D01*
G01X0Y162000D02*
X694500D01*
G01X15167Y258000D02*
X11833D01*
Y263000D01*
X15167D01*
G01X13833Y260583D02*
X11833D01*
G01X17850Y261333D02*
X20350Y258000D01*
G01Y261333D02*
X17850Y258000D01*
G01X24700Y263000D02*
Y258000D01*
G01X23533Y261333D02*
X25867D01*
G01X29050Y260250D02*
X31717D01*
X31467Y260833D01*
X31050Y261167D01*
X30467Y261333D01*
X29883Y261250D01*
X29383Y261000D01*
X29050Y260417D01*
X28883Y259917D01*
Y259417D01*
X29050Y258917D01*
X29467Y258417D01*
X29967Y258083D01*
X30550Y258000D01*
X31133Y258167D01*
X31717Y258667D01*
G01X34733Y258000D02*
Y261333D01*
G01Y260667D02*
X35150Y261000D01*
X35567Y261250D01*
X36150Y261333D01*
X36567Y261250D01*
X37067Y261000D01*
G01X40083Y258000D02*
Y261333D01*
G01Y260500D02*
X40417Y260917D01*
X40917Y261250D01*
X41583Y261333D01*
X42167Y261250D01*
X42667Y260917D01*
X42917Y260333D01*
Y258000D01*
G01X48600D02*
Y261333D01*
G01Y260750D02*
X48267Y261083D01*
X47767Y261250D01*
X47183Y261333D01*
X46600Y261167D01*
X46100Y260833D01*
X45767Y260333D01*
X45600Y259667D01*
X45767Y259000D01*
X46100Y258500D01*
X46600Y258167D01*
X47183Y258000D01*
X47767Y258083D01*
X48267Y258333D01*
X48600Y258667D01*
G01X52700Y258000D02*
Y263000D01*
G01X63900Y258000D02*
Y263000D01*
G01X71000Y258000D02*
Y261333D01*
G01Y260750D02*
X70667Y261083D01*
X70167Y261250D01*
X69583Y261333D01*
X69000Y261167D01*
X68500Y260833D01*
X68167Y260333D01*
X68000Y259667D01*
X68167Y259000D01*
X68500Y258500D01*
X69000Y258167D01*
X69583Y258000D01*
X70167Y258083D01*
X70667Y258333D01*
X71000Y258667D01*
G01X73350Y256500D02*
X73850Y256333D01*
X74517Y256500D01*
X74933Y256833D01*
X75267Y257250D01*
X75767Y258583D01*
X76850Y261333D01*
G01X74183D02*
X75767Y258583D01*
G01X79450Y260250D02*
X82117D01*
X81867Y260833D01*
X81450Y261167D01*
X80867Y261333D01*
X80283Y261250D01*
X79783Y261000D01*
X79450Y260417D01*
X79283Y259917D01*
Y259417D01*
X79450Y258917D01*
X79867Y258417D01*
X80367Y258083D01*
X80950Y258000D01*
X81533Y258167D01*
X82117Y258667D01*
G01X85133Y258000D02*
Y261333D01*
G01Y260667D02*
X85550Y261000D01*
X85967Y261250D01*
X86550Y261333D01*
X86967Y261250D01*
X87467Y261000D01*
G01X15333Y292583D02*
X14833Y292833D01*
X14250Y293000D01*
X13583D01*
X12833Y292750D01*
X12250Y292333D01*
X11833Y291833D01*
X11500Y291000D01*
X11417Y290250D01*
X11583Y289500D01*
X11833Y289000D01*
X12333Y288500D01*
X12917Y288167D01*
X13500Y288000D01*
X14083D01*
X14667Y288167D01*
X15167Y288417D01*
X15583Y288750D01*
G01X19100Y288000D02*
X18600Y288083D01*
X18100Y288417D01*
X17767Y289000D01*
X17600Y289667D01*
X17767Y290333D01*
X18100Y290917D01*
X18600Y291250D01*
X19100Y291333D01*
X19600Y291250D01*
X20100Y290917D01*
X20433Y290333D01*
X20517Y289667D01*
X20433Y289000D01*
X20100Y288417D01*
X19600Y288083D01*
X19100Y288000D01*
G01X23200Y286333D02*
Y291333D01*
G01Y290583D02*
X23617Y291000D01*
X24033Y291250D01*
X24700Y291333D01*
X25283Y291250D01*
X25867Y290833D01*
X26117Y290250D01*
X26200Y289667D01*
X26117Y289083D01*
X25867Y288500D01*
X25367Y288167D01*
X24700Y288000D01*
X24117Y288083D01*
X23533Y288333D01*
X23200Y288667D01*
G01X28800Y286333D02*
Y291333D01*
G01Y290583D02*
X29217Y291000D01*
X29633Y291250D01*
X30300Y291333D01*
X30883Y291250D01*
X31467Y290833D01*
X31717Y290250D01*
X31800Y289667D01*
X31717Y289083D01*
X31467Y288500D01*
X30967Y288167D01*
X30300Y288000D01*
X29717Y288083D01*
X29133Y288333D01*
X28800Y288667D01*
G01X34650Y290250D02*
X37317D01*
X37067Y290833D01*
X36650Y291167D01*
X36067Y291333D01*
X35483Y291250D01*
X34983Y291000D01*
X34650Y290417D01*
X34483Y289917D01*
Y289417D01*
X34650Y288917D01*
X35067Y288417D01*
X35567Y288083D01*
X36150Y288000D01*
X36733Y288167D01*
X37317Y288667D01*
G01X40333Y288000D02*
Y291333D01*
G01Y290667D02*
X40750Y291000D01*
X41167Y291250D01*
X41750Y291333D01*
X42167Y291250D01*
X42667Y291000D01*
G01X51033Y288000D02*
Y293000D01*
X53033D01*
X53700Y292750D01*
X54200Y292167D01*
X54367Y291500D01*
X54200Y290833D01*
X53783Y290333D01*
X53033Y290083D01*
X51033D01*
G01X58300Y288000D02*
Y293000D01*
G01X65400Y288000D02*
Y291333D01*
G01Y290750D02*
X65067Y291083D01*
X64567Y291250D01*
X63983Y291333D01*
X63400Y291167D01*
X62900Y290833D01*
X62567Y290333D01*
X62400Y289667D01*
X62567Y289000D01*
X62900Y288500D01*
X63400Y288167D01*
X63983Y288000D01*
X64567Y288083D01*
X65067Y288333D01*
X65400Y288667D01*
G01X69500Y293000D02*
Y288000D01*
G01X68333Y291333D02*
X70667D01*
G01X75100D02*
Y288000D01*
G01Y292667D02*
X74933Y292750D01*
Y292917D01*
X75100Y293000D01*
X75267Y292917D01*
Y292750D01*
X75100Y292667D01*
G01X79283Y288000D02*
Y291333D01*
G01Y290500D02*
X79617Y290917D01*
X80117Y291250D01*
X80783Y291333D01*
X81367Y291250D01*
X81867Y290917D01*
X82117Y290333D01*
Y288000D01*
G01X85133Y286750D02*
X85717Y286417D01*
X86383Y286333D01*
X86967Y286417D01*
X87467Y286833D01*
X87800Y287417D01*
Y291333D01*
G01Y290667D02*
X87467Y291000D01*
X86967Y291250D01*
X86383Y291333D01*
X85717Y291167D01*
X85300Y290833D01*
X84967Y290250D01*
X84800Y289667D01*
X84883Y289167D01*
X85217Y288583D01*
X85717Y288167D01*
X86383Y288000D01*
X86883Y288083D01*
X87467Y288417D01*
X87800Y288750D01*
G01X0Y252000D02*
X694500D01*
G01X0Y267000D02*
X694500D01*
G01X1500Y324000D02*
X694500D01*
G01X11667Y470500D02*
Y475500D01*
X13333D01*
X14000Y475250D01*
X14500Y474917D01*
X14917Y474417D01*
X15250Y473833D01*
X15333Y473000D01*
X15250Y472167D01*
X14917Y471583D01*
X14500Y471083D01*
X14000Y470750D01*
X13333Y470500D01*
X11667D01*
G01X17933D02*
Y473833D01*
G01Y473167D02*
X18350Y473500D01*
X18767Y473750D01*
X19350Y473833D01*
X19767Y473750D01*
X20267Y473500D01*
G01X24700Y473833D02*
Y470500D01*
G01Y475167D02*
X24533Y475250D01*
Y475417D01*
X24700Y475500D01*
X24867Y475417D01*
Y475250D01*
X24700Y475167D01*
G01X30300Y470500D02*
Y475500D01*
G01X35900Y470500D02*
Y475500D01*
G01X12500Y636500D02*
X14500D01*
G01X13500D02*
Y631500D01*
G01X12500D02*
X14500D01*
G01X17683D02*
Y634833D01*
G01Y634000D02*
X18017Y634417D01*
X18517Y634750D01*
X19183Y634833D01*
X19767Y634750D01*
X20267Y634417D01*
X20517Y633833D01*
Y631500D01*
G01X23283D02*
Y634833D01*
G01Y634000D02*
X23617Y634417D01*
X24117Y634750D01*
X24783Y634833D01*
X25367Y634750D01*
X25867Y634417D01*
X26117Y633833D01*
Y631500D01*
G01X29050Y633750D02*
X31717D01*
X31467Y634333D01*
X31050Y634667D01*
X30467Y634833D01*
X29883Y634750D01*
X29383Y634500D01*
X29050Y633917D01*
X28883Y633417D01*
Y632917D01*
X29050Y632417D01*
X29467Y631917D01*
X29967Y631583D01*
X30550Y631500D01*
X31133Y631667D01*
X31717Y632167D01*
G01X34733Y631500D02*
Y634833D01*
G01Y634167D02*
X35150Y634500D01*
X35567Y634750D01*
X36150Y634833D01*
X36567Y634750D01*
X37067Y634500D01*
G01X47100Y631500D02*
Y636500D01*
G01X54200Y631500D02*
Y634833D01*
G01Y634250D02*
X53867Y634583D01*
X53367Y634750D01*
X52783Y634833D01*
X52200Y634667D01*
X51700Y634333D01*
X51367Y633833D01*
X51200Y633167D01*
X51367Y632500D01*
X51700Y632000D01*
X52200Y631667D01*
X52783Y631500D01*
X53367Y631583D01*
X53867Y631833D01*
X54200Y632167D01*
G01X56550Y630000D02*
X57050Y629833D01*
X57717Y630000D01*
X58133Y630333D01*
X58467Y630750D01*
X58967Y632083D01*
X60050Y634833D01*
G01X57383D02*
X58967Y632083D01*
G01X62650Y633750D02*
X65317D01*
X65067Y634333D01*
X64650Y634667D01*
X64067Y634833D01*
X63483Y634750D01*
X62983Y634500D01*
X62650Y633917D01*
X62483Y633417D01*
Y632917D01*
X62650Y632417D01*
X63067Y631917D01*
X63567Y631583D01*
X64150Y631500D01*
X64733Y631667D01*
X65317Y632167D01*
G01X68333Y631500D02*
Y634833D01*
G01Y634167D02*
X68750Y634500D01*
X69167Y634750D01*
X69750Y634833D01*
X70167Y634750D01*
X70667Y634500D01*
G01X0Y610500D02*
X694500D01*
G01X9917Y693667D02*
X10417Y694167D01*
X11000Y694417D01*
X11667Y694500D01*
X12500Y694333D01*
X13083Y693917D01*
X13250Y693417D01*
X13167Y692917D01*
X12833Y692500D01*
X11167Y691667D01*
X10417Y691083D01*
X9917Y690250D01*
X9750Y689500D01*
X13250D01*
G01X17100Y689333D02*
X16933Y689417D01*
Y689583D01*
X17100Y689667D01*
X17267Y689583D01*
Y689417D01*
X17100Y689333D01*
G01X22700Y694500D02*
Y689500D01*
G01X20783Y694500D02*
X24617D01*
G01X28300Y689500D02*
X27800Y689583D01*
X27300Y689917D01*
X26967Y690500D01*
X26800Y691167D01*
X26967Y691833D01*
X27300Y692417D01*
X27800Y692750D01*
X28300Y692833D01*
X28800Y692750D01*
X29300Y692417D01*
X29633Y691833D01*
X29717Y691167D01*
X29633Y690500D01*
X29300Y689917D01*
X28800Y689583D01*
X28300Y689500D01*
G01X33900D02*
Y694500D01*
G01X38250Y691750D02*
X40917D01*
X40667Y692333D01*
X40250Y692667D01*
X39667Y692833D01*
X39083Y692750D01*
X38583Y692500D01*
X38250Y691917D01*
X38083Y691417D01*
Y690917D01*
X38250Y690417D01*
X38667Y689917D01*
X39167Y689583D01*
X39750Y689500D01*
X40333Y689667D01*
X40917Y690167D01*
G01X43933Y689500D02*
Y692833D01*
G01Y692167D02*
X44350Y692500D01*
X44767Y692750D01*
X45350Y692833D01*
X45767Y692750D01*
X46267Y692500D01*
G01X52200Y689500D02*
Y692833D01*
G01Y692250D02*
X51867Y692583D01*
X51367Y692750D01*
X50783Y692833D01*
X50200Y692667D01*
X49700Y692333D01*
X49367Y691833D01*
X49200Y691167D01*
X49367Y690500D01*
X49700Y690000D01*
X50200Y689667D01*
X50783Y689500D01*
X51367Y689583D01*
X51867Y689833D01*
X52200Y690167D01*
G01X54883Y689500D02*
Y692833D01*
G01Y692000D02*
X55217Y692417D01*
X55717Y692750D01*
X56383Y692833D01*
X56967Y692750D01*
X57467Y692417D01*
X57717Y691833D01*
Y689500D01*
G01X63233Y692417D02*
X62650Y692750D01*
X62150Y692833D01*
X61483Y692667D01*
X60983Y692333D01*
X60650Y691750D01*
X60567Y691167D01*
X60650Y690583D01*
X60983Y690083D01*
X61483Y689667D01*
X62150Y689500D01*
X62733Y689667D01*
X63233Y690000D01*
G01X66250Y691750D02*
X68917D01*
X68667Y692333D01*
X68250Y692667D01*
X67667Y692833D01*
X67083Y692750D01*
X66583Y692500D01*
X66250Y691917D01*
X66083Y691417D01*
Y690917D01*
X66250Y690417D01*
X66667Y689917D01*
X67167Y689583D01*
X67750Y689500D01*
X68333Y689667D01*
X68917Y690167D01*
G01X78700Y694500D02*
Y689500D01*
G01X77533Y692833D02*
X79867D01*
G01X85800Y689500D02*
Y692833D01*
G01Y692250D02*
X85467Y692583D01*
X84967Y692750D01*
X84383Y692833D01*
X83800Y692667D01*
X83300Y692333D01*
X82967Y691833D01*
X82800Y691167D01*
X82967Y690500D01*
X83300Y690000D01*
X83800Y689667D01*
X84383Y689500D01*
X84967Y689583D01*
X85467Y689833D01*
X85800Y690167D01*
G01X88400Y689500D02*
Y694500D01*
G01Y692000D02*
X88817Y692500D01*
X89317Y692750D01*
X89817Y692833D01*
X90567Y692667D01*
X91067Y692333D01*
X91400Y691750D01*
Y691083D01*
X91233Y690417D01*
X90900Y689917D01*
X90317Y689583D01*
X89817Y689500D01*
X89317Y689583D01*
X88817Y689833D01*
X88400Y690250D01*
G01X95500Y689500D02*
Y694500D01*
G01X99850Y691750D02*
X102517D01*
X102267Y692333D01*
X101850Y692667D01*
X101267Y692833D01*
X100683Y692750D01*
X100183Y692500D01*
X99850Y691917D01*
X99683Y691417D01*
Y690917D01*
X99850Y690417D01*
X100267Y689917D01*
X100767Y689583D01*
X101350Y689500D01*
X101933Y689667D01*
X102517Y690167D01*
G01X106700Y689333D02*
X106533Y689417D01*
Y689583D01*
X106700Y689667D01*
X106867Y689583D01*
Y689417D01*
X106700Y689333D01*
G01Y691583D02*
X106533Y691667D01*
Y691833D01*
X106700Y691917D01*
X106867Y691833D01*
Y691667D01*
X106700Y691583D01*
G01X0Y679000D02*
X694500D01*
G01X-1000Y654000D02*
X694500D01*
G01X0Y850500D02*
Y709000D01*
X694500D01*
Y850500D01*
G01X7000Y832500D02*
Y837500D01*
X6000Y836500D01*
G01Y832500D02*
X8000D01*
G01X12600Y832333D02*
X12433Y832417D01*
Y832583D01*
X12600Y832667D01*
X12767Y832583D01*
Y832417D01*
X12600Y832333D01*
G01X16450Y833167D02*
X17117Y832750D01*
X17867Y832500D01*
X18533D01*
X19200Y832750D01*
X19700Y833167D01*
X19950Y833750D01*
X19783Y834333D01*
X19367Y834833D01*
X18617Y835167D01*
X17617Y835333D01*
X17033Y835667D01*
X16783Y836250D01*
X16950Y836833D01*
X17367Y837250D01*
X17950Y837500D01*
X18533D01*
X19117Y837333D01*
X19617Y836917D01*
G01X22300Y830833D02*
Y835833D01*
G01Y835083D02*
X22717Y835500D01*
X23133Y835750D01*
X23800Y835833D01*
X24383Y835750D01*
X24967Y835333D01*
X25217Y834750D01*
X25300Y834167D01*
X25217Y833583D01*
X24967Y833000D01*
X24467Y832667D01*
X23800Y832500D01*
X23217Y832583D01*
X22633Y832833D01*
X22300Y833167D01*
G01X28150Y834750D02*
X30817D01*
X30567Y835333D01*
X30150Y835667D01*
X29567Y835833D01*
X28983Y835750D01*
X28483Y835500D01*
X28150Y834917D01*
X27983Y834417D01*
Y833917D01*
X28150Y833417D01*
X28567Y832917D01*
X29067Y832583D01*
X29650Y832500D01*
X30233Y832667D01*
X30817Y833167D01*
G01X36333Y835417D02*
X35750Y835750D01*
X35250Y835833D01*
X34583Y835667D01*
X34083Y835333D01*
X33750Y834750D01*
X33667Y834167D01*
X33750Y833583D01*
X34083Y833083D01*
X34583Y832667D01*
X35250Y832500D01*
X35833Y832667D01*
X36333Y833000D01*
G01X40600Y835833D02*
Y832500D01*
G01Y837167D02*
X40433Y837250D01*
Y837417D01*
X40600Y837500D01*
X40767Y837417D01*
Y837250D01*
X40600Y837167D01*
G01X45700Y832500D02*
Y836750D01*
X45867Y837167D01*
X46200Y837417D01*
X46700Y837500D01*
X47200Y837333D01*
X47450Y836917D01*
G01X46450Y835500D02*
X44783D01*
G01X51800Y835833D02*
Y832500D01*
G01Y837167D02*
X51633Y837250D01*
Y837417D01*
X51800Y837500D01*
X51967Y837417D01*
Y837250D01*
X51800Y837167D01*
G01X58733Y835417D02*
X58150Y835750D01*
X57650Y835833D01*
X56983Y835667D01*
X56483Y835333D01*
X56150Y834750D01*
X56067Y834167D01*
X56150Y833583D01*
X56483Y833083D01*
X56983Y832667D01*
X57650Y832500D01*
X58233Y832667D01*
X58733Y833000D01*
G01X64500Y832500D02*
Y835833D01*
G01Y835250D02*
X64167Y835583D01*
X63667Y835750D01*
X63083Y835833D01*
X62500Y835667D01*
X62000Y835333D01*
X61667Y834833D01*
X61500Y834167D01*
X61667Y833500D01*
X62000Y833000D01*
X62500Y832667D01*
X63083Y832500D01*
X63667Y832583D01*
X64167Y832833D01*
X64500Y833167D01*
G01X68600Y837500D02*
Y832500D01*
G01X67433Y835833D02*
X69767D01*
G01X74200D02*
Y832500D01*
G01Y837167D02*
X74033Y837250D01*
Y837417D01*
X74200Y837500D01*
X74367Y837417D01*
Y837250D01*
X74200Y837167D01*
G01X79800Y832500D02*
X79300Y832583D01*
X78800Y832917D01*
X78467Y833500D01*
X78300Y834167D01*
X78467Y834833D01*
X78800Y835417D01*
X79300Y835750D01*
X79800Y835833D01*
X80300Y835750D01*
X80800Y835417D01*
X81133Y834833D01*
X81217Y834167D01*
X81133Y833500D01*
X80800Y832917D01*
X80300Y832583D01*
X79800Y832500D01*
G01X83983D02*
Y835833D01*
G01Y835000D02*
X84317Y835417D01*
X84817Y835750D01*
X85483Y835833D01*
X86067Y835750D01*
X86567Y835417D01*
X86817Y834833D01*
Y832500D01*
G01X98100Y837500D02*
Y832500D01*
G01Y833250D02*
X97767Y832833D01*
X97267Y832583D01*
X96683Y832500D01*
X96017Y832667D01*
X95517Y833083D01*
X95183Y833583D01*
X95100Y834167D01*
X95183Y834750D01*
X95517Y835250D01*
X96017Y835667D01*
X96683Y835833D01*
X97267Y835750D01*
X97683Y835583D01*
X98100Y835250D01*
G01X102200Y832500D02*
X101700Y832583D01*
X101200Y832917D01*
X100867Y833500D01*
X100700Y834167D01*
X100867Y834833D01*
X101200Y835417D01*
X101700Y835750D01*
X102200Y835833D01*
X102700Y835750D01*
X103200Y835417D01*
X103533Y834833D01*
X103617Y834167D01*
X103533Y833500D01*
X103200Y832917D01*
X102700Y832583D01*
X102200Y832500D01*
G01X109133Y835417D02*
X108550Y835750D01*
X108050Y835833D01*
X107383Y835667D01*
X106883Y835333D01*
X106550Y834750D01*
X106467Y834167D01*
X106550Y833583D01*
X106883Y833083D01*
X107383Y832667D01*
X108050Y832500D01*
X108633Y832667D01*
X109133Y833000D01*
G01X111983Y835833D02*
Y833500D01*
X112317Y832917D01*
X112817Y832583D01*
X113400Y832500D01*
X113983Y832583D01*
X114483Y832917D01*
X114817Y833500D01*
G01Y832500D02*
Y835833D01*
G01X116500Y832500D02*
Y835833D01*
G01Y834917D02*
X116750Y835333D01*
X117167Y835667D01*
X117750Y835833D01*
X118333Y835667D01*
X118750Y835333D01*
X119000Y834917D01*
Y832500D01*
G01Y834917D02*
X119250Y835333D01*
X119667Y835667D01*
X120250Y835833D01*
X120833Y835667D01*
X121250Y835333D01*
X121500Y834833D01*
Y832500D01*
G01X123350Y834750D02*
X126017D01*
X125767Y835333D01*
X125350Y835667D01*
X124767Y835833D01*
X124183Y835750D01*
X123683Y835500D01*
X123350Y834917D01*
X123183Y834417D01*
Y833917D01*
X123350Y833417D01*
X123767Y832917D01*
X124267Y832583D01*
X124850Y832500D01*
X125433Y832667D01*
X126017Y833167D01*
G01X128783Y832500D02*
Y835833D01*
G01Y835000D02*
X129117Y835417D01*
X129617Y835750D01*
X130283Y835833D01*
X130867Y835750D01*
X131367Y835417D01*
X131617Y834833D01*
Y832500D01*
G01X135800Y837500D02*
Y832500D01*
G01X134633Y835833D02*
X136967D01*
G01X141400Y832333D02*
X141233Y832417D01*
Y832583D01*
X141400Y832667D01*
X141567Y832583D01*
Y832417D01*
X141400Y832333D01*
G01Y834583D02*
X141233Y834667D01*
Y834833D01*
X141400Y834917D01*
X141567Y834833D01*
Y834667D01*
X141400Y834583D01*
G01X0Y820500D02*
X694500D01*
G01X0Y850500D02*
X694500D01*
G01X34000Y663333D02*
Y668333D01*
G01Y667583D02*
X34417Y668000D01*
X34833Y668250D01*
X35500Y668333D01*
X36083Y668250D01*
X36667Y667833D01*
X36917Y667250D01*
X37000Y666667D01*
X36917Y666083D01*
X36667Y665500D01*
X36167Y665167D01*
X35500Y665000D01*
X34917Y665083D01*
X34333Y665333D01*
X34000Y665667D01*
G01X39933Y665000D02*
Y668333D01*
G01Y667667D02*
X40350Y668000D01*
X40767Y668250D01*
X41350Y668333D01*
X41767Y668250D01*
X42267Y668000D01*
G01X46700Y665000D02*
X46200Y665083D01*
X45700Y665417D01*
X45367Y666000D01*
X45200Y666667D01*
X45367Y667333D01*
X45700Y667917D01*
X46200Y668250D01*
X46700Y668333D01*
X47200Y668250D01*
X47700Y667917D01*
X48033Y667333D01*
X48117Y666667D01*
X48033Y666000D01*
X47700Y665417D01*
X47200Y665083D01*
X46700Y665000D01*
G01X53633Y667917D02*
X53050Y668250D01*
X52550Y668333D01*
X51883Y668167D01*
X51383Y667833D01*
X51050Y667250D01*
X50967Y666667D01*
X51050Y666083D01*
X51383Y665583D01*
X51883Y665167D01*
X52550Y665000D01*
X53133Y665167D01*
X53633Y665500D01*
G01X56650Y667250D02*
X59317D01*
X59067Y667833D01*
X58650Y668167D01*
X58067Y668333D01*
X57483Y668250D01*
X56983Y668000D01*
X56650Y667417D01*
X56483Y666917D01*
Y666417D01*
X56650Y665917D01*
X57067Y665417D01*
X57567Y665083D01*
X58150Y665000D01*
X58733Y665167D01*
X59317Y665667D01*
G01X62250Y665583D02*
X62667Y665250D01*
X63250Y665000D01*
X63750D01*
X64250Y665167D01*
X64583Y665417D01*
X64750Y665750D01*
X64667Y666250D01*
X64333Y666500D01*
X62833Y667000D01*
X62500Y667583D01*
X62667Y668000D01*
X63000Y668250D01*
X63500Y668333D01*
X64000Y668250D01*
X64500Y668000D01*
G01X67850Y665583D02*
X68267Y665250D01*
X68850Y665000D01*
X69350D01*
X69850Y665167D01*
X70183Y665417D01*
X70350Y665750D01*
X70267Y666250D01*
X69933Y666500D01*
X68433Y667000D01*
X68100Y667583D01*
X68267Y668000D01*
X68600Y668250D01*
X69100Y668333D01*
X69600Y668250D01*
X70100Y668000D01*
G01X67000Y725433D02*
X66833Y725517D01*
Y725683D01*
X67000Y725767D01*
X67167Y725683D01*
Y725517D01*
X67000Y725433D01*
G01X71000Y729600D02*
X73000D01*
G01X72000D02*
Y724600D01*
G01X71000D02*
X73000D01*
G01X75933D02*
Y729600D01*
X77933D01*
X78600Y729350D01*
X79100Y728767D01*
X79267Y728100D01*
X79100Y727433D01*
X78683Y726933D01*
X77933Y726683D01*
X75933D01*
G01X85033Y729183D02*
X84533Y729433D01*
X83950Y729600D01*
X83283D01*
X82533Y729350D01*
X81950Y728933D01*
X81533Y728433D01*
X81200Y727600D01*
X81117Y726850D01*
X81283Y726100D01*
X81533Y725600D01*
X82033Y725100D01*
X82617Y724767D01*
X83200Y724600D01*
X83783D01*
X84367Y724767D01*
X84867Y725017D01*
X85283Y725350D01*
G01X87717Y726267D02*
X89883D01*
G01X92733Y729600D02*
Y724600D01*
X96067D01*
G01X98917Y726267D02*
X101083D01*
G01X105600Y724600D02*
Y729600D01*
X104600Y728600D01*
G01Y724600D02*
X106600D01*
G01X111200Y729600D02*
X110533Y729433D01*
X110033Y729017D01*
X109700Y728517D01*
X109450Y727850D01*
X109367Y727100D01*
X109450Y726350D01*
X109700Y725683D01*
X110033Y725183D01*
X110533Y724767D01*
X111200Y724600D01*
X111867Y724767D01*
X112367Y725183D01*
X112700Y725683D01*
X112950Y726350D01*
X113033Y727100D01*
X112950Y727850D01*
X112700Y728517D01*
X112367Y729017D01*
X111867Y729433D01*
X111200Y729600D01*
G01X115383Y725183D02*
X115967Y724767D01*
X116633Y724600D01*
X117300Y724767D01*
X117883Y725267D01*
X118300Y726017D01*
X118467Y726767D01*
Y727683D01*
X118300Y728433D01*
X117883Y729100D01*
X117383Y729433D01*
X116800Y729600D01*
X116133Y729433D01*
X115633Y729100D01*
X115300Y728600D01*
X115133Y727933D01*
X115300Y727350D01*
X115717Y726767D01*
X116217Y726433D01*
X116800Y726350D01*
X117467Y726517D01*
X117967Y726933D01*
X118467Y727683D01*
G01X126250Y725267D02*
X126917Y724850D01*
X127667Y724600D01*
X128333D01*
X129000Y724850D01*
X129500Y725267D01*
X129750Y725850D01*
X129583Y726433D01*
X129167Y726933D01*
X128417Y727267D01*
X127417Y727433D01*
X126833Y727767D01*
X126583Y728350D01*
X126750Y728933D01*
X127167Y729350D01*
X127750Y729600D01*
X128333D01*
X128917Y729433D01*
X129417Y729017D01*
G01X132100Y722933D02*
Y727933D01*
G01Y727183D02*
X132517Y727600D01*
X132933Y727850D01*
X133600Y727933D01*
X134183Y727850D01*
X134767Y727433D01*
X135017Y726850D01*
X135100Y726267D01*
X135017Y725683D01*
X134767Y725100D01*
X134267Y724767D01*
X133600Y724600D01*
X133017Y724683D01*
X132433Y724933D01*
X132100Y725267D01*
G01X137950Y726850D02*
X140617D01*
X140367Y727433D01*
X139950Y727767D01*
X139367Y727933D01*
X138783Y727850D01*
X138283Y727600D01*
X137950Y727017D01*
X137783Y726517D01*
Y726017D01*
X137950Y725517D01*
X138367Y725017D01*
X138867Y724683D01*
X139450Y724600D01*
X140033Y724767D01*
X140617Y725267D01*
G01X146133Y727517D02*
X145550Y727850D01*
X145050Y727933D01*
X144383Y727767D01*
X143883Y727433D01*
X143550Y726850D01*
X143467Y726267D01*
X143550Y725683D01*
X143883Y725183D01*
X144383Y724767D01*
X145050Y724600D01*
X145633Y724767D01*
X146133Y725100D01*
G01X150400Y727933D02*
Y724600D01*
G01Y729267D02*
X150233Y729350D01*
Y729517D01*
X150400Y729600D01*
X150567Y729517D01*
Y729350D01*
X150400Y729267D01*
G01X155500Y724600D02*
Y728850D01*
X155667Y729267D01*
X156000Y729517D01*
X156500Y729600D01*
X157000Y729433D01*
X157250Y729017D01*
G01X156250Y727600D02*
X154583D01*
G01X161600Y727933D02*
Y724600D01*
G01Y729267D02*
X161433Y729350D01*
Y729517D01*
X161600Y729600D01*
X161767Y729517D01*
Y729350D01*
X161600Y729267D01*
G01X168533Y727517D02*
X167950Y727850D01*
X167450Y727933D01*
X166783Y727767D01*
X166283Y727433D01*
X165950Y726850D01*
X165867Y726267D01*
X165950Y725683D01*
X166283Y725183D01*
X166783Y724767D01*
X167450Y724600D01*
X168033Y724767D01*
X168533Y725100D01*
G01X174300Y724600D02*
Y727933D01*
G01Y727350D02*
X173967Y727683D01*
X173467Y727850D01*
X172883Y727933D01*
X172300Y727767D01*
X171800Y727433D01*
X171467Y726933D01*
X171300Y726267D01*
X171467Y725600D01*
X171800Y725100D01*
X172300Y724767D01*
X172883Y724600D01*
X173467Y724683D01*
X173967Y724933D01*
X174300Y725267D01*
G01X178400Y729600D02*
Y724600D01*
G01X177233Y727933D02*
X179567D01*
G01X184000D02*
Y724600D01*
G01Y729267D02*
X183833Y729350D01*
Y729517D01*
X184000Y729600D01*
X184167Y729517D01*
Y729350D01*
X184000Y729267D01*
G01X189600Y724600D02*
X189100Y724683D01*
X188600Y725017D01*
X188267Y725600D01*
X188100Y726267D01*
X188267Y726933D01*
X188600Y727517D01*
X189100Y727850D01*
X189600Y727933D01*
X190100Y727850D01*
X190600Y727517D01*
X190933Y726933D01*
X191017Y726267D01*
X190933Y725600D01*
X190600Y725017D01*
X190100Y724683D01*
X189600Y724600D01*
G01X193783D02*
Y727933D01*
G01Y727100D02*
X194117Y727517D01*
X194617Y727850D01*
X195283Y727933D01*
X195867Y727850D01*
X196367Y727517D01*
X196617Y726933D01*
Y724600D01*
G01X205900D02*
Y728850D01*
X206067Y729267D01*
X206400Y729517D01*
X206900Y729600D01*
X207400Y729433D01*
X207650Y729017D01*
G01X206650Y727600D02*
X204983D01*
G01X212000Y724600D02*
X211500Y724683D01*
X211000Y725017D01*
X210667Y725600D01*
X210500Y726267D01*
X210667Y726933D01*
X211000Y727517D01*
X211500Y727850D01*
X212000Y727933D01*
X212500Y727850D01*
X213000Y727517D01*
X213333Y726933D01*
X213417Y726267D01*
X213333Y725600D01*
X213000Y725017D01*
X212500Y724683D01*
X212000Y724600D01*
G01X216433D02*
Y727933D01*
G01Y727267D02*
X216850Y727600D01*
X217267Y727850D01*
X217850Y727933D01*
X218267Y727850D01*
X218767Y727600D01*
G01X227133Y724600D02*
Y729600D01*
X229217D01*
X229883Y729350D01*
X230300Y729017D01*
X230467Y728350D01*
X230300Y727683D01*
X229800Y727267D01*
X229217Y727017D01*
X227133D01*
G01X229217D02*
X230467Y724600D01*
G01X233150Y726850D02*
X235817D01*
X235567Y727433D01*
X235150Y727767D01*
X234567Y727933D01*
X233983Y727850D01*
X233483Y727600D01*
X233150Y727017D01*
X232983Y726517D01*
Y726017D01*
X233150Y725517D01*
X233567Y725017D01*
X234067Y724683D01*
X234650Y724600D01*
X235233Y724767D01*
X235817Y725267D01*
G01X238750Y725183D02*
X239167Y724850D01*
X239750Y724600D01*
X240250D01*
X240750Y724767D01*
X241083Y725017D01*
X241250Y725350D01*
X241167Y725850D01*
X240833Y726100D01*
X239333Y726600D01*
X239000Y727183D01*
X239167Y727600D01*
X239500Y727850D01*
X240000Y727933D01*
X240500Y727850D01*
X241000Y727600D01*
G01X245600Y727933D02*
Y724600D01*
G01Y729267D02*
X245433Y729350D01*
Y729517D01*
X245600Y729600D01*
X245767Y729517D01*
Y729350D01*
X245600Y729267D01*
G01X249783Y724600D02*
Y727933D01*
G01Y727100D02*
X250117Y727517D01*
X250617Y727850D01*
X251283Y727933D01*
X251867Y727850D01*
X252367Y727517D01*
X252617Y726933D01*
Y724600D01*
G01X261400Y729600D02*
X263400D01*
G01X262400D02*
Y724600D01*
G01X261400D02*
X263400D01*
G01X265500D02*
Y727933D01*
G01Y727017D02*
X265750Y727433D01*
X266167Y727767D01*
X266750Y727933D01*
X267333Y727767D01*
X267750Y727433D01*
X268000Y727017D01*
Y724600D01*
G01Y727017D02*
X268250Y727433D01*
X268667Y727767D01*
X269250Y727933D01*
X269833Y727767D01*
X270250Y727433D01*
X270500Y726933D01*
Y724600D01*
G01X272100Y722933D02*
Y727933D01*
G01Y727183D02*
X272517Y727600D01*
X272933Y727850D01*
X273600Y727933D01*
X274183Y727850D01*
X274767Y727433D01*
X275017Y726850D01*
X275100Y726267D01*
X275017Y725683D01*
X274767Y725100D01*
X274267Y724767D01*
X273600Y724600D01*
X273017Y724683D01*
X272433Y724933D01*
X272100Y725267D01*
G01X278033Y724600D02*
Y727933D01*
G01Y727267D02*
X278450Y727600D01*
X278867Y727850D01*
X279450Y727933D01*
X279867Y727850D01*
X280367Y727600D01*
G01X283550Y726850D02*
X286217D01*
X285967Y727433D01*
X285550Y727767D01*
X284967Y727933D01*
X284383Y727850D01*
X283883Y727600D01*
X283550Y727017D01*
X283383Y726517D01*
Y726017D01*
X283550Y725517D01*
X283967Y725017D01*
X284467Y724683D01*
X285050Y724600D01*
X285633Y724767D01*
X286217Y725267D01*
G01X289233Y723350D02*
X289817Y723017D01*
X290483Y722933D01*
X291067Y723017D01*
X291567Y723433D01*
X291900Y724017D01*
Y727933D01*
G01Y727267D02*
X291567Y727600D01*
X291067Y727850D01*
X290483Y727933D01*
X289817Y727767D01*
X289400Y727433D01*
X289067Y726850D01*
X288900Y726267D01*
X288983Y725767D01*
X289317Y725183D01*
X289817Y724767D01*
X290483Y724600D01*
X290983Y724683D01*
X291567Y725017D01*
X291900Y725350D01*
G01X294583Y724600D02*
Y727933D01*
G01Y727100D02*
X294917Y727517D01*
X295417Y727850D01*
X296083Y727933D01*
X296667Y727850D01*
X297167Y727517D01*
X297417Y726933D01*
Y724600D01*
G01X303100D02*
Y727933D01*
G01Y727350D02*
X302767Y727683D01*
X302267Y727850D01*
X301683Y727933D01*
X301100Y727767D01*
X300600Y727433D01*
X300267Y726933D01*
X300100Y726267D01*
X300267Y725600D01*
X300600Y725100D01*
X301100Y724767D01*
X301683Y724600D01*
X302267Y724683D01*
X302767Y724933D01*
X303100Y725267D01*
G01X307200Y729600D02*
Y724600D01*
G01X306033Y727933D02*
X308367D01*
G01X311550Y726850D02*
X314217D01*
X313967Y727433D01*
X313550Y727767D01*
X312967Y727933D01*
X312383Y727850D01*
X311883Y727600D01*
X311550Y727017D01*
X311383Y726517D01*
Y726017D01*
X311550Y725517D01*
X311967Y725017D01*
X312467Y724683D01*
X313050Y724600D01*
X313633Y724767D01*
X314217Y725267D01*
G01X319900Y729600D02*
Y724600D01*
G01Y725350D02*
X319567Y724933D01*
X319067Y724683D01*
X318483Y724600D01*
X317817Y724767D01*
X317317Y725183D01*
X316983Y725683D01*
X316900Y726267D01*
X316983Y726850D01*
X317317Y727350D01*
X317817Y727767D01*
X318483Y727933D01*
X319067Y727850D01*
X319483Y727683D01*
X319900Y727350D01*
G01X328017Y724600D02*
Y729600D01*
X331183D01*
G01X330017Y727183D02*
X328017D01*
G01X336700Y724600D02*
Y727933D01*
G01Y727350D02*
X336367Y727683D01*
X335867Y727850D01*
X335283Y727933D01*
X334700Y727767D01*
X334200Y727433D01*
X333867Y726933D01*
X333700Y726267D01*
X333867Y725600D01*
X334200Y725100D01*
X334700Y724767D01*
X335283Y724600D01*
X335867Y724683D01*
X336367Y724933D01*
X336700Y725267D01*
G01X339300Y724600D02*
Y729600D01*
G01Y727100D02*
X339717Y727600D01*
X340217Y727850D01*
X340717Y727933D01*
X341467Y727767D01*
X341967Y727433D01*
X342300Y726850D01*
Y726183D01*
X342133Y725517D01*
X341800Y725017D01*
X341217Y724683D01*
X340717Y724600D01*
X340217Y724683D01*
X339717Y724933D01*
X339300Y725350D01*
G01X345233Y724600D02*
Y727933D01*
G01Y727267D02*
X345650Y727600D01*
X346067Y727850D01*
X346650Y727933D01*
X347067Y727850D01*
X347567Y727600D01*
G01X352000Y727933D02*
Y724600D01*
G01Y729267D02*
X351833Y729350D01*
Y729517D01*
X352000Y729600D01*
X352167Y729517D01*
Y729350D01*
X352000Y729267D01*
G01X358933Y727517D02*
X358350Y727850D01*
X357850Y727933D01*
X357183Y727767D01*
X356683Y727433D01*
X356350Y726850D01*
X356267Y726267D01*
X356350Y725683D01*
X356683Y725183D01*
X357183Y724767D01*
X357850Y724600D01*
X358433Y724767D01*
X358933Y725100D01*
G01X362783Y722933D02*
X361950Y723767D01*
X361533Y724600D01*
Y727933D01*
X361950Y728767D01*
X362783Y729600D01*
G01X367133Y724600D02*
Y729600D01*
X369133D01*
X369800Y729350D01*
X370300Y728767D01*
X370467Y728100D01*
X370300Y727433D01*
X369883Y726933D01*
X369133Y726683D01*
X367133D01*
G01X373233Y724600D02*
Y727933D01*
G01Y727267D02*
X373650Y727600D01*
X374067Y727850D01*
X374650Y727933D01*
X375067Y727850D01*
X375567Y727600D01*
G01X378750Y726850D02*
X381417D01*
X381167Y727433D01*
X380750Y727767D01*
X380167Y727933D01*
X379583Y727850D01*
X379083Y727600D01*
X378750Y727017D01*
X378583Y726517D01*
Y726017D01*
X378750Y725517D01*
X379167Y725017D01*
X379667Y724683D01*
X380250Y724600D01*
X380833Y724767D01*
X381417Y725267D01*
G01X384100Y722933D02*
Y727933D01*
G01Y727183D02*
X384517Y727600D01*
X384933Y727850D01*
X385600Y727933D01*
X386183Y727850D01*
X386767Y727433D01*
X387017Y726850D01*
X387100Y726267D01*
X387017Y725683D01*
X386767Y725100D01*
X386267Y724767D01*
X385600Y724600D01*
X385017Y724683D01*
X384433Y724933D01*
X384100Y725267D01*
G01X390033Y724600D02*
Y727933D01*
G01Y727267D02*
X390450Y727600D01*
X390867Y727850D01*
X391450Y727933D01*
X391867Y727850D01*
X392367Y727600D01*
G01X395550Y726850D02*
X398217D01*
X397967Y727433D01*
X397550Y727767D01*
X396967Y727933D01*
X396383Y727850D01*
X395883Y727600D01*
X395550Y727017D01*
X395383Y726517D01*
Y726017D01*
X395550Y725517D01*
X395967Y725017D01*
X396467Y724683D01*
X397050Y724600D01*
X397633Y724767D01*
X398217Y725267D01*
G01X401233Y723350D02*
X401817Y723017D01*
X402483Y722933D01*
X403067Y723017D01*
X403567Y723433D01*
X403900Y724017D01*
Y727933D01*
G01Y727267D02*
X403567Y727600D01*
X403067Y727850D01*
X402483Y727933D01*
X401817Y727767D01*
X401400Y727433D01*
X401067Y726850D01*
X400900Y726267D01*
X400983Y725767D01*
X401317Y725183D01*
X401817Y724767D01*
X402483Y724600D01*
X402983Y724683D01*
X403567Y725017D01*
X403900Y725350D01*
G01X408417Y722933D02*
X409250Y723767D01*
X409667Y724600D01*
Y727933D01*
X409250Y728767D01*
X408417Y729600D01*
G01X418700Y724600D02*
Y728850D01*
X418867Y729267D01*
X419200Y729517D01*
X419700Y729600D01*
X420200Y729433D01*
X420450Y729017D01*
G01X419450Y727600D02*
X417783D01*
G01X424800Y724600D02*
X424300Y724683D01*
X423800Y725017D01*
X423467Y725600D01*
X423300Y726267D01*
X423467Y726933D01*
X423800Y727517D01*
X424300Y727850D01*
X424800Y727933D01*
X425300Y727850D01*
X425800Y727517D01*
X426133Y726933D01*
X426217Y726267D01*
X426133Y725600D01*
X425800Y725017D01*
X425300Y724683D01*
X424800Y724600D01*
G01X429233D02*
Y727933D01*
G01Y727267D02*
X429650Y727600D01*
X430067Y727850D01*
X430650Y727933D01*
X431067Y727850D01*
X431567Y727600D01*
G01X439433Y724600D02*
Y729600D01*
X441600Y725433D01*
X443767Y729600D01*
Y724600D01*
G01X445783Y727933D02*
Y725600D01*
X446117Y725017D01*
X446617Y724683D01*
X447200Y724600D01*
X447783Y724683D01*
X448283Y725017D01*
X448617Y725600D01*
G01Y724600D02*
Y727933D01*
G01X452800Y724600D02*
Y729600D01*
G01X458400D02*
Y724600D01*
G01X457233Y727933D02*
X459567D01*
G01X464000D02*
Y724600D01*
G01Y729267D02*
X463833Y729350D01*
Y729517D01*
X464000Y729600D01*
X464167Y729517D01*
Y729350D01*
X464000Y729267D01*
G01X469600Y724600D02*
Y729600D01*
G01X476700Y724600D02*
Y727933D01*
G01Y727350D02*
X476367Y727683D01*
X475867Y727850D01*
X475283Y727933D01*
X474700Y727767D01*
X474200Y727433D01*
X473867Y726933D01*
X473700Y726267D01*
X473867Y725600D01*
X474200Y725100D01*
X474700Y724767D01*
X475283Y724600D01*
X475867Y724683D01*
X476367Y724933D01*
X476700Y725267D01*
G01X479050Y723100D02*
X479550Y722933D01*
X480217Y723100D01*
X480633Y723433D01*
X480967Y723850D01*
X481467Y725183D01*
X482550Y727933D01*
G01X479883D02*
X481467Y725183D01*
G01X485150Y726850D02*
X487817D01*
X487567Y727433D01*
X487150Y727767D01*
X486567Y727933D01*
X485983Y727850D01*
X485483Y727600D01*
X485150Y727017D01*
X484983Y726517D01*
Y726017D01*
X485150Y725517D01*
X485567Y725017D01*
X486067Y724683D01*
X486650Y724600D01*
X487233Y724767D01*
X487817Y725267D01*
G01X490833Y724600D02*
Y727933D01*
G01Y727267D02*
X491250Y727600D01*
X491667Y727850D01*
X492250Y727933D01*
X492667Y727850D01*
X493167Y727600D01*
G01X501533Y724600D02*
Y729600D01*
X503533D01*
X504200Y729350D01*
X504700Y728767D01*
X504867Y728100D01*
X504700Y727433D01*
X504283Y726933D01*
X503533Y726683D01*
X501533D01*
G01X507633Y724600D02*
Y727933D01*
G01Y727267D02*
X508050Y727600D01*
X508467Y727850D01*
X509050Y727933D01*
X509467Y727850D01*
X509967Y727600D01*
G01X514400Y727933D02*
Y724600D01*
G01Y729267D02*
X514233Y729350D01*
Y729517D01*
X514400Y729600D01*
X514567Y729517D01*
Y729350D01*
X514400Y729267D01*
G01X518583Y724600D02*
Y727933D01*
G01Y727100D02*
X518917Y727517D01*
X519417Y727850D01*
X520083Y727933D01*
X520667Y727850D01*
X521167Y727517D01*
X521417Y726933D01*
Y724600D01*
G01X525600Y729600D02*
Y724600D01*
G01X524433Y727933D02*
X526767D01*
G01X529950Y726850D02*
X532617D01*
X532367Y727433D01*
X531950Y727767D01*
X531367Y727933D01*
X530783Y727850D01*
X530283Y727600D01*
X529950Y727017D01*
X529783Y726517D01*
Y726017D01*
X529950Y725517D01*
X530367Y725017D01*
X530867Y724683D01*
X531450Y724600D01*
X532033Y724767D01*
X532617Y725267D01*
G01X538300Y729600D02*
Y724600D01*
G01Y725350D02*
X537967Y724933D01*
X537467Y724683D01*
X536883Y724600D01*
X536217Y724767D01*
X535717Y725183D01*
X535383Y725683D01*
X535300Y726267D01*
X535383Y726850D01*
X535717Y727350D01*
X536217Y727767D01*
X536883Y727933D01*
X537467Y727850D01*
X537883Y727683D01*
X538300Y727350D01*
G01X548667Y727267D02*
X549000Y727517D01*
X549250Y727933D01*
X549417Y728517D01*
X549250Y729017D01*
X548917Y729350D01*
X548333Y729600D01*
X546083D01*
Y724600D01*
X548833D01*
X549417Y724933D01*
X549750Y725433D01*
X549917Y726017D01*
X549750Y726600D01*
X549250Y727100D01*
X548667Y727267D01*
X546083D01*
G01X553600Y724600D02*
X553100Y724683D01*
X552600Y725017D01*
X552267Y725600D01*
X552100Y726267D01*
X552267Y726933D01*
X552600Y727517D01*
X553100Y727850D01*
X553600Y727933D01*
X554100Y727850D01*
X554600Y727517D01*
X554933Y726933D01*
X555017Y726267D01*
X554933Y725600D01*
X554600Y725017D01*
X554100Y724683D01*
X553600Y724600D01*
G01X560700D02*
Y727933D01*
G01Y727350D02*
X560367Y727683D01*
X559867Y727850D01*
X559283Y727933D01*
X558700Y727767D01*
X558200Y727433D01*
X557867Y726933D01*
X557700Y726267D01*
X557867Y725600D01*
X558200Y725100D01*
X558700Y724767D01*
X559283Y724600D01*
X559867Y724683D01*
X560367Y724933D01*
X560700Y725267D01*
G01X563633Y724600D02*
Y727933D01*
G01Y727267D02*
X564050Y727600D01*
X564467Y727850D01*
X565050Y727933D01*
X565467Y727850D01*
X565967Y727600D01*
G01X571900Y729600D02*
Y724600D01*
G01Y725350D02*
X571567Y724933D01*
X571067Y724683D01*
X570483Y724600D01*
X569817Y724767D01*
X569317Y725183D01*
X568983Y725683D01*
X568900Y726267D01*
X568983Y726850D01*
X569317Y727350D01*
X569817Y727767D01*
X570483Y727933D01*
X571067Y727850D01*
X571483Y727683D01*
X571900Y727350D01*
G01X574750Y725183D02*
X575167Y724850D01*
X575750Y724600D01*
X576250D01*
X576750Y724767D01*
X577083Y725017D01*
X577250Y725350D01*
X577167Y725850D01*
X576833Y726100D01*
X575333Y726600D01*
X575000Y727183D01*
X575167Y727600D01*
X575500Y727850D01*
X576000Y727933D01*
X576500Y727850D01*
X577000Y727600D01*
G01X57000Y802500D02*
X59000D01*
G01X58000D02*
Y797500D01*
G01X57000D02*
X59000D01*
G01X63100D02*
Y801750D01*
X63267Y802167D01*
X63600Y802417D01*
X64100Y802500D01*
X64600Y802333D01*
X64850Y801917D01*
G01X63850Y800500D02*
X62183D01*
G01X74800Y802500D02*
Y797500D01*
G01X73633Y800833D02*
X75967D01*
G01X78983Y797500D02*
Y802500D01*
G01Y800083D02*
X79400Y800500D01*
X79817Y800750D01*
X80483Y800833D01*
X80983Y800750D01*
X81567Y800417D01*
X81817Y799917D01*
Y797500D01*
G01X84750Y799750D02*
X87417D01*
X87167Y800333D01*
X86750Y800667D01*
X86167Y800833D01*
X85583Y800750D01*
X85083Y800500D01*
X84750Y799917D01*
X84583Y799417D01*
Y798917D01*
X84750Y798417D01*
X85167Y797917D01*
X85667Y797583D01*
X86250Y797500D01*
X86833Y797667D01*
X87417Y798167D01*
G01X98533Y800417D02*
X97950Y800750D01*
X97450Y800833D01*
X96783Y800667D01*
X96283Y800333D01*
X95950Y799750D01*
X95867Y799167D01*
X95950Y798583D01*
X96283Y798083D01*
X96783Y797667D01*
X97450Y797500D01*
X98033Y797667D01*
X98533Y798000D01*
G01X101633Y797500D02*
Y800833D01*
G01Y800167D02*
X102050Y800500D01*
X102467Y800750D01*
X103050Y800833D01*
X103467Y800750D01*
X103967Y800500D01*
G01X108400Y800833D02*
Y797500D01*
G01Y802167D02*
X108233Y802250D01*
Y802417D01*
X108400Y802500D01*
X108567Y802417D01*
Y802250D01*
X108400Y802167D01*
G01X114000Y802500D02*
Y797500D01*
G01X112833Y800833D02*
X115167D01*
G01X118350Y799750D02*
X121017D01*
X120767Y800333D01*
X120350Y800667D01*
X119767Y800833D01*
X119183Y800750D01*
X118683Y800500D01*
X118350Y799917D01*
X118183Y799417D01*
Y798917D01*
X118350Y798417D01*
X118767Y797917D01*
X119267Y797583D01*
X119850Y797500D01*
X120433Y797667D01*
X121017Y798167D01*
G01X124033Y797500D02*
Y800833D01*
G01Y800167D02*
X124450Y800500D01*
X124867Y800750D01*
X125450Y800833D01*
X125867Y800750D01*
X126367Y800500D01*
G01X130800Y800833D02*
Y797500D01*
G01Y802167D02*
X130633Y802250D01*
Y802417D01*
X130800Y802500D01*
X130967Y802417D01*
Y802250D01*
X130800Y802167D01*
G01X137900Y797500D02*
Y800833D01*
G01Y800250D02*
X137567Y800583D01*
X137067Y800750D01*
X136483Y800833D01*
X135900Y800667D01*
X135400Y800333D01*
X135067Y799833D01*
X134900Y799167D01*
X135067Y798500D01*
X135400Y798000D01*
X135900Y797667D01*
X136483Y797500D01*
X137067Y797583D01*
X137567Y797833D01*
X137900Y798167D01*
G01X147600Y800833D02*
Y797500D01*
G01Y802167D02*
X147433Y802250D01*
Y802417D01*
X147600Y802500D01*
X147767Y802417D01*
Y802250D01*
X147600Y802167D01*
G01X151950Y798083D02*
X152367Y797750D01*
X152950Y797500D01*
X153450D01*
X153950Y797667D01*
X154283Y797917D01*
X154450Y798250D01*
X154367Y798750D01*
X154033Y799000D01*
X152533Y799500D01*
X152200Y800083D01*
X152367Y800500D01*
X152700Y800750D01*
X153200Y800833D01*
X153700Y800750D01*
X154200Y800500D01*
G01X162983Y797500D02*
Y800833D01*
G01Y800000D02*
X163317Y800417D01*
X163817Y800750D01*
X164483Y800833D01*
X165067Y800750D01*
X165567Y800417D01*
X165817Y799833D01*
Y797500D01*
G01X170000D02*
X169500Y797583D01*
X169000Y797917D01*
X168667Y798500D01*
X168500Y799167D01*
X168667Y799833D01*
X169000Y800417D01*
X169500Y800750D01*
X170000Y800833D01*
X170500Y800750D01*
X171000Y800417D01*
X171333Y799833D01*
X171417Y799167D01*
X171333Y798500D01*
X171000Y797917D01*
X170500Y797583D01*
X170000Y797500D01*
G01X175600Y802500D02*
Y797500D01*
G01X174433Y800833D02*
X176767D01*
G01X185550Y798083D02*
X185967Y797750D01*
X186550Y797500D01*
X187050D01*
X187550Y797667D01*
X187883Y797917D01*
X188050Y798250D01*
X187967Y798750D01*
X187633Y799000D01*
X186133Y799500D01*
X185800Y800083D01*
X185967Y800500D01*
X186300Y800750D01*
X186800Y800833D01*
X187300Y800750D01*
X187800Y800500D01*
G01X190900Y795833D02*
Y800833D01*
G01Y800083D02*
X191317Y800500D01*
X191733Y800750D01*
X192400Y800833D01*
X192983Y800750D01*
X193567Y800333D01*
X193817Y799750D01*
X193900Y799167D01*
X193817Y798583D01*
X193567Y798000D01*
X193067Y797667D01*
X192400Y797500D01*
X191817Y797583D01*
X191233Y797833D01*
X190900Y798167D01*
G01X196750Y799750D02*
X199417D01*
X199167Y800333D01*
X198750Y800667D01*
X198167Y800833D01*
X197583Y800750D01*
X197083Y800500D01*
X196750Y799917D01*
X196583Y799417D01*
Y798917D01*
X196750Y798417D01*
X197167Y797917D01*
X197667Y797583D01*
X198250Y797500D01*
X198833Y797667D01*
X199417Y798167D01*
G01X204933Y800417D02*
X204350Y800750D01*
X203850Y800833D01*
X203183Y800667D01*
X202683Y800333D01*
X202350Y799750D01*
X202267Y799167D01*
X202350Y798583D01*
X202683Y798083D01*
X203183Y797667D01*
X203850Y797500D01*
X204433Y797667D01*
X204933Y798000D01*
G01X209200Y800833D02*
Y797500D01*
G01Y802167D02*
X209033Y802250D01*
Y802417D01*
X209200Y802500D01*
X209367Y802417D01*
Y802250D01*
X209200Y802167D01*
G01X214300Y797500D02*
Y801750D01*
X214467Y802167D01*
X214800Y802417D01*
X215300Y802500D01*
X215800Y802333D01*
X216050Y801917D01*
G01X215050Y800500D02*
X213383D01*
G01X220400Y800833D02*
Y797500D01*
G01Y802167D02*
X220233Y802250D01*
Y802417D01*
X220400Y802500D01*
X220567Y802417D01*
Y802250D01*
X220400Y802167D01*
G01X224750Y799750D02*
X227417D01*
X227167Y800333D01*
X226750Y800667D01*
X226167Y800833D01*
X225583Y800750D01*
X225083Y800500D01*
X224750Y799917D01*
X224583Y799417D01*
Y798917D01*
X224750Y798417D01*
X225167Y797917D01*
X225667Y797583D01*
X226250Y797500D01*
X226833Y797667D01*
X227417Y798167D01*
G01X233100Y802500D02*
Y797500D01*
G01Y798250D02*
X232767Y797833D01*
X232267Y797583D01*
X231683Y797500D01*
X231017Y797667D01*
X230517Y798083D01*
X230183Y798583D01*
X230100Y799167D01*
X230183Y799750D01*
X230517Y800250D01*
X231017Y800667D01*
X231683Y800833D01*
X232267Y800750D01*
X232683Y800583D01*
X233100Y800250D01*
G01X242800Y800833D02*
Y797500D01*
G01Y802167D02*
X242633Y802250D01*
Y802417D01*
X242800Y802500D01*
X242967Y802417D01*
Y802250D01*
X242800Y802167D01*
G01X246983Y797500D02*
Y800833D01*
G01Y800000D02*
X247317Y800417D01*
X247817Y800750D01*
X248483Y800833D01*
X249067Y800750D01*
X249567Y800417D01*
X249817Y799833D01*
Y797500D01*
G01X259600Y802500D02*
Y797500D01*
G01X258433Y800833D02*
X260767D01*
G01X263783Y797500D02*
Y802500D01*
G01Y800083D02*
X264200Y800500D01*
X264617Y800750D01*
X265283Y800833D01*
X265783Y800750D01*
X266367Y800417D01*
X266617Y799917D01*
Y797500D01*
G01X269550Y799750D02*
X272217D01*
X271967Y800333D01*
X271550Y800667D01*
X270967Y800833D01*
X270383Y800750D01*
X269883Y800500D01*
X269550Y799917D01*
X269383Y799417D01*
Y798917D01*
X269550Y798417D01*
X269967Y797917D01*
X270467Y797583D01*
X271050Y797500D01*
X271633Y797667D01*
X272217Y798167D01*
G01X282000Y802500D02*
Y797500D01*
G01X280833Y800833D02*
X283167D01*
G01X289100Y797500D02*
Y800833D01*
G01Y800250D02*
X288767Y800583D01*
X288267Y800750D01*
X287683Y800833D01*
X287100Y800667D01*
X286600Y800333D01*
X286267Y799833D01*
X286100Y799167D01*
X286267Y798500D01*
X286600Y798000D01*
X287100Y797667D01*
X287683Y797500D01*
X288267Y797583D01*
X288767Y797833D01*
X289100Y798167D01*
G01X291700Y797500D02*
Y802500D01*
G01Y800000D02*
X292117Y800500D01*
X292617Y800750D01*
X293117Y800833D01*
X293867Y800667D01*
X294367Y800333D01*
X294700Y799750D01*
Y799083D01*
X294533Y798417D01*
X294200Y797917D01*
X293617Y797583D01*
X293117Y797500D01*
X292617Y797583D01*
X292117Y797833D01*
X291700Y798250D01*
G01X298800Y797500D02*
Y802500D01*
G01X303150Y799750D02*
X305817D01*
X305567Y800333D01*
X305150Y800667D01*
X304567Y800833D01*
X303983Y800750D01*
X303483Y800500D01*
X303150Y799917D01*
X302983Y799417D01*
Y798917D01*
X303150Y798417D01*
X303567Y797917D01*
X304067Y797583D01*
X304650Y797500D01*
X305233Y797667D01*
X305817Y798167D01*
G01X310000Y797333D02*
X309833Y797417D01*
Y797583D01*
X310000Y797667D01*
X310167Y797583D01*
Y797417D01*
X310000Y797333D01*
G01Y799583D02*
X309833Y799667D01*
Y799833D01*
X310000Y799917D01*
X310167Y799833D01*
Y799667D01*
X310000Y799583D01*
G01X67000Y734433D02*
X66833Y734517D01*
Y734683D01*
X67000Y734767D01*
X67167Y734683D01*
Y734517D01*
X67000Y734433D01*
G01Y743433D02*
X66833Y743517D01*
Y743683D01*
X67000Y743767D01*
X67167Y743683D01*
Y743517D01*
X67000Y743433D01*
G01Y752433D02*
X66833Y752517D01*
Y752683D01*
X67000Y752767D01*
X67167Y752683D01*
Y752517D01*
X67000Y752433D01*
G01Y761433D02*
X66833Y761517D01*
Y761683D01*
X67000Y761767D01*
X67167Y761683D01*
Y761517D01*
X67000Y761433D01*
G01Y770433D02*
X66833Y770517D01*
Y770683D01*
X67000Y770767D01*
X67167Y770683D01*
Y770517D01*
X67000Y770433D01*
G01X71000Y738600D02*
X73000D01*
G01X72000D02*
Y733600D01*
G01X71000D02*
X73000D01*
G01X75933D02*
Y738600D01*
X77933D01*
X78600Y738350D01*
X79100Y737767D01*
X79267Y737100D01*
X79100Y736433D01*
X78683Y735933D01*
X77933Y735683D01*
X75933D01*
G01X85033Y738183D02*
X84533Y738433D01*
X83950Y738600D01*
X83283D01*
X82533Y738350D01*
X81950Y737933D01*
X81533Y737433D01*
X81200Y736600D01*
X81117Y735850D01*
X81283Y735100D01*
X81533Y734600D01*
X82033Y734100D01*
X82617Y733767D01*
X83200Y733600D01*
X83783D01*
X84367Y733767D01*
X84867Y734017D01*
X85283Y734350D01*
G01X87717Y735267D02*
X89883D01*
G01X92233Y733600D02*
Y738600D01*
X94400Y734433D01*
X96567Y738600D01*
Y733600D01*
G01X98417D02*
Y738600D01*
X101583D01*
G01X100417Y736183D02*
X98417D01*
G01X104517Y735267D02*
X106683D01*
G01X111200Y733600D02*
Y738600D01*
X110200Y737600D01*
G01Y733600D02*
X112200D01*
G01X114967Y734350D02*
X115467Y733933D01*
X116050Y733683D01*
X116800Y733600D01*
X117550Y733767D01*
X118133Y734100D01*
X118550Y734683D01*
X118633Y735350D01*
X118467Y736017D01*
X118050Y736433D01*
X117467Y736767D01*
X116883Y736850D01*
X116300Y736767D01*
X115550Y736433D01*
X115800Y738600D01*
X118050D01*
G01X122400D02*
X121733Y738433D01*
X121233Y738017D01*
X120900Y737517D01*
X120650Y736850D01*
X120567Y736100D01*
X120650Y735350D01*
X120900Y734683D01*
X121233Y734183D01*
X121733Y733767D01*
X122400Y733600D01*
X123067Y733767D01*
X123567Y734183D01*
X123900Y734683D01*
X124150Y735350D01*
X124233Y736100D01*
X124150Y736850D01*
X123900Y737517D01*
X123567Y738017D01*
X123067Y738433D01*
X122400Y738600D01*
G01X131433Y733600D02*
Y738600D01*
X133600Y734433D01*
X135767Y738600D01*
Y733600D01*
G01X137950Y735850D02*
X140617D01*
X140367Y736433D01*
X139950Y736767D01*
X139367Y736933D01*
X138783Y736850D01*
X138283Y736600D01*
X137950Y736017D01*
X137783Y735517D01*
Y735017D01*
X137950Y734517D01*
X138367Y734017D01*
X138867Y733683D01*
X139450Y733600D01*
X140033Y733767D01*
X140617Y734267D01*
G01X144800Y738600D02*
Y733600D01*
G01X143633Y736933D02*
X145967D01*
G01X151900Y733600D02*
Y736933D01*
G01Y736350D02*
X151567Y736683D01*
X151067Y736850D01*
X150483Y736933D01*
X149900Y736767D01*
X149400Y736433D01*
X149067Y735933D01*
X148900Y735267D01*
X149067Y734600D01*
X149400Y734100D01*
X149900Y733767D01*
X150483Y733600D01*
X151067Y733683D01*
X151567Y733933D01*
X151900Y734267D01*
G01X156000Y733600D02*
Y738600D01*
G01X165617Y733600D02*
Y738600D01*
X168783D01*
G01X167617Y736183D02*
X165617D01*
G01X172800Y733600D02*
X172300Y733683D01*
X171800Y734017D01*
X171467Y734600D01*
X171300Y735267D01*
X171467Y735933D01*
X171800Y736517D01*
X172300Y736850D01*
X172800Y736933D01*
X173300Y736850D01*
X173800Y736517D01*
X174133Y735933D01*
X174217Y735267D01*
X174133Y734600D01*
X173800Y734017D01*
X173300Y733683D01*
X172800Y733600D01*
G01X178400Y736933D02*
Y733600D01*
G01Y738267D02*
X178233Y738350D01*
Y738517D01*
X178400Y738600D01*
X178567Y738517D01*
Y738350D01*
X178400Y738267D01*
G01X184000Y733600D02*
Y738600D01*
G01X194700Y733600D02*
Y737850D01*
X194867Y738267D01*
X195200Y738517D01*
X195700Y738600D01*
X196200Y738433D01*
X196450Y738017D01*
G01X195450Y736600D02*
X193783D01*
G01X200800Y733600D02*
X200300Y733683D01*
X199800Y734017D01*
X199467Y734600D01*
X199300Y735267D01*
X199467Y735933D01*
X199800Y736517D01*
X200300Y736850D01*
X200800Y736933D01*
X201300Y736850D01*
X201800Y736517D01*
X202133Y735933D01*
X202217Y735267D01*
X202133Y734600D01*
X201800Y734017D01*
X201300Y733683D01*
X200800Y733600D01*
G01X205233D02*
Y736933D01*
G01Y736267D02*
X205650Y736600D01*
X206067Y736850D01*
X206650Y736933D01*
X207067Y736850D01*
X207567Y736600D01*
G01X215933Y733600D02*
Y738600D01*
X217933D01*
X218600Y738350D01*
X219100Y737767D01*
X219267Y737100D01*
X219100Y736433D01*
X218683Y735933D01*
X217933Y735683D01*
X215933D01*
G01X222033Y733600D02*
Y736933D01*
G01Y736267D02*
X222450Y736600D01*
X222867Y736850D01*
X223450Y736933D01*
X223867Y736850D01*
X224367Y736600D01*
G01X228800Y736933D02*
Y733600D01*
G01Y738267D02*
X228633Y738350D01*
Y738517D01*
X228800Y738600D01*
X228967Y738517D01*
Y738350D01*
X228800Y738267D01*
G01X232983Y733600D02*
Y736933D01*
G01Y736100D02*
X233317Y736517D01*
X233817Y736850D01*
X234483Y736933D01*
X235067Y736850D01*
X235567Y736517D01*
X235817Y735933D01*
Y733600D01*
G01X240000Y738600D02*
Y733600D01*
G01X238833Y736933D02*
X241167D01*
G01X244350Y735850D02*
X247017D01*
X246767Y736433D01*
X246350Y736767D01*
X245767Y736933D01*
X245183Y736850D01*
X244683Y736600D01*
X244350Y736017D01*
X244183Y735517D01*
Y735017D01*
X244350Y734517D01*
X244767Y734017D01*
X245267Y733683D01*
X245850Y733600D01*
X246433Y733767D01*
X247017Y734267D01*
G01X252700Y738600D02*
Y733600D01*
G01Y734350D02*
X252367Y733933D01*
X251867Y733683D01*
X251283Y733600D01*
X250617Y733767D01*
X250117Y734183D01*
X249783Y734683D01*
X249700Y735267D01*
X249783Y735850D01*
X250117Y736350D01*
X250617Y736767D01*
X251283Y736933D01*
X251867Y736850D01*
X252283Y736683D01*
X252700Y736350D01*
G01X259900Y738600D02*
X261067Y733600D01*
X262400Y738600D01*
X263733Y733600D01*
X264900Y738600D01*
G01X268000Y736933D02*
Y733600D01*
G01Y738267D02*
X267833Y738350D01*
Y738517D01*
X268000Y738600D01*
X268167Y738517D01*
Y738350D01*
X268000Y738267D01*
G01X272433Y733600D02*
Y736933D01*
G01Y736267D02*
X272850Y736600D01*
X273267Y736850D01*
X273850Y736933D01*
X274267Y736850D01*
X274767Y736600D01*
G01X279200Y736933D02*
Y733600D01*
G01Y738267D02*
X279033Y738350D01*
Y738517D01*
X279200Y738600D01*
X279367Y738517D01*
Y738350D01*
X279200Y738267D01*
G01X283383Y733600D02*
Y736933D01*
G01Y736100D02*
X283717Y736517D01*
X284217Y736850D01*
X284883Y736933D01*
X285467Y736850D01*
X285967Y736517D01*
X286217Y735933D01*
Y733600D01*
G01X289233Y732350D02*
X289817Y732017D01*
X290483Y731933D01*
X291067Y732017D01*
X291567Y732433D01*
X291900Y733017D01*
Y736933D01*
G01Y736267D02*
X291567Y736600D01*
X291067Y736850D01*
X290483Y736933D01*
X289817Y736767D01*
X289400Y736433D01*
X289067Y735850D01*
X288900Y735267D01*
X288983Y734767D01*
X289317Y734183D01*
X289817Y733767D01*
X290483Y733600D01*
X290983Y733683D01*
X291567Y734017D01*
X291900Y734350D01*
G01X299517Y733600D02*
X301600Y738600D01*
X303683Y733600D01*
G01X302933Y735350D02*
X300267D01*
G01X305700Y731933D02*
Y736933D01*
G01Y736183D02*
X306117Y736600D01*
X306533Y736850D01*
X307200Y736933D01*
X307783Y736850D01*
X308367Y736433D01*
X308617Y735850D01*
X308700Y735267D01*
X308617Y734683D01*
X308367Y734100D01*
X307867Y733767D01*
X307200Y733600D01*
X306617Y733683D01*
X306033Y733933D01*
X305700Y734267D01*
G01X311300Y731933D02*
Y736933D01*
G01Y736183D02*
X311717Y736600D01*
X312133Y736850D01*
X312800Y736933D01*
X313383Y736850D01*
X313967Y736433D01*
X314217Y735850D01*
X314300Y735267D01*
X314217Y734683D01*
X313967Y734100D01*
X313467Y733767D01*
X312800Y733600D01*
X312217Y733683D01*
X311633Y733933D01*
X311300Y734267D01*
G01X318400Y733600D02*
Y738600D01*
G01X324000Y736933D02*
Y733600D01*
G01Y738267D02*
X323833Y738350D01*
Y738517D01*
X324000Y738600D01*
X324167Y738517D01*
Y738350D01*
X324000Y738267D01*
G01X330933Y736517D02*
X330350Y736850D01*
X329850Y736933D01*
X329183Y736767D01*
X328683Y736433D01*
X328350Y735850D01*
X328267Y735267D01*
X328350Y734683D01*
X328683Y734183D01*
X329183Y733767D01*
X329850Y733600D01*
X330433Y733767D01*
X330933Y734100D01*
G01X336700Y733600D02*
Y736933D01*
G01Y736350D02*
X336367Y736683D01*
X335867Y736850D01*
X335283Y736933D01*
X334700Y736767D01*
X334200Y736433D01*
X333867Y735933D01*
X333700Y735267D01*
X333867Y734600D01*
X334200Y734100D01*
X334700Y733767D01*
X335283Y733600D01*
X335867Y733683D01*
X336367Y733933D01*
X336700Y734267D01*
G01X340800Y738600D02*
Y733600D01*
G01X339633Y736933D02*
X341967D01*
G01X346400D02*
Y733600D01*
G01Y738267D02*
X346233Y738350D01*
Y738517D01*
X346400Y738600D01*
X346567Y738517D01*
Y738350D01*
X346400Y738267D01*
G01X352000Y733600D02*
X351500Y733683D01*
X351000Y734017D01*
X350667Y734600D01*
X350500Y735267D01*
X350667Y735933D01*
X351000Y736517D01*
X351500Y736850D01*
X352000Y736933D01*
X352500Y736850D01*
X353000Y736517D01*
X353333Y735933D01*
X353417Y735267D01*
X353333Y734600D01*
X353000Y734017D01*
X352500Y733683D01*
X352000Y733600D01*
G01X356183D02*
Y736933D01*
G01Y736100D02*
X356517Y736517D01*
X357017Y736850D01*
X357683Y736933D01*
X358267Y736850D01*
X358767Y736517D01*
X359017Y735933D01*
Y733600D01*
G01X361950Y734183D02*
X362367Y733850D01*
X362950Y733600D01*
X363450D01*
X363950Y733767D01*
X364283Y734017D01*
X364450Y734350D01*
X364367Y734850D01*
X364033Y735100D01*
X362533Y735600D01*
X362200Y736183D01*
X362367Y736600D01*
X362700Y736850D01*
X363200Y736933D01*
X363700Y736850D01*
X364200Y736600D01*
G01X71000Y747600D02*
X73000D01*
G01X72000D02*
Y742600D01*
G01X71000D02*
X73000D01*
G01X75933D02*
Y747600D01*
X77933D01*
X78600Y747350D01*
X79100Y746767D01*
X79267Y746100D01*
X79100Y745433D01*
X78683Y744933D01*
X77933Y744683D01*
X75933D01*
G01X85033Y747183D02*
X84533Y747433D01*
X83950Y747600D01*
X83283D01*
X82533Y747350D01*
X81950Y746933D01*
X81533Y746433D01*
X81200Y745600D01*
X81117Y744850D01*
X81283Y744100D01*
X81533Y743600D01*
X82033Y743100D01*
X82617Y742767D01*
X83200Y742600D01*
X83783D01*
X84367Y742767D01*
X84867Y743017D01*
X85283Y743350D01*
G01X87717Y744267D02*
X89883D01*
G01X95400Y742600D02*
Y747600D01*
X92317Y744017D01*
X96483D01*
G01X100000Y742600D02*
Y747600D01*
X99000Y746600D01*
G01Y742600D02*
X101000D01*
G01X105600Y747600D02*
X104933Y747433D01*
X104433Y747017D01*
X104100Y746517D01*
X103850Y745850D01*
X103767Y745100D01*
X103850Y744350D01*
X104100Y743683D01*
X104433Y743183D01*
X104933Y742767D01*
X105600Y742600D01*
X106267Y742767D01*
X106767Y743183D01*
X107100Y743683D01*
X107350Y744350D01*
X107433Y745100D01*
X107350Y745850D01*
X107100Y746517D01*
X106767Y747017D01*
X106267Y747433D01*
X105600Y747600D01*
G01X111200Y742600D02*
Y747600D01*
X110200Y746600D01*
G01Y742600D02*
X112200D01*
G01X120650Y743267D02*
X121317Y742850D01*
X122067Y742600D01*
X122733D01*
X123400Y742850D01*
X123900Y743267D01*
X124150Y743850D01*
X123983Y744433D01*
X123567Y744933D01*
X122817Y745267D01*
X121817Y745433D01*
X121233Y745767D01*
X120983Y746350D01*
X121150Y746933D01*
X121567Y747350D01*
X122150Y747600D01*
X122733D01*
X123317Y747433D01*
X123817Y747017D01*
G01X126500Y740933D02*
Y745933D01*
G01Y745183D02*
X126917Y745600D01*
X127333Y745850D01*
X128000Y745933D01*
X128583Y745850D01*
X129167Y745433D01*
X129417Y744850D01*
X129500Y744267D01*
X129417Y743683D01*
X129167Y743100D01*
X128667Y742767D01*
X128000Y742600D01*
X127417Y742683D01*
X126833Y742933D01*
X126500Y743267D01*
G01X132350Y744850D02*
X135017D01*
X134767Y745433D01*
X134350Y745767D01*
X133767Y745933D01*
X133183Y745850D01*
X132683Y745600D01*
X132350Y745017D01*
X132183Y744517D01*
Y744017D01*
X132350Y743517D01*
X132767Y743017D01*
X133267Y742683D01*
X133850Y742600D01*
X134433Y742767D01*
X135017Y743267D01*
G01X140533Y745517D02*
X139950Y745850D01*
X139450Y745933D01*
X138783Y745767D01*
X138283Y745433D01*
X137950Y744850D01*
X137867Y744267D01*
X137950Y743683D01*
X138283Y743183D01*
X138783Y742767D01*
X139450Y742600D01*
X140033Y742767D01*
X140533Y743100D01*
G01X144800Y745933D02*
Y742600D01*
G01Y747267D02*
X144633Y747350D01*
Y747517D01*
X144800Y747600D01*
X144967Y747517D01*
Y747350D01*
X144800Y747267D01*
G01X149900Y742600D02*
Y746850D01*
X150067Y747267D01*
X150400Y747517D01*
X150900Y747600D01*
X151400Y747433D01*
X151650Y747017D01*
G01X150650Y745600D02*
X148983D01*
G01X156000Y745933D02*
Y742600D01*
G01Y747267D02*
X155833Y747350D01*
Y747517D01*
X156000Y747600D01*
X156167Y747517D01*
Y747350D01*
X156000Y747267D01*
G01X162933Y745517D02*
X162350Y745850D01*
X161850Y745933D01*
X161183Y745767D01*
X160683Y745433D01*
X160350Y744850D01*
X160267Y744267D01*
X160350Y743683D01*
X160683Y743183D01*
X161183Y742767D01*
X161850Y742600D01*
X162433Y742767D01*
X162933Y743100D01*
G01X168700Y742600D02*
Y745933D01*
G01Y745350D02*
X168367Y745683D01*
X167867Y745850D01*
X167283Y745933D01*
X166700Y745767D01*
X166200Y745433D01*
X165867Y744933D01*
X165700Y744267D01*
X165867Y743600D01*
X166200Y743100D01*
X166700Y742767D01*
X167283Y742600D01*
X167867Y742683D01*
X168367Y742933D01*
X168700Y743267D01*
G01X172800Y747600D02*
Y742600D01*
G01X171633Y745933D02*
X173967D01*
G01X178400D02*
Y742600D01*
G01Y747267D02*
X178233Y747350D01*
Y747517D01*
X178400Y747600D01*
X178567Y747517D01*
Y747350D01*
X178400Y747267D01*
G01X184000Y742600D02*
X183500Y742683D01*
X183000Y743017D01*
X182667Y743600D01*
X182500Y744267D01*
X182667Y744933D01*
X183000Y745517D01*
X183500Y745850D01*
X184000Y745933D01*
X184500Y745850D01*
X185000Y745517D01*
X185333Y744933D01*
X185417Y744267D01*
X185333Y743600D01*
X185000Y743017D01*
X184500Y742683D01*
X184000Y742600D01*
G01X188183D02*
Y745933D01*
G01Y745100D02*
X188517Y745517D01*
X189017Y745850D01*
X189683Y745933D01*
X190267Y745850D01*
X190767Y745517D01*
X191017Y744933D01*
Y742600D01*
G01X200300D02*
Y746850D01*
X200467Y747267D01*
X200800Y747517D01*
X201300Y747600D01*
X201800Y747433D01*
X202050Y747017D01*
G01X201050Y745600D02*
X199383D01*
G01X206400Y742600D02*
X205900Y742683D01*
X205400Y743017D01*
X205067Y743600D01*
X204900Y744267D01*
X205067Y744933D01*
X205400Y745517D01*
X205900Y745850D01*
X206400Y745933D01*
X206900Y745850D01*
X207400Y745517D01*
X207733Y744933D01*
X207817Y744267D01*
X207733Y743600D01*
X207400Y743017D01*
X206900Y742683D01*
X206400Y742600D01*
G01X210833D02*
Y745933D01*
G01Y745267D02*
X211250Y745600D01*
X211667Y745850D01*
X212250Y745933D01*
X212667Y745850D01*
X213167Y745600D01*
G01X223867Y745267D02*
X224200Y745517D01*
X224450Y745933D01*
X224617Y746517D01*
X224450Y747017D01*
X224117Y747350D01*
X223533Y747600D01*
X221283D01*
Y742600D01*
X224033D01*
X224617Y742933D01*
X224950Y743433D01*
X225117Y744017D01*
X224950Y744600D01*
X224450Y745100D01*
X223867Y745267D01*
X221283D01*
G01X230300Y742600D02*
Y745933D01*
G01Y745350D02*
X229967Y745683D01*
X229467Y745850D01*
X228883Y745933D01*
X228300Y745767D01*
X227800Y745433D01*
X227467Y744933D01*
X227300Y744267D01*
X227467Y743600D01*
X227800Y743100D01*
X228300Y742767D01*
X228883Y742600D01*
X229467Y742683D01*
X229967Y742933D01*
X230300Y743267D01*
G01X233150Y743183D02*
X233567Y742850D01*
X234150Y742600D01*
X234650D01*
X235150Y742767D01*
X235483Y743017D01*
X235650Y743350D01*
X235567Y743850D01*
X235233Y744100D01*
X233733Y744600D01*
X233400Y745183D01*
X233567Y745600D01*
X233900Y745850D01*
X234400Y745933D01*
X234900Y745850D01*
X235400Y745600D01*
G01X238750Y744850D02*
X241417D01*
X241167Y745433D01*
X240750Y745767D01*
X240167Y745933D01*
X239583Y745850D01*
X239083Y745600D01*
X238750Y745017D01*
X238583Y744517D01*
Y744017D01*
X238750Y743517D01*
X239167Y743017D01*
X239667Y742683D01*
X240250Y742600D01*
X240833Y742767D01*
X241417Y743267D01*
G01X249033Y742600D02*
Y747600D01*
X251200Y743433D01*
X253367Y747600D01*
Y742600D01*
G01X258300D02*
Y745933D01*
G01Y745350D02*
X257967Y745683D01*
X257467Y745850D01*
X256883Y745933D01*
X256300Y745767D01*
X255800Y745433D01*
X255467Y744933D01*
X255300Y744267D01*
X255467Y743600D01*
X255800Y743100D01*
X256300Y742767D01*
X256883Y742600D01*
X257467Y742683D01*
X257967Y742933D01*
X258300Y743267D01*
G01X262400Y747600D02*
Y742600D01*
G01X261233Y745933D02*
X263567D01*
G01X266750Y744850D02*
X269417D01*
X269167Y745433D01*
X268750Y745767D01*
X268167Y745933D01*
X267583Y745850D01*
X267083Y745600D01*
X266750Y745017D01*
X266583Y744517D01*
Y744017D01*
X266750Y743517D01*
X267167Y743017D01*
X267667Y742683D01*
X268250Y742600D01*
X268833Y742767D01*
X269417Y743267D01*
G01X272433Y742600D02*
Y745933D01*
G01Y745267D02*
X272850Y745600D01*
X273267Y745850D01*
X273850Y745933D01*
X274267Y745850D01*
X274767Y745600D01*
G01X279200Y745933D02*
Y742600D01*
G01Y747267D02*
X279033Y747350D01*
Y747517D01*
X279200Y747600D01*
X279367Y747517D01*
Y747350D01*
X279200Y747267D01*
G01X286300Y742600D02*
Y745933D01*
G01Y745350D02*
X285967Y745683D01*
X285467Y745850D01*
X284883Y745933D01*
X284300Y745767D01*
X283800Y745433D01*
X283467Y744933D01*
X283300Y744267D01*
X283467Y743600D01*
X283800Y743100D01*
X284300Y742767D01*
X284883Y742600D01*
X285467Y742683D01*
X285967Y742933D01*
X286300Y743267D01*
G01X290400Y742600D02*
Y747600D01*
G01X294750Y743183D02*
X295167Y742850D01*
X295750Y742600D01*
X296250D01*
X296750Y742767D01*
X297083Y743017D01*
X297250Y743350D01*
X297167Y743850D01*
X296833Y744100D01*
X295333Y744600D01*
X295000Y745183D01*
X295167Y745600D01*
X295500Y745850D01*
X296000Y745933D01*
X296500Y745850D01*
X297000Y745600D01*
G01X306700Y742600D02*
Y746850D01*
X306867Y747267D01*
X307200Y747517D01*
X307700Y747600D01*
X308200Y747433D01*
X308450Y747017D01*
G01X307450Y745600D02*
X305783D01*
G01X312800Y742600D02*
X312300Y742683D01*
X311800Y743017D01*
X311467Y743600D01*
X311300Y744267D01*
X311467Y744933D01*
X311800Y745517D01*
X312300Y745850D01*
X312800Y745933D01*
X313300Y745850D01*
X313800Y745517D01*
X314133Y744933D01*
X314217Y744267D01*
X314133Y743600D01*
X313800Y743017D01*
X313300Y742683D01*
X312800Y742600D01*
G01X317233D02*
Y745933D01*
G01Y745267D02*
X317650Y745600D01*
X318067Y745850D01*
X318650Y745933D01*
X319067Y745850D01*
X319567Y745600D01*
G01X327933Y742600D02*
Y747600D01*
X330017D01*
X330683Y747350D01*
X331100Y747017D01*
X331267Y746350D01*
X331100Y745683D01*
X330600Y745267D01*
X330017Y745017D01*
X327933D01*
G01X330017D02*
X331267Y742600D01*
G01X335200Y745933D02*
Y742600D01*
G01Y747267D02*
X335033Y747350D01*
Y747517D01*
X335200Y747600D01*
X335367Y747517D01*
Y747350D01*
X335200Y747267D01*
G01X339633Y741350D02*
X340217Y741017D01*
X340883Y740933D01*
X341467Y741017D01*
X341967Y741433D01*
X342300Y742017D01*
Y745933D01*
G01Y745267D02*
X341967Y745600D01*
X341467Y745850D01*
X340883Y745933D01*
X340217Y745767D01*
X339800Y745433D01*
X339467Y744850D01*
X339300Y744267D01*
X339383Y743767D01*
X339717Y743183D01*
X340217Y742767D01*
X340883Y742600D01*
X341383Y742683D01*
X341967Y743017D01*
X342300Y743350D01*
G01X346400Y745933D02*
Y742600D01*
G01Y747267D02*
X346233Y747350D01*
Y747517D01*
X346400Y747600D01*
X346567Y747517D01*
Y747350D01*
X346400Y747267D01*
G01X353500Y747600D02*
Y742600D01*
G01Y743350D02*
X353167Y742933D01*
X352667Y742683D01*
X352083Y742600D01*
X351417Y742767D01*
X350917Y743183D01*
X350583Y743683D01*
X350500Y744267D01*
X350583Y744850D01*
X350917Y745350D01*
X351417Y745767D01*
X352083Y745933D01*
X352667Y745850D01*
X353083Y745683D01*
X353500Y745350D01*
G01X364700Y742600D02*
Y745933D01*
G01Y745350D02*
X364367Y745683D01*
X363867Y745850D01*
X363283Y745933D01*
X362700Y745767D01*
X362200Y745433D01*
X361867Y744933D01*
X361700Y744267D01*
X361867Y743600D01*
X362200Y743100D01*
X362700Y742767D01*
X363283Y742600D01*
X363867Y742683D01*
X364367Y742933D01*
X364700Y743267D01*
G01X367383Y742600D02*
Y745933D01*
G01Y745100D02*
X367717Y745517D01*
X368217Y745850D01*
X368883Y745933D01*
X369467Y745850D01*
X369967Y745517D01*
X370217Y744933D01*
Y742600D01*
G01X375900Y747600D02*
Y742600D01*
G01Y743350D02*
X375567Y742933D01*
X375067Y742683D01*
X374483Y742600D01*
X373817Y742767D01*
X373317Y743183D01*
X372983Y743683D01*
X372900Y744267D01*
X372983Y744850D01*
X373317Y745350D01*
X373817Y745767D01*
X374483Y745933D01*
X375067Y745850D01*
X375483Y745683D01*
X375900Y745350D01*
G01X383433Y742600D02*
Y747600D01*
X385600Y743433D01*
X387767Y747600D01*
Y742600D01*
G01X389783Y745933D02*
Y743600D01*
X390117Y743017D01*
X390617Y742683D01*
X391200Y742600D01*
X391783Y742683D01*
X392283Y743017D01*
X392617Y743600D01*
G01Y742600D02*
Y745933D01*
G01X396800Y742600D02*
Y747600D01*
G01X402400D02*
Y742600D01*
G01X401233Y745933D02*
X403567D01*
G01X408000D02*
Y742600D01*
G01Y747267D02*
X407833Y747350D01*
Y747517D01*
X408000Y747600D01*
X408167Y747517D01*
Y747350D01*
X408000Y747267D01*
G01X413600Y742600D02*
Y747600D01*
G01X420700Y742600D02*
Y745933D01*
G01Y745350D02*
X420367Y745683D01*
X419867Y745850D01*
X419283Y745933D01*
X418700Y745767D01*
X418200Y745433D01*
X417867Y744933D01*
X417700Y744267D01*
X417867Y743600D01*
X418200Y743100D01*
X418700Y742767D01*
X419283Y742600D01*
X419867Y742683D01*
X420367Y742933D01*
X420700Y743267D01*
G01X423050Y741100D02*
X423550Y740933D01*
X424217Y741100D01*
X424633Y741433D01*
X424967Y741850D01*
X425467Y743183D01*
X426550Y745933D01*
G01X423883D02*
X425467Y743183D01*
G01X429150Y744850D02*
X431817D01*
X431567Y745433D01*
X431150Y745767D01*
X430567Y745933D01*
X429983Y745850D01*
X429483Y745600D01*
X429150Y745017D01*
X428983Y744517D01*
Y744017D01*
X429150Y743517D01*
X429567Y743017D01*
X430067Y742683D01*
X430650Y742600D01*
X431233Y742767D01*
X431817Y743267D01*
G01X434833Y742600D02*
Y745933D01*
G01Y745267D02*
X435250Y745600D01*
X435667Y745850D01*
X436250Y745933D01*
X436667Y745850D01*
X437167Y745600D01*
G01X445533Y742600D02*
Y747600D01*
X447533D01*
X448200Y747350D01*
X448700Y746767D01*
X448867Y746100D01*
X448700Y745433D01*
X448283Y744933D01*
X447533Y744683D01*
X445533D01*
G01X451633Y742600D02*
Y745933D01*
G01Y745267D02*
X452050Y745600D01*
X452467Y745850D01*
X453050Y745933D01*
X453467Y745850D01*
X453967Y745600D01*
G01X458400Y745933D02*
Y742600D01*
G01Y747267D02*
X458233Y747350D01*
Y747517D01*
X458400Y747600D01*
X458567Y747517D01*
Y747350D01*
X458400Y747267D01*
G01X462583Y742600D02*
Y745933D01*
G01Y745100D02*
X462917Y745517D01*
X463417Y745850D01*
X464083Y745933D01*
X464667Y745850D01*
X465167Y745517D01*
X465417Y744933D01*
Y742600D01*
G01X469600Y747600D02*
Y742600D01*
G01X468433Y745933D02*
X470767D01*
G01X473950Y744850D02*
X476617D01*
X476367Y745433D01*
X475950Y745767D01*
X475367Y745933D01*
X474783Y745850D01*
X474283Y745600D01*
X473950Y745017D01*
X473783Y744517D01*
Y744017D01*
X473950Y743517D01*
X474367Y743017D01*
X474867Y742683D01*
X475450Y742600D01*
X476033Y742767D01*
X476617Y743267D01*
G01X482300Y747600D02*
Y742600D01*
G01Y743350D02*
X481967Y742933D01*
X481467Y742683D01*
X480883Y742600D01*
X480217Y742767D01*
X479717Y743183D01*
X479383Y743683D01*
X479300Y744267D01*
X479383Y744850D01*
X479717Y745350D01*
X480217Y745767D01*
X480883Y745933D01*
X481467Y745850D01*
X481883Y745683D01*
X482300Y745350D01*
G01X492667Y745267D02*
X493000Y745517D01*
X493250Y745933D01*
X493417Y746517D01*
X493250Y747017D01*
X492917Y747350D01*
X492333Y747600D01*
X490083D01*
Y742600D01*
X492833D01*
X493417Y742933D01*
X493750Y743433D01*
X493917Y744017D01*
X493750Y744600D01*
X493250Y745100D01*
X492667Y745267D01*
X490083D01*
G01X497600Y742600D02*
X497100Y742683D01*
X496600Y743017D01*
X496267Y743600D01*
X496100Y744267D01*
X496267Y744933D01*
X496600Y745517D01*
X497100Y745850D01*
X497600Y745933D01*
X498100Y745850D01*
X498600Y745517D01*
X498933Y744933D01*
X499017Y744267D01*
X498933Y743600D01*
X498600Y743017D01*
X498100Y742683D01*
X497600Y742600D01*
G01X504700D02*
Y745933D01*
G01Y745350D02*
X504367Y745683D01*
X503867Y745850D01*
X503283Y745933D01*
X502700Y745767D01*
X502200Y745433D01*
X501867Y744933D01*
X501700Y744267D01*
X501867Y743600D01*
X502200Y743100D01*
X502700Y742767D01*
X503283Y742600D01*
X503867Y742683D01*
X504367Y742933D01*
X504700Y743267D01*
G01X507633Y742600D02*
Y745933D01*
G01Y745267D02*
X508050Y745600D01*
X508467Y745850D01*
X509050Y745933D01*
X509467Y745850D01*
X509967Y745600D01*
G01X515900Y747600D02*
Y742600D01*
G01Y743350D02*
X515567Y742933D01*
X515067Y742683D01*
X514483Y742600D01*
X513817Y742767D01*
X513317Y743183D01*
X512983Y743683D01*
X512900Y744267D01*
X512983Y744850D01*
X513317Y745350D01*
X513817Y745767D01*
X514483Y745933D01*
X515067Y745850D01*
X515483Y745683D01*
X515900Y745350D01*
G01X518750Y743183D02*
X519167Y742850D01*
X519750Y742600D01*
X520250D01*
X520750Y742767D01*
X521083Y743017D01*
X521250Y743350D01*
X521167Y743850D01*
X520833Y744100D01*
X519333Y744600D01*
X519000Y745183D01*
X519167Y745600D01*
X519500Y745850D01*
X520000Y745933D01*
X520500Y745850D01*
X521000Y745600D01*
G01X71000Y756600D02*
X73000D01*
G01X72000D02*
Y751600D01*
G01X71000D02*
X73000D01*
G01X75933D02*
Y756600D01*
X77933D01*
X78600Y756350D01*
X79100Y755767D01*
X79267Y755100D01*
X79100Y754433D01*
X78683Y753933D01*
X77933Y753683D01*
X75933D01*
G01X85033Y756183D02*
X84533Y756433D01*
X83950Y756600D01*
X83283D01*
X82533Y756350D01*
X81950Y755933D01*
X81533Y755433D01*
X81200Y754600D01*
X81117Y753850D01*
X81283Y753100D01*
X81533Y752600D01*
X82033Y752100D01*
X82617Y751767D01*
X83200Y751600D01*
X83783D01*
X84367Y751767D01*
X84867Y752017D01*
X85283Y752350D01*
G01X87717Y753267D02*
X89883D01*
G01X94400Y756600D02*
Y751600D01*
G01X92483Y756600D02*
X96317D01*
G01X97833Y751600D02*
Y756600D01*
X100000Y752433D01*
X102167Y756600D01*
Y751600D01*
G01X104517Y753267D02*
X106683D01*
G01X109617Y753683D02*
X110200Y754267D01*
X110700Y754600D01*
X111367Y754767D01*
X111950Y754600D01*
X112367Y754267D01*
X112700Y753767D01*
X112783Y753183D01*
X112700Y752683D01*
X112367Y752183D01*
X111867Y751767D01*
X111283Y751600D01*
X110617Y751767D01*
X110033Y752267D01*
X109700Y753017D01*
X109617Y753850D01*
X109783Y754933D01*
X110033Y755517D01*
X110450Y756100D01*
X111033Y756517D01*
X111617Y756600D01*
X112200Y756433D01*
X112617Y756017D01*
G01X114967Y752350D02*
X115467Y751933D01*
X116050Y751683D01*
X116800Y751600D01*
X117550Y751767D01*
X118133Y752100D01*
X118550Y752683D01*
X118633Y753350D01*
X118467Y754017D01*
X118050Y754433D01*
X117467Y754767D01*
X116883Y754850D01*
X116300Y754767D01*
X115550Y754433D01*
X115800Y756600D01*
X118050D01*
G01X122400D02*
X121733Y756433D01*
X121233Y756017D01*
X120900Y755517D01*
X120650Y754850D01*
X120567Y754100D01*
X120650Y753350D01*
X120900Y752683D01*
X121233Y752183D01*
X121733Y751767D01*
X122400Y751600D01*
X123067Y751767D01*
X123567Y752183D01*
X123900Y752683D01*
X124150Y753350D01*
X124233Y754100D01*
X124150Y754850D01*
X123900Y755517D01*
X123567Y756017D01*
X123067Y756433D01*
X122400Y756600D01*
G01X133600D02*
Y751600D01*
G01X131683Y756600D02*
X135517D01*
G01X137950Y753850D02*
X140617D01*
X140367Y754433D01*
X139950Y754767D01*
X139367Y754933D01*
X138783Y754850D01*
X138283Y754600D01*
X137950Y754017D01*
X137783Y753517D01*
Y753017D01*
X137950Y752517D01*
X138367Y752017D01*
X138867Y751683D01*
X139450Y751600D01*
X140033Y751767D01*
X140617Y752267D01*
G01X143550Y752183D02*
X143967Y751850D01*
X144550Y751600D01*
X145050D01*
X145550Y751767D01*
X145883Y752017D01*
X146050Y752350D01*
X145967Y752850D01*
X145633Y753100D01*
X144133Y753600D01*
X143800Y754183D01*
X143967Y754600D01*
X144300Y754850D01*
X144800Y754933D01*
X145300Y754850D01*
X145800Y754600D01*
G01X150400Y756600D02*
Y751600D01*
G01X149233Y754933D02*
X151567D01*
G01X159433Y751600D02*
Y756600D01*
X161600Y752433D01*
X163767Y756600D01*
Y751600D01*
G01X165950Y753850D02*
X168617D01*
X168367Y754433D01*
X167950Y754767D01*
X167367Y754933D01*
X166783Y754850D01*
X166283Y754600D01*
X165950Y754017D01*
X165783Y753517D01*
Y753017D01*
X165950Y752517D01*
X166367Y752017D01*
X166867Y751683D01*
X167450Y751600D01*
X168033Y751767D01*
X168617Y752267D01*
G01X172800Y756600D02*
Y751600D01*
G01X171633Y754933D02*
X173967D01*
G01X176983Y751600D02*
Y756600D01*
G01Y754183D02*
X177400Y754600D01*
X177817Y754850D01*
X178483Y754933D01*
X178983Y754850D01*
X179567Y754517D01*
X179817Y754017D01*
Y751600D01*
G01X184000D02*
X183500Y751683D01*
X183000Y752017D01*
X182667Y752600D01*
X182500Y753267D01*
X182667Y753933D01*
X183000Y754517D01*
X183500Y754850D01*
X184000Y754933D01*
X184500Y754850D01*
X185000Y754517D01*
X185333Y753933D01*
X185417Y753267D01*
X185333Y752600D01*
X185000Y752017D01*
X184500Y751683D01*
X184000Y751600D01*
G01X191100Y756600D02*
Y751600D01*
G01Y752350D02*
X190767Y751933D01*
X190267Y751683D01*
X189683Y751600D01*
X189017Y751767D01*
X188517Y752183D01*
X188183Y752683D01*
X188100Y753267D01*
X188183Y753850D01*
X188517Y754350D01*
X189017Y754767D01*
X189683Y754933D01*
X190267Y754850D01*
X190683Y754683D01*
X191100Y754350D01*
G01X193950Y752183D02*
X194367Y751850D01*
X194950Y751600D01*
X195450D01*
X195950Y751767D01*
X196283Y752017D01*
X196450Y752350D01*
X196367Y752850D01*
X196033Y753100D01*
X194533Y753600D01*
X194200Y754183D01*
X194367Y754600D01*
X194700Y754850D01*
X195200Y754933D01*
X195700Y754850D01*
X196200Y754600D01*
G01X204233Y751600D02*
Y756600D01*
X206400Y752433D01*
X208567Y756600D01*
Y751600D01*
G01X213500D02*
Y754933D01*
G01Y754350D02*
X213167Y754683D01*
X212667Y754850D01*
X212083Y754933D01*
X211500Y754767D01*
X211000Y754433D01*
X210667Y753933D01*
X210500Y753267D01*
X210667Y752600D01*
X211000Y752100D01*
X211500Y751767D01*
X212083Y751600D01*
X212667Y751683D01*
X213167Y751933D01*
X213500Y752267D01*
G01X216183Y751600D02*
Y754933D01*
G01Y754100D02*
X216517Y754517D01*
X217017Y754850D01*
X217683Y754933D01*
X218267Y754850D01*
X218767Y754517D01*
X219017Y753933D01*
Y751600D01*
G01X221783Y754933D02*
Y752600D01*
X222117Y752017D01*
X222617Y751683D01*
X223200Y751600D01*
X223783Y751683D01*
X224283Y752017D01*
X224617Y752600D01*
G01Y751600D02*
Y754933D01*
G01X230300Y751600D02*
Y754933D01*
G01Y754350D02*
X229967Y754683D01*
X229467Y754850D01*
X228883Y754933D01*
X228300Y754767D01*
X227800Y754433D01*
X227467Y753933D01*
X227300Y753267D01*
X227467Y752600D01*
X227800Y752100D01*
X228300Y751767D01*
X228883Y751600D01*
X229467Y751683D01*
X229967Y751933D01*
X230300Y752267D01*
G01X234400Y751600D02*
Y756600D01*
G01X71000Y765600D02*
X73000D01*
G01X72000D02*
Y760600D01*
G01X71000D02*
X73000D01*
G01X75933D02*
Y765600D01*
X77933D01*
X78600Y765350D01*
X79100Y764767D01*
X79267Y764100D01*
X79100Y763433D01*
X78683Y762933D01*
X77933Y762683D01*
X75933D01*
G01X85033Y765183D02*
X84533Y765433D01*
X83950Y765600D01*
X83283D01*
X82533Y765350D01*
X81950Y764933D01*
X81533Y764433D01*
X81200Y763600D01*
X81117Y762850D01*
X81283Y762100D01*
X81533Y761600D01*
X82033Y761100D01*
X82617Y760767D01*
X83200Y760600D01*
X83783D01*
X84367Y760767D01*
X84867Y761017D01*
X85283Y761350D01*
G01X87717Y762267D02*
X89883D01*
G01X92817Y762683D02*
X93400Y763267D01*
X93900Y763600D01*
X94567Y763767D01*
X95150Y763600D01*
X95567Y763267D01*
X95900Y762767D01*
X95983Y762183D01*
X95900Y761683D01*
X95567Y761183D01*
X95067Y760767D01*
X94483Y760600D01*
X93817Y760767D01*
X93233Y761267D01*
X92900Y762017D01*
X92817Y762850D01*
X92983Y763933D01*
X93233Y764517D01*
X93650Y765100D01*
X94233Y765517D01*
X94817Y765600D01*
X95400Y765433D01*
X95817Y765017D01*
G01X100000Y765600D02*
X99333Y765433D01*
X98833Y765017D01*
X98500Y764517D01*
X98250Y763850D01*
X98167Y763100D01*
X98250Y762350D01*
X98500Y761683D01*
X98833Y761183D01*
X99333Y760767D01*
X100000Y760600D01*
X100667Y760767D01*
X101167Y761183D01*
X101500Y761683D01*
X101750Y762350D01*
X101833Y763100D01*
X101750Y763850D01*
X101500Y764517D01*
X101167Y765017D01*
X100667Y765433D01*
X100000Y765600D01*
G01X105600Y760600D02*
Y765600D01*
X104600Y764600D01*
G01Y760600D02*
X106600D01*
G01X109617Y762683D02*
X110200Y763267D01*
X110700Y763600D01*
X111367Y763767D01*
X111950Y763600D01*
X112367Y763267D01*
X112700Y762767D01*
X112783Y762183D01*
X112700Y761683D01*
X112367Y761183D01*
X111867Y760767D01*
X111283Y760600D01*
X110617Y760767D01*
X110033Y761267D01*
X109700Y762017D01*
X109617Y762850D01*
X109783Y763933D01*
X110033Y764517D01*
X110450Y765100D01*
X111033Y765517D01*
X111617Y765600D01*
X112200Y765433D01*
X112617Y765017D01*
G01X122400Y760600D02*
X121733Y760683D01*
X121150Y761017D01*
X120650Y761517D01*
X120317Y762100D01*
X120150Y762767D01*
Y763433D01*
X120317Y764100D01*
X120650Y764683D01*
X121150Y765183D01*
X121733Y765517D01*
X122400Y765600D01*
X123067Y765517D01*
X123650Y765183D01*
X124150Y764683D01*
X124483Y764100D01*
X124650Y763433D01*
Y762767D01*
X124483Y762100D01*
X124150Y761517D01*
X123650Y761017D01*
X123067Y760683D01*
X122400Y760600D01*
G01X123067Y761933D02*
X124067Y760600D01*
G01X126583Y763933D02*
Y761600D01*
X126917Y761017D01*
X127417Y760683D01*
X128000Y760600D01*
X128583Y760683D01*
X129083Y761017D01*
X129417Y761600D01*
G01Y760600D02*
Y763933D01*
G01X135100Y760600D02*
Y763933D01*
G01Y763350D02*
X134767Y763683D01*
X134267Y763850D01*
X133683Y763933D01*
X133100Y763767D01*
X132600Y763433D01*
X132267Y762933D01*
X132100Y762267D01*
X132267Y761600D01*
X132600Y761100D01*
X133100Y760767D01*
X133683Y760600D01*
X134267Y760683D01*
X134767Y760933D01*
X135100Y761267D01*
G01X139200Y760600D02*
Y765600D01*
G01X144800Y763933D02*
Y760600D01*
G01Y765267D02*
X144633Y765350D01*
Y765517D01*
X144800Y765600D01*
X144967Y765517D01*
Y765350D01*
X144800Y765267D01*
G01X149900Y760600D02*
Y764850D01*
X150067Y765267D01*
X150400Y765517D01*
X150900Y765600D01*
X151400Y765433D01*
X151650Y765017D01*
G01X150650Y763600D02*
X148983D01*
G01X156000Y763933D02*
Y760600D01*
G01Y765267D02*
X155833Y765350D01*
Y765517D01*
X156000Y765600D01*
X156167Y765517D01*
Y765350D01*
X156000Y765267D01*
G01X162933Y763517D02*
X162350Y763850D01*
X161850Y763933D01*
X161183Y763767D01*
X160683Y763433D01*
X160350Y762850D01*
X160267Y762267D01*
X160350Y761683D01*
X160683Y761183D01*
X161183Y760767D01*
X161850Y760600D01*
X162433Y760767D01*
X162933Y761100D01*
G01X168700Y760600D02*
Y763933D01*
G01Y763350D02*
X168367Y763683D01*
X167867Y763850D01*
X167283Y763933D01*
X166700Y763767D01*
X166200Y763433D01*
X165867Y762933D01*
X165700Y762267D01*
X165867Y761600D01*
X166200Y761100D01*
X166700Y760767D01*
X167283Y760600D01*
X167867Y760683D01*
X168367Y760933D01*
X168700Y761267D01*
G01X172800Y765600D02*
Y760600D01*
G01X171633Y763933D02*
X173967D01*
G01X178400D02*
Y760600D01*
G01Y765267D02*
X178233Y765350D01*
Y765517D01*
X178400Y765600D01*
X178567Y765517D01*
Y765350D01*
X178400Y765267D01*
G01X184000Y760600D02*
X183500Y760683D01*
X183000Y761017D01*
X182667Y761600D01*
X182500Y762267D01*
X182667Y762933D01*
X183000Y763517D01*
X183500Y763850D01*
X184000Y763933D01*
X184500Y763850D01*
X185000Y763517D01*
X185333Y762933D01*
X185417Y762267D01*
X185333Y761600D01*
X185000Y761017D01*
X184500Y760683D01*
X184000Y760600D01*
G01X188183D02*
Y763933D01*
G01Y763100D02*
X188517Y763517D01*
X189017Y763850D01*
X189683Y763933D01*
X190267Y763850D01*
X190767Y763517D01*
X191017Y762933D01*
Y760600D01*
G01X203300Y758933D02*
X199133Y763933D01*
Y764767D01*
X199967Y765600D01*
X200800D01*
X201633Y764767D01*
Y763933D01*
X200800Y763100D01*
X199133Y762267D01*
X198300Y761433D01*
Y759767D01*
X199133Y758933D01*
X201633D01*
X203300Y760600D01*
G01X210333D02*
Y765600D01*
X212333D01*
X213000Y765350D01*
X213500Y764767D01*
X213667Y764100D01*
X213500Y763433D01*
X213083Y762933D01*
X212333Y762683D01*
X210333D01*
G01X216350Y762850D02*
X219017D01*
X218767Y763433D01*
X218350Y763767D01*
X217767Y763933D01*
X217183Y763850D01*
X216683Y763600D01*
X216350Y763017D01*
X216183Y762517D01*
Y762017D01*
X216350Y761517D01*
X216767Y761017D01*
X217267Y760683D01*
X217850Y760600D01*
X218433Y760767D01*
X219017Y761267D01*
G01X222033Y760600D02*
Y763933D01*
G01Y763267D02*
X222450Y763600D01*
X222867Y763850D01*
X223450Y763933D01*
X223867Y763850D01*
X224367Y763600D01*
G01X228300Y760600D02*
Y764850D01*
X228467Y765267D01*
X228800Y765517D01*
X229300Y765600D01*
X229800Y765433D01*
X230050Y765017D01*
G01X229050Y763600D02*
X227383D01*
G01X234400Y760600D02*
X233900Y760683D01*
X233400Y761017D01*
X233067Y761600D01*
X232900Y762267D01*
X233067Y762933D01*
X233400Y763517D01*
X233900Y763850D01*
X234400Y763933D01*
X234900Y763850D01*
X235400Y763517D01*
X235733Y762933D01*
X235817Y762267D01*
X235733Y761600D01*
X235400Y761017D01*
X234900Y760683D01*
X234400Y760600D01*
G01X238833D02*
Y763933D01*
G01Y763267D02*
X239250Y763600D01*
X239667Y763850D01*
X240250Y763933D01*
X240667Y763850D01*
X241167Y763600D01*
G01X243100Y760600D02*
Y763933D01*
G01Y763017D02*
X243350Y763433D01*
X243767Y763767D01*
X244350Y763933D01*
X244933Y763767D01*
X245350Y763433D01*
X245600Y763017D01*
Y760600D01*
G01Y763017D02*
X245850Y763433D01*
X246267Y763767D01*
X246850Y763933D01*
X247433Y763767D01*
X247850Y763433D01*
X248100Y762933D01*
Y760600D01*
G01X252700D02*
Y763933D01*
G01Y763350D02*
X252367Y763683D01*
X251867Y763850D01*
X251283Y763933D01*
X250700Y763767D01*
X250200Y763433D01*
X249867Y762933D01*
X249700Y762267D01*
X249867Y761600D01*
X250200Y761100D01*
X250700Y760767D01*
X251283Y760600D01*
X251867Y760683D01*
X252367Y760933D01*
X252700Y761267D01*
G01X255383Y760600D02*
Y763933D01*
G01Y763100D02*
X255717Y763517D01*
X256217Y763850D01*
X256883Y763933D01*
X257467Y763850D01*
X257967Y763517D01*
X258217Y762933D01*
Y760600D01*
G01X263733Y763517D02*
X263150Y763850D01*
X262650Y763933D01*
X261983Y763767D01*
X261483Y763433D01*
X261150Y762850D01*
X261067Y762267D01*
X261150Y761683D01*
X261483Y761183D01*
X261983Y760767D01*
X262650Y760600D01*
X263233Y760767D01*
X263733Y761100D01*
G01X266750Y762850D02*
X269417D01*
X269167Y763433D01*
X268750Y763767D01*
X268167Y763933D01*
X267583Y763850D01*
X267083Y763600D01*
X266750Y763017D01*
X266583Y762517D01*
Y762017D01*
X266750Y761517D01*
X267167Y761017D01*
X267667Y760683D01*
X268250Y760600D01*
X268833Y760767D01*
X269417Y761267D01*
G01X277450D02*
X278117Y760850D01*
X278867Y760600D01*
X279533D01*
X280200Y760850D01*
X280700Y761267D01*
X280950Y761850D01*
X280783Y762433D01*
X280367Y762933D01*
X279617Y763267D01*
X278617Y763433D01*
X278033Y763767D01*
X277783Y764350D01*
X277950Y764933D01*
X278367Y765350D01*
X278950Y765600D01*
X279533D01*
X280117Y765433D01*
X280617Y765017D01*
G01X283300Y758933D02*
Y763933D01*
G01Y763183D02*
X283717Y763600D01*
X284133Y763850D01*
X284800Y763933D01*
X285383Y763850D01*
X285967Y763433D01*
X286217Y762850D01*
X286300Y762267D01*
X286217Y761683D01*
X285967Y761100D01*
X285467Y760767D01*
X284800Y760600D01*
X284217Y760683D01*
X283633Y760933D01*
X283300Y761267D01*
G01X289150Y762850D02*
X291817D01*
X291567Y763433D01*
X291150Y763767D01*
X290567Y763933D01*
X289983Y763850D01*
X289483Y763600D01*
X289150Y763017D01*
X288983Y762517D01*
Y762017D01*
X289150Y761517D01*
X289567Y761017D01*
X290067Y760683D01*
X290650Y760600D01*
X291233Y760767D01*
X291817Y761267D01*
G01X297333Y763517D02*
X296750Y763850D01*
X296250Y763933D01*
X295583Y763767D01*
X295083Y763433D01*
X294750Y762850D01*
X294667Y762267D01*
X294750Y761683D01*
X295083Y761183D01*
X295583Y760767D01*
X296250Y760600D01*
X296833Y760767D01*
X297333Y761100D01*
G01X301600Y763933D02*
Y760600D01*
G01Y765267D02*
X301433Y765350D01*
Y765517D01*
X301600Y765600D01*
X301767Y765517D01*
Y765350D01*
X301600Y765267D01*
G01X306700Y760600D02*
Y764850D01*
X306867Y765267D01*
X307200Y765517D01*
X307700Y765600D01*
X308200Y765433D01*
X308450Y765017D01*
G01X307450Y763600D02*
X305783D01*
G01X312800Y763933D02*
Y760600D01*
G01Y765267D02*
X312633Y765350D01*
Y765517D01*
X312800Y765600D01*
X312967Y765517D01*
Y765350D01*
X312800Y765267D01*
G01X319733Y763517D02*
X319150Y763850D01*
X318650Y763933D01*
X317983Y763767D01*
X317483Y763433D01*
X317150Y762850D01*
X317067Y762267D01*
X317150Y761683D01*
X317483Y761183D01*
X317983Y760767D01*
X318650Y760600D01*
X319233Y760767D01*
X319733Y761100D01*
G01X325500Y760600D02*
Y763933D01*
G01Y763350D02*
X325167Y763683D01*
X324667Y763850D01*
X324083Y763933D01*
X323500Y763767D01*
X323000Y763433D01*
X322667Y762933D01*
X322500Y762267D01*
X322667Y761600D01*
X323000Y761100D01*
X323500Y760767D01*
X324083Y760600D01*
X324667Y760683D01*
X325167Y760933D01*
X325500Y761267D01*
G01X329600Y765600D02*
Y760600D01*
G01X328433Y763933D02*
X330767D01*
G01X335200D02*
Y760600D01*
G01Y765267D02*
X335033Y765350D01*
Y765517D01*
X335200Y765600D01*
X335367Y765517D01*
Y765350D01*
X335200Y765267D01*
G01X340800Y760600D02*
X340300Y760683D01*
X339800Y761017D01*
X339467Y761600D01*
X339300Y762267D01*
X339467Y762933D01*
X339800Y763517D01*
X340300Y763850D01*
X340800Y763933D01*
X341300Y763850D01*
X341800Y763517D01*
X342133Y762933D01*
X342217Y762267D01*
X342133Y761600D01*
X341800Y761017D01*
X341300Y760683D01*
X340800Y760600D01*
G01X344983D02*
Y763933D01*
G01Y763100D02*
X345317Y763517D01*
X345817Y763850D01*
X346483Y763933D01*
X347067Y763850D01*
X347567Y763517D01*
X347817Y762933D01*
Y760600D01*
G01X357100D02*
Y764850D01*
X357267Y765267D01*
X357600Y765517D01*
X358100Y765600D01*
X358600Y765433D01*
X358850Y765017D01*
G01X357850Y763600D02*
X356183D01*
G01X363200Y760600D02*
X362700Y760683D01*
X362200Y761017D01*
X361867Y761600D01*
X361700Y762267D01*
X361867Y762933D01*
X362200Y763517D01*
X362700Y763850D01*
X363200Y763933D01*
X363700Y763850D01*
X364200Y763517D01*
X364533Y762933D01*
X364617Y762267D01*
X364533Y761600D01*
X364200Y761017D01*
X363700Y760683D01*
X363200Y760600D01*
G01X367633D02*
Y763933D01*
G01Y763267D02*
X368050Y763600D01*
X368467Y763850D01*
X369050Y763933D01*
X369467Y763850D01*
X369967Y763600D01*
G01X378250Y760600D02*
Y765600D01*
G01X381750D02*
Y760600D01*
G01Y763100D02*
X378250D01*
G01X385600Y763933D02*
Y760600D01*
G01Y765267D02*
X385433Y765350D01*
Y765517D01*
X385600Y765600D01*
X385767Y765517D01*
Y765350D01*
X385600Y765267D01*
G01X390033Y759350D02*
X390617Y759017D01*
X391283Y758933D01*
X391867Y759017D01*
X392367Y759433D01*
X392700Y760017D01*
Y763933D01*
G01Y763267D02*
X392367Y763600D01*
X391867Y763850D01*
X391283Y763933D01*
X390617Y763767D01*
X390200Y763433D01*
X389867Y762850D01*
X389700Y762267D01*
X389783Y761767D01*
X390117Y761183D01*
X390617Y760767D01*
X391283Y760600D01*
X391783Y760683D01*
X392367Y761017D01*
X392700Y761350D01*
G01X395383Y760600D02*
Y765600D01*
G01Y763183D02*
X395800Y763600D01*
X396217Y763850D01*
X396883Y763933D01*
X397383Y763850D01*
X397967Y763517D01*
X398217Y763017D01*
Y760600D01*
G01X406167D02*
Y765600D01*
X407833D01*
X408500Y765350D01*
X409000Y765017D01*
X409417Y764517D01*
X409750Y763933D01*
X409833Y763100D01*
X409750Y762267D01*
X409417Y761683D01*
X409000Y761183D01*
X408500Y760850D01*
X407833Y760600D01*
X406167D01*
G01X412350Y762850D02*
X415017D01*
X414767Y763433D01*
X414350Y763767D01*
X413767Y763933D01*
X413183Y763850D01*
X412683Y763600D01*
X412350Y763017D01*
X412183Y762517D01*
Y762017D01*
X412350Y761517D01*
X412767Y761017D01*
X413267Y760683D01*
X413850Y760600D01*
X414433Y760767D01*
X415017Y761267D01*
G01X417783Y760600D02*
Y763933D01*
G01Y763100D02*
X418117Y763517D01*
X418617Y763850D01*
X419283Y763933D01*
X419867Y763850D01*
X420367Y763517D01*
X420617Y762933D01*
Y760600D01*
G01X423550Y761183D02*
X423967Y760850D01*
X424550Y760600D01*
X425050D01*
X425550Y760767D01*
X425883Y761017D01*
X426050Y761350D01*
X425967Y761850D01*
X425633Y762100D01*
X424133Y762600D01*
X423800Y763183D01*
X423967Y763600D01*
X424300Y763850D01*
X424800Y763933D01*
X425300Y763850D01*
X425800Y763600D01*
G01X430400Y763933D02*
Y760600D01*
G01Y765267D02*
X430233Y765350D01*
Y765517D01*
X430400Y765600D01*
X430567Y765517D01*
Y765350D01*
X430400Y765267D01*
G01X436000Y765600D02*
Y760600D01*
G01X434833Y763933D02*
X437167D01*
G01X439850Y759100D02*
X440350Y758933D01*
X441017Y759100D01*
X441433Y759433D01*
X441767Y759850D01*
X442267Y761183D01*
X443350Y763933D01*
G01X440683D02*
X442267Y761183D01*
G01X451800Y765600D02*
X453800D01*
G01X452800D02*
Y760600D01*
G01X451800D02*
X453800D01*
G01X456983D02*
Y763933D01*
G01Y763100D02*
X457317Y763517D01*
X457817Y763850D01*
X458483Y763933D01*
X459067Y763850D01*
X459567Y763517D01*
X459817Y762933D01*
Y760600D01*
G01X464000Y765600D02*
Y760600D01*
G01X462833Y763933D02*
X465167D01*
G01X468350Y762850D02*
X471017D01*
X470767Y763433D01*
X470350Y763767D01*
X469767Y763933D01*
X469183Y763850D01*
X468683Y763600D01*
X468350Y763017D01*
X468183Y762517D01*
Y762017D01*
X468350Y761517D01*
X468767Y761017D01*
X469267Y760683D01*
X469850Y760600D01*
X470433Y760767D01*
X471017Y761267D01*
G01X474033Y760600D02*
Y763933D01*
G01Y763267D02*
X474450Y763600D01*
X474867Y763850D01*
X475450Y763933D01*
X475867Y763850D01*
X476367Y763600D01*
G01X482133Y763517D02*
X481550Y763850D01*
X481050Y763933D01*
X480383Y763767D01*
X479883Y763433D01*
X479550Y762850D01*
X479467Y762267D01*
X479550Y761683D01*
X479883Y761183D01*
X480383Y760767D01*
X481050Y760600D01*
X481633Y760767D01*
X482133Y761100D01*
G01X486400Y760600D02*
X485900Y760683D01*
X485400Y761017D01*
X485067Y761600D01*
X484900Y762267D01*
X485067Y762933D01*
X485400Y763517D01*
X485900Y763850D01*
X486400Y763933D01*
X486900Y763850D01*
X487400Y763517D01*
X487733Y762933D01*
X487817Y762267D01*
X487733Y761600D01*
X487400Y761017D01*
X486900Y760683D01*
X486400Y760600D01*
G01X490583D02*
Y763933D01*
G01Y763100D02*
X490917Y763517D01*
X491417Y763850D01*
X492083Y763933D01*
X492667Y763850D01*
X493167Y763517D01*
X493417Y762933D01*
Y760600D01*
G01X496183D02*
Y763933D01*
G01Y763100D02*
X496517Y763517D01*
X497017Y763850D01*
X497683Y763933D01*
X498267Y763850D01*
X498767Y763517D01*
X499017Y762933D01*
Y760600D01*
G01X501950Y762850D02*
X504617D01*
X504367Y763433D01*
X503950Y763767D01*
X503367Y763933D01*
X502783Y763850D01*
X502283Y763600D01*
X501950Y763017D01*
X501783Y762517D01*
Y762017D01*
X501950Y761517D01*
X502367Y761017D01*
X502867Y760683D01*
X503450Y760600D01*
X504033Y760767D01*
X504617Y761267D01*
G01X510133Y763517D02*
X509550Y763850D01*
X509050Y763933D01*
X508383Y763767D01*
X507883Y763433D01*
X507550Y762850D01*
X507467Y762267D01*
X507550Y761683D01*
X507883Y761183D01*
X508383Y760767D01*
X509050Y760600D01*
X509633Y760767D01*
X510133Y761100D01*
G01X514400Y765600D02*
Y760600D01*
G01X513233Y763933D02*
X515567D01*
G01X519583Y758933D02*
X518750Y759767D01*
X518333Y760600D01*
Y763933D01*
X518750Y764767D01*
X519583Y765600D01*
G01X523850Y760600D02*
Y765600D01*
G01X527350D02*
Y760600D01*
G01Y763100D02*
X523850D01*
G01X529367Y760600D02*
Y765600D01*
X531033D01*
X531700Y765350D01*
X532200Y765017D01*
X532617Y764517D01*
X532950Y763933D01*
X533033Y763100D01*
X532950Y762267D01*
X532617Y761683D01*
X532200Y761183D01*
X531700Y760850D01*
X531033Y760600D01*
X529367D01*
G01X535800Y765600D02*
X537800D01*
G01X536800D02*
Y760600D01*
G01X535800D02*
X537800D01*
G01X542817Y758933D02*
X543650Y759767D01*
X544067Y760600D01*
Y763933D01*
X543650Y764767D01*
X542817Y765600D01*
G01X551933D02*
Y760600D01*
X555267D01*
G01X560700D02*
Y763933D01*
G01Y763350D02*
X560367Y763683D01*
X559867Y763850D01*
X559283Y763933D01*
X558700Y763767D01*
X558200Y763433D01*
X557867Y762933D01*
X557700Y762267D01*
X557867Y761600D01*
X558200Y761100D01*
X558700Y760767D01*
X559283Y760600D01*
X559867Y760683D01*
X560367Y760933D01*
X560700Y761267D01*
G01X563050Y759100D02*
X563550Y758933D01*
X564217Y759100D01*
X564633Y759433D01*
X564967Y759850D01*
X565467Y761183D01*
X566550Y763933D01*
G01X563883D02*
X565467Y761183D01*
G01X569150Y762850D02*
X571817D01*
X571567Y763433D01*
X571150Y763767D01*
X570567Y763933D01*
X569983Y763850D01*
X569483Y763600D01*
X569150Y763017D01*
X568983Y762517D01*
Y762017D01*
X569150Y761517D01*
X569567Y761017D01*
X570067Y760683D01*
X570650Y760600D01*
X571233Y760767D01*
X571817Y761267D01*
G01X574833Y760600D02*
Y763933D01*
G01Y763267D02*
X575250Y763600D01*
X575667Y763850D01*
X576250Y763933D01*
X576667Y763850D01*
X577167Y763600D01*
G01X580350Y761183D02*
X580767Y760850D01*
X581350Y760600D01*
X581850D01*
X582350Y760767D01*
X582683Y761017D01*
X582850Y761350D01*
X582767Y761850D01*
X582433Y762100D01*
X580933Y762600D01*
X580600Y763183D01*
X580767Y763600D01*
X581100Y763850D01*
X581600Y763933D01*
X582100Y763850D01*
X582600Y763600D01*
G01X592800Y760600D02*
X592300Y760683D01*
X591800Y761017D01*
X591467Y761600D01*
X591300Y762267D01*
X591467Y762933D01*
X591800Y763517D01*
X592300Y763850D01*
X592800Y763933D01*
X593300Y763850D01*
X593800Y763517D01*
X594133Y762933D01*
X594217Y762267D01*
X594133Y761600D01*
X593800Y761017D01*
X593300Y760683D01*
X592800Y760600D01*
G01X597233D02*
Y763933D01*
G01Y763267D02*
X597650Y763600D01*
X598067Y763850D01*
X598650Y763933D01*
X599067Y763850D01*
X599567Y763600D01*
G01X610267Y763267D02*
X610600Y763517D01*
X610850Y763933D01*
X611017Y764517D01*
X610850Y765017D01*
X610517Y765350D01*
X609933Y765600D01*
X607683D01*
Y760600D01*
X610433D01*
X611017Y760933D01*
X611350Y761433D01*
X611517Y762017D01*
X611350Y762600D01*
X610850Y763100D01*
X610267Y763267D01*
X607683D01*
G01X615200Y760600D02*
X614700Y760683D01*
X614200Y761017D01*
X613867Y761600D01*
X613700Y762267D01*
X613867Y762933D01*
X614200Y763517D01*
X614700Y763850D01*
X615200Y763933D01*
X615700Y763850D01*
X616200Y763517D01*
X616533Y762933D01*
X616617Y762267D01*
X616533Y761600D01*
X616200Y761017D01*
X615700Y760683D01*
X615200Y760600D01*
G01X622300D02*
Y763933D01*
G01Y763350D02*
X621967Y763683D01*
X621467Y763850D01*
X620883Y763933D01*
X620300Y763767D01*
X619800Y763433D01*
X619467Y762933D01*
X619300Y762267D01*
X619467Y761600D01*
X619800Y761100D01*
X620300Y760767D01*
X620883Y760600D01*
X621467Y760683D01*
X621967Y760933D01*
X622300Y761267D01*
G01X625233Y760600D02*
Y763933D01*
G01Y763267D02*
X625650Y763600D01*
X626067Y763850D01*
X626650Y763933D01*
X627067Y763850D01*
X627567Y763600D01*
G01X633500Y765600D02*
Y760600D01*
G01Y761350D02*
X633167Y760933D01*
X632667Y760683D01*
X632083Y760600D01*
X631417Y760767D01*
X630917Y761183D01*
X630583Y761683D01*
X630500Y762267D01*
X630583Y762850D01*
X630917Y763350D01*
X631417Y763767D01*
X632083Y763933D01*
X632667Y763850D01*
X633083Y763683D01*
X633500Y763350D01*
G01X636350Y761183D02*
X636767Y760850D01*
X637350Y760600D01*
X637850D01*
X638350Y760767D01*
X638683Y761017D01*
X638850Y761350D01*
X638767Y761850D01*
X638433Y762100D01*
X636933Y762600D01*
X636600Y763183D01*
X636767Y763600D01*
X637100Y763850D01*
X637600Y763933D01*
X638100Y763850D01*
X638600Y763600D01*
G01X643617Y758933D02*
X644450Y759767D01*
X644867Y760600D01*
Y763933D01*
X644450Y764767D01*
X643617Y765600D01*
G01X71000Y774600D02*
X73000D01*
G01X72000D02*
Y769600D01*
G01X71000D02*
X73000D01*
G01X75933D02*
Y774600D01*
X77933D01*
X78600Y774350D01*
X79100Y773767D01*
X79267Y773100D01*
X79100Y772433D01*
X78683Y771933D01*
X77933Y771683D01*
X75933D01*
G01X85033Y774183D02*
X84533Y774433D01*
X83950Y774600D01*
X83283D01*
X82533Y774350D01*
X81950Y773933D01*
X81533Y773433D01*
X81200Y772600D01*
X81117Y771850D01*
X81283Y771100D01*
X81533Y770600D01*
X82033Y770100D01*
X82617Y769767D01*
X83200Y769600D01*
X83783D01*
X84367Y769767D01*
X84867Y770017D01*
X85283Y770350D01*
G01X87717Y771267D02*
X89883D01*
G01X92817Y771683D02*
X93400Y772267D01*
X93900Y772600D01*
X94567Y772767D01*
X95150Y772600D01*
X95567Y772267D01*
X95900Y771767D01*
X95983Y771183D01*
X95900Y770683D01*
X95567Y770183D01*
X95067Y769767D01*
X94483Y769600D01*
X93817Y769767D01*
X93233Y770267D01*
X92900Y771017D01*
X92817Y771850D01*
X92983Y772933D01*
X93233Y773517D01*
X93650Y774100D01*
X94233Y774517D01*
X94817Y774600D01*
X95400Y774433D01*
X95817Y774017D01*
G01X100000Y774600D02*
X99333Y774433D01*
X98833Y774017D01*
X98500Y773517D01*
X98250Y772850D01*
X98167Y772100D01*
X98250Y771350D01*
X98500Y770683D01*
X98833Y770183D01*
X99333Y769767D01*
X100000Y769600D01*
X100667Y769767D01*
X101167Y770183D01*
X101500Y770683D01*
X101750Y771350D01*
X101833Y772100D01*
X101750Y772850D01*
X101500Y773517D01*
X101167Y774017D01*
X100667Y774433D01*
X100000Y774600D01*
G01X105600Y769600D02*
Y774600D01*
X104600Y773600D01*
G01Y769600D02*
X106600D01*
G01X109617Y773767D02*
X110117Y774267D01*
X110700Y774517D01*
X111367Y774600D01*
X112200Y774433D01*
X112783Y774017D01*
X112950Y773517D01*
X112867Y773017D01*
X112533Y772600D01*
X110867Y771767D01*
X110117Y771183D01*
X109617Y770350D01*
X109450Y769600D01*
X112950D01*
G01X122400D02*
X121733Y769683D01*
X121150Y770017D01*
X120650Y770517D01*
X120317Y771100D01*
X120150Y771767D01*
Y772433D01*
X120317Y773100D01*
X120650Y773683D01*
X121150Y774183D01*
X121733Y774517D01*
X122400Y774600D01*
X123067Y774517D01*
X123650Y774183D01*
X124150Y773683D01*
X124483Y773100D01*
X124650Y772433D01*
Y771767D01*
X124483Y771100D01*
X124150Y770517D01*
X123650Y770017D01*
X123067Y769683D01*
X122400Y769600D01*
G01X123067Y770933D02*
X124067Y769600D01*
G01X126583Y772933D02*
Y770600D01*
X126917Y770017D01*
X127417Y769683D01*
X128000Y769600D01*
X128583Y769683D01*
X129083Y770017D01*
X129417Y770600D01*
G01Y769600D02*
Y772933D01*
G01X135100Y769600D02*
Y772933D01*
G01Y772350D02*
X134767Y772683D01*
X134267Y772850D01*
X133683Y772933D01*
X133100Y772767D01*
X132600Y772433D01*
X132267Y771933D01*
X132100Y771267D01*
X132267Y770600D01*
X132600Y770100D01*
X133100Y769767D01*
X133683Y769600D01*
X134267Y769683D01*
X134767Y769933D01*
X135100Y770267D01*
G01X139200Y769600D02*
Y774600D01*
G01X144800Y772933D02*
Y769600D01*
G01Y774267D02*
X144633Y774350D01*
Y774517D01*
X144800Y774600D01*
X144967Y774517D01*
Y774350D01*
X144800Y774267D01*
G01X149900Y769600D02*
Y773850D01*
X150067Y774267D01*
X150400Y774517D01*
X150900Y774600D01*
X151400Y774433D01*
X151650Y774017D01*
G01X150650Y772600D02*
X148983D01*
G01X156000Y772933D02*
Y769600D01*
G01Y774267D02*
X155833Y774350D01*
Y774517D01*
X156000Y774600D01*
X156167Y774517D01*
Y774350D01*
X156000Y774267D01*
G01X162933Y772517D02*
X162350Y772850D01*
X161850Y772933D01*
X161183Y772767D01*
X160683Y772433D01*
X160350Y771850D01*
X160267Y771267D01*
X160350Y770683D01*
X160683Y770183D01*
X161183Y769767D01*
X161850Y769600D01*
X162433Y769767D01*
X162933Y770100D01*
G01X168700Y769600D02*
Y772933D01*
G01Y772350D02*
X168367Y772683D01*
X167867Y772850D01*
X167283Y772933D01*
X166700Y772767D01*
X166200Y772433D01*
X165867Y771933D01*
X165700Y771267D01*
X165867Y770600D01*
X166200Y770100D01*
X166700Y769767D01*
X167283Y769600D01*
X167867Y769683D01*
X168367Y769933D01*
X168700Y770267D01*
G01X172800Y774600D02*
Y769600D01*
G01X171633Y772933D02*
X173967D01*
G01X178400D02*
Y769600D01*
G01Y774267D02*
X178233Y774350D01*
Y774517D01*
X178400Y774600D01*
X178567Y774517D01*
Y774350D01*
X178400Y774267D01*
G01X184000Y769600D02*
X183500Y769683D01*
X183000Y770017D01*
X182667Y770600D01*
X182500Y771267D01*
X182667Y771933D01*
X183000Y772517D01*
X183500Y772850D01*
X184000Y772933D01*
X184500Y772850D01*
X185000Y772517D01*
X185333Y771933D01*
X185417Y771267D01*
X185333Y770600D01*
X185000Y770017D01*
X184500Y769683D01*
X184000Y769600D01*
G01X188183D02*
Y772933D01*
G01Y772100D02*
X188517Y772517D01*
X189017Y772850D01*
X189683Y772933D01*
X190267Y772850D01*
X190767Y772517D01*
X191017Y771933D01*
Y769600D01*
G01X202300D02*
Y772933D01*
G01Y772350D02*
X201967Y772683D01*
X201467Y772850D01*
X200883Y772933D01*
X200300Y772767D01*
X199800Y772433D01*
X199467Y771933D01*
X199300Y771267D01*
X199467Y770600D01*
X199800Y770100D01*
X200300Y769767D01*
X200883Y769600D01*
X201467Y769683D01*
X201967Y769933D01*
X202300Y770267D01*
G01X204983Y769600D02*
Y772933D01*
G01Y772100D02*
X205317Y772517D01*
X205817Y772850D01*
X206483Y772933D01*
X207067Y772850D01*
X207567Y772517D01*
X207817Y771933D01*
Y769600D01*
G01X213500Y774600D02*
Y769600D01*
G01Y770350D02*
X213167Y769933D01*
X212667Y769683D01*
X212083Y769600D01*
X211417Y769767D01*
X210917Y770183D01*
X210583Y770683D01*
X210500Y771267D01*
X210583Y771850D01*
X210917Y772350D01*
X211417Y772767D01*
X212083Y772933D01*
X212667Y772850D01*
X213083Y772683D01*
X213500Y772350D01*
G01X221533Y769600D02*
Y774600D01*
X223533D01*
X224200Y774350D01*
X224700Y773767D01*
X224867Y773100D01*
X224700Y772433D01*
X224283Y771933D01*
X223533Y771683D01*
X221533D01*
G01X227550Y771850D02*
X230217D01*
X229967Y772433D01*
X229550Y772767D01*
X228967Y772933D01*
X228383Y772850D01*
X227883Y772600D01*
X227550Y772017D01*
X227383Y771517D01*
Y771017D01*
X227550Y770517D01*
X227967Y770017D01*
X228467Y769683D01*
X229050Y769600D01*
X229633Y769767D01*
X230217Y770267D01*
G01X233233Y769600D02*
Y772933D01*
G01Y772267D02*
X233650Y772600D01*
X234067Y772850D01*
X234650Y772933D01*
X235067Y772850D01*
X235567Y772600D01*
G01X239500Y769600D02*
Y773850D01*
X239667Y774267D01*
X240000Y774517D01*
X240500Y774600D01*
X241000Y774433D01*
X241250Y774017D01*
G01X240250Y772600D02*
X238583D01*
G01X245600Y769600D02*
X245100Y769683D01*
X244600Y770017D01*
X244267Y770600D01*
X244100Y771267D01*
X244267Y771933D01*
X244600Y772517D01*
X245100Y772850D01*
X245600Y772933D01*
X246100Y772850D01*
X246600Y772517D01*
X246933Y771933D01*
X247017Y771267D01*
X246933Y770600D01*
X246600Y770017D01*
X246100Y769683D01*
X245600Y769600D01*
G01X250033D02*
Y772933D01*
G01Y772267D02*
X250450Y772600D01*
X250867Y772850D01*
X251450Y772933D01*
X251867Y772850D01*
X252367Y772600D01*
G01X254300Y769600D02*
Y772933D01*
G01Y772017D02*
X254550Y772433D01*
X254967Y772767D01*
X255550Y772933D01*
X256133Y772767D01*
X256550Y772433D01*
X256800Y772017D01*
Y769600D01*
G01Y772017D02*
X257050Y772433D01*
X257467Y772767D01*
X258050Y772933D01*
X258633Y772767D01*
X259050Y772433D01*
X259300Y771933D01*
Y769600D01*
G01X263900D02*
Y772933D01*
G01Y772350D02*
X263567Y772683D01*
X263067Y772850D01*
X262483Y772933D01*
X261900Y772767D01*
X261400Y772433D01*
X261067Y771933D01*
X260900Y771267D01*
X261067Y770600D01*
X261400Y770100D01*
X261900Y769767D01*
X262483Y769600D01*
X263067Y769683D01*
X263567Y769933D01*
X263900Y770267D01*
G01X266583Y769600D02*
Y772933D01*
G01Y772100D02*
X266917Y772517D01*
X267417Y772850D01*
X268083Y772933D01*
X268667Y772850D01*
X269167Y772517D01*
X269417Y771933D01*
Y769600D01*
G01X274933Y772517D02*
X274350Y772850D01*
X273850Y772933D01*
X273183Y772767D01*
X272683Y772433D01*
X272350Y771850D01*
X272267Y771267D01*
X272350Y770683D01*
X272683Y770183D01*
X273183Y769767D01*
X273850Y769600D01*
X274433Y769767D01*
X274933Y770100D01*
G01X277950Y771850D02*
X280617D01*
X280367Y772433D01*
X279950Y772767D01*
X279367Y772933D01*
X278783Y772850D01*
X278283Y772600D01*
X277950Y772017D01*
X277783Y771517D01*
Y771017D01*
X277950Y770517D01*
X278367Y770017D01*
X278867Y769683D01*
X279450Y769600D01*
X280033Y769767D01*
X280617Y770267D01*
G01X288650D02*
X289317Y769850D01*
X290067Y769600D01*
X290733D01*
X291400Y769850D01*
X291900Y770267D01*
X292150Y770850D01*
X291983Y771433D01*
X291567Y771933D01*
X290817Y772267D01*
X289817Y772433D01*
X289233Y772767D01*
X288983Y773350D01*
X289150Y773933D01*
X289567Y774350D01*
X290150Y774600D01*
X290733D01*
X291317Y774433D01*
X291817Y774017D01*
G01X294500Y767933D02*
Y772933D01*
G01Y772183D02*
X294917Y772600D01*
X295333Y772850D01*
X296000Y772933D01*
X296583Y772850D01*
X297167Y772433D01*
X297417Y771850D01*
X297500Y771267D01*
X297417Y770683D01*
X297167Y770100D01*
X296667Y769767D01*
X296000Y769600D01*
X295417Y769683D01*
X294833Y769933D01*
X294500Y770267D01*
G01X300350Y771850D02*
X303017D01*
X302767Y772433D01*
X302350Y772767D01*
X301767Y772933D01*
X301183Y772850D01*
X300683Y772600D01*
X300350Y772017D01*
X300183Y771517D01*
Y771017D01*
X300350Y770517D01*
X300767Y770017D01*
X301267Y769683D01*
X301850Y769600D01*
X302433Y769767D01*
X303017Y770267D01*
G01X308533Y772517D02*
X307950Y772850D01*
X307450Y772933D01*
X306783Y772767D01*
X306283Y772433D01*
X305950Y771850D01*
X305867Y771267D01*
X305950Y770683D01*
X306283Y770183D01*
X306783Y769767D01*
X307450Y769600D01*
X308033Y769767D01*
X308533Y770100D01*
G01X312800Y772933D02*
Y769600D01*
G01Y774267D02*
X312633Y774350D01*
Y774517D01*
X312800Y774600D01*
X312967Y774517D01*
Y774350D01*
X312800Y774267D01*
G01X317900Y769600D02*
Y773850D01*
X318067Y774267D01*
X318400Y774517D01*
X318900Y774600D01*
X319400Y774433D01*
X319650Y774017D01*
G01X318650Y772600D02*
X316983D01*
G01X324000Y772933D02*
Y769600D01*
G01Y774267D02*
X323833Y774350D01*
Y774517D01*
X324000Y774600D01*
X324167Y774517D01*
Y774350D01*
X324000Y774267D01*
G01X330933Y772517D02*
X330350Y772850D01*
X329850Y772933D01*
X329183Y772767D01*
X328683Y772433D01*
X328350Y771850D01*
X328267Y771267D01*
X328350Y770683D01*
X328683Y770183D01*
X329183Y769767D01*
X329850Y769600D01*
X330433Y769767D01*
X330933Y770100D01*
G01X336700Y769600D02*
Y772933D01*
G01Y772350D02*
X336367Y772683D01*
X335867Y772850D01*
X335283Y772933D01*
X334700Y772767D01*
X334200Y772433D01*
X333867Y771933D01*
X333700Y771267D01*
X333867Y770600D01*
X334200Y770100D01*
X334700Y769767D01*
X335283Y769600D01*
X335867Y769683D01*
X336367Y769933D01*
X336700Y770267D01*
G01X340800Y774600D02*
Y769600D01*
G01X339633Y772933D02*
X341967D01*
G01X346400D02*
Y769600D01*
G01Y774267D02*
X346233Y774350D01*
Y774517D01*
X346400Y774600D01*
X346567Y774517D01*
Y774350D01*
X346400Y774267D01*
G01X352000Y769600D02*
X351500Y769683D01*
X351000Y770017D01*
X350667Y770600D01*
X350500Y771267D01*
X350667Y771933D01*
X351000Y772517D01*
X351500Y772850D01*
X352000Y772933D01*
X352500Y772850D01*
X353000Y772517D01*
X353333Y771933D01*
X353417Y771267D01*
X353333Y770600D01*
X353000Y770017D01*
X352500Y769683D01*
X352000Y769600D01*
G01X356183D02*
Y772933D01*
G01Y772100D02*
X356517Y772517D01*
X357017Y772850D01*
X357683Y772933D01*
X358267Y772850D01*
X358767Y772517D01*
X359017Y771933D01*
Y769600D01*
G01X368300D02*
Y773850D01*
X368467Y774267D01*
X368800Y774517D01*
X369300Y774600D01*
X369800Y774433D01*
X370050Y774017D01*
G01X369050Y772600D02*
X367383D01*
G01X374400Y769600D02*
X373900Y769683D01*
X373400Y770017D01*
X373067Y770600D01*
X372900Y771267D01*
X373067Y771933D01*
X373400Y772517D01*
X373900Y772850D01*
X374400Y772933D01*
X374900Y772850D01*
X375400Y772517D01*
X375733Y771933D01*
X375817Y771267D01*
X375733Y770600D01*
X375400Y770017D01*
X374900Y769683D01*
X374400Y769600D01*
G01X378833D02*
Y772933D01*
G01Y772267D02*
X379250Y772600D01*
X379667Y772850D01*
X380250Y772933D01*
X380667Y772850D01*
X381167Y772600D01*
G01X389533Y769600D02*
Y774600D01*
X391617D01*
X392283Y774350D01*
X392700Y774017D01*
X392867Y773350D01*
X392700Y772683D01*
X392200Y772267D01*
X391617Y772017D01*
X389533D01*
G01X391617D02*
X392867Y769600D01*
G01X396800Y772933D02*
Y769600D01*
G01Y774267D02*
X396633Y774350D01*
Y774517D01*
X396800Y774600D01*
X396967Y774517D01*
Y774350D01*
X396800Y774267D01*
G01X401233Y768350D02*
X401817Y768017D01*
X402483Y767933D01*
X403067Y768017D01*
X403567Y768433D01*
X403900Y769017D01*
Y772933D01*
G01Y772267D02*
X403567Y772600D01*
X403067Y772850D01*
X402483Y772933D01*
X401817Y772767D01*
X401400Y772433D01*
X401067Y771850D01*
X400900Y771267D01*
X400983Y770767D01*
X401317Y770183D01*
X401817Y769767D01*
X402483Y769600D01*
X402983Y769683D01*
X403567Y770017D01*
X403900Y770350D01*
G01X408000Y772933D02*
Y769600D01*
G01Y774267D02*
X407833Y774350D01*
Y774517D01*
X408000Y774600D01*
X408167Y774517D01*
Y774350D01*
X408000Y774267D01*
G01X415100Y774600D02*
Y769600D01*
G01Y770350D02*
X414767Y769933D01*
X414267Y769683D01*
X413683Y769600D01*
X413017Y769767D01*
X412517Y770183D01*
X412183Y770683D01*
X412100Y771267D01*
X412183Y771850D01*
X412517Y772350D01*
X413017Y772767D01*
X413683Y772933D01*
X414267Y772850D01*
X414683Y772683D01*
X415100Y772350D01*
G01X423133Y769600D02*
Y774600D01*
X425133D01*
X425800Y774350D01*
X426300Y773767D01*
X426467Y773100D01*
X426300Y772433D01*
X425883Y771933D01*
X425133Y771683D01*
X423133D01*
G01X429233Y769600D02*
Y772933D01*
G01Y772267D02*
X429650Y772600D01*
X430067Y772850D01*
X430650Y772933D01*
X431067Y772850D01*
X431567Y772600D01*
G01X436000Y772933D02*
Y769600D01*
G01Y774267D02*
X435833Y774350D01*
Y774517D01*
X436000Y774600D01*
X436167Y774517D01*
Y774350D01*
X436000Y774267D01*
G01X440183Y769600D02*
Y772933D01*
G01Y772100D02*
X440517Y772517D01*
X441017Y772850D01*
X441683Y772933D01*
X442267Y772850D01*
X442767Y772517D01*
X443017Y771933D01*
Y769600D01*
G01X447200Y774600D02*
Y769600D01*
G01X446033Y772933D02*
X448367D01*
G01X451550Y771850D02*
X454217D01*
X453967Y772433D01*
X453550Y772767D01*
X452967Y772933D01*
X452383Y772850D01*
X451883Y772600D01*
X451550Y772017D01*
X451383Y771517D01*
Y771017D01*
X451550Y770517D01*
X451967Y770017D01*
X452467Y769683D01*
X453050Y769600D01*
X453633Y769767D01*
X454217Y770267D01*
G01X459900Y774600D02*
Y769600D01*
G01Y770350D02*
X459567Y769933D01*
X459067Y769683D01*
X458483Y769600D01*
X457817Y769767D01*
X457317Y770183D01*
X456983Y770683D01*
X456900Y771267D01*
X456983Y771850D01*
X457317Y772350D01*
X457817Y772767D01*
X458483Y772933D01*
X459067Y772850D01*
X459483Y772683D01*
X459900Y772350D01*
G01X470267Y772267D02*
X470600Y772517D01*
X470850Y772933D01*
X471017Y773517D01*
X470850Y774017D01*
X470517Y774350D01*
X469933Y774600D01*
X467683D01*
Y769600D01*
X470433D01*
X471017Y769933D01*
X471350Y770433D01*
X471517Y771017D01*
X471350Y771600D01*
X470850Y772100D01*
X470267Y772267D01*
X467683D01*
G01X475200Y769600D02*
X474700Y769683D01*
X474200Y770017D01*
X473867Y770600D01*
X473700Y771267D01*
X473867Y771933D01*
X474200Y772517D01*
X474700Y772850D01*
X475200Y772933D01*
X475700Y772850D01*
X476200Y772517D01*
X476533Y771933D01*
X476617Y771267D01*
X476533Y770600D01*
X476200Y770017D01*
X475700Y769683D01*
X475200Y769600D01*
G01X482300D02*
Y772933D01*
G01Y772350D02*
X481967Y772683D01*
X481467Y772850D01*
X480883Y772933D01*
X480300Y772767D01*
X479800Y772433D01*
X479467Y771933D01*
X479300Y771267D01*
X479467Y770600D01*
X479800Y770100D01*
X480300Y769767D01*
X480883Y769600D01*
X481467Y769683D01*
X481967Y769933D01*
X482300Y770267D01*
G01X485233Y769600D02*
Y772933D01*
G01Y772267D02*
X485650Y772600D01*
X486067Y772850D01*
X486650Y772933D01*
X487067Y772850D01*
X487567Y772600D01*
G01X493500Y774600D02*
Y769600D01*
G01Y770350D02*
X493167Y769933D01*
X492667Y769683D01*
X492083Y769600D01*
X491417Y769767D01*
X490917Y770183D01*
X490583Y770683D01*
X490500Y771267D01*
X490583Y771850D01*
X490917Y772350D01*
X491417Y772767D01*
X492083Y772933D01*
X492667Y772850D01*
X493083Y772683D01*
X493500Y772350D01*
G01X496350Y770183D02*
X496767Y769850D01*
X497350Y769600D01*
X497850D01*
X498350Y769767D01*
X498683Y770017D01*
X498850Y770350D01*
X498767Y770850D01*
X498433Y771100D01*
X496933Y771600D01*
X496600Y772183D01*
X496767Y772600D01*
X497100Y772850D01*
X497600Y772933D01*
X498100Y772850D01*
X498600Y772600D01*
G01X67000Y779433D02*
X66833Y779517D01*
Y779683D01*
X67000Y779767D01*
X67167Y779683D01*
Y779517D01*
X67000Y779433D01*
G01Y786333D02*
X66833Y786417D01*
Y786583D01*
X67000Y786667D01*
X67167Y786583D01*
Y786417D01*
X67000Y786333D01*
G01X71000Y783600D02*
X73000D01*
G01X72000D02*
Y778600D01*
G01X71000D02*
X73000D01*
G01X75933D02*
Y783600D01*
X77933D01*
X78600Y783350D01*
X79100Y782767D01*
X79267Y782100D01*
X79100Y781433D01*
X78683Y780933D01*
X77933Y780683D01*
X75933D01*
G01X85033Y783183D02*
X84533Y783433D01*
X83950Y783600D01*
X83283D01*
X82533Y783350D01*
X81950Y782933D01*
X81533Y782433D01*
X81200Y781600D01*
X81117Y780850D01*
X81283Y780100D01*
X81533Y779600D01*
X82033Y779100D01*
X82617Y778767D01*
X83200Y778600D01*
X83783D01*
X84367Y778767D01*
X84867Y779017D01*
X85283Y779350D01*
G01X87717Y780267D02*
X89883D01*
G01X92817Y780683D02*
X93400Y781267D01*
X93900Y781600D01*
X94567Y781767D01*
X95150Y781600D01*
X95567Y781267D01*
X95900Y780767D01*
X95983Y780183D01*
X95900Y779683D01*
X95567Y779183D01*
X95067Y778767D01*
X94483Y778600D01*
X93817Y778767D01*
X93233Y779267D01*
X92900Y780017D01*
X92817Y780850D01*
X92983Y781933D01*
X93233Y782517D01*
X93650Y783100D01*
X94233Y783517D01*
X94817Y783600D01*
X95400Y783433D01*
X95817Y783017D01*
G01X100000Y783600D02*
X99333Y783433D01*
X98833Y783017D01*
X98500Y782517D01*
X98250Y781850D01*
X98167Y781100D01*
X98250Y780350D01*
X98500Y779683D01*
X98833Y779183D01*
X99333Y778767D01*
X100000Y778600D01*
X100667Y778767D01*
X101167Y779183D01*
X101500Y779683D01*
X101750Y780350D01*
X101833Y781100D01*
X101750Y781850D01*
X101500Y782517D01*
X101167Y783017D01*
X100667Y783433D01*
X100000Y783600D01*
G01X105600Y778600D02*
Y783600D01*
X104600Y782600D01*
G01Y778600D02*
X106600D01*
G01X111200D02*
Y783600D01*
X110200Y782600D01*
G01Y778600D02*
X112200D01*
G01X122900Y781100D02*
X124567D01*
Y779600D01*
X124067Y779100D01*
X123483Y778767D01*
X122650Y778600D01*
X121817Y778767D01*
X121233Y779100D01*
X120733Y779600D01*
X120400Y780183D01*
X120233Y780850D01*
Y781433D01*
X120400Y781933D01*
X120733Y782517D01*
X121233Y783017D01*
X121733Y783350D01*
X122400Y783600D01*
X122983D01*
X123650Y783433D01*
X124150Y783100D01*
G01X126750Y780850D02*
X129417D01*
X129167Y781433D01*
X128750Y781767D01*
X128167Y781933D01*
X127583Y781850D01*
X127083Y781600D01*
X126750Y781017D01*
X126583Y780517D01*
Y780017D01*
X126750Y779517D01*
X127167Y779017D01*
X127667Y778683D01*
X128250Y778600D01*
X128833Y778767D01*
X129417Y779267D01*
G01X132183Y778600D02*
Y781933D01*
G01Y781100D02*
X132517Y781517D01*
X133017Y781850D01*
X133683Y781933D01*
X134267Y781850D01*
X134767Y781517D01*
X135017Y780933D01*
Y778600D01*
G01X137950Y780850D02*
X140617D01*
X140367Y781433D01*
X139950Y781767D01*
X139367Y781933D01*
X138783Y781850D01*
X138283Y781600D01*
X137950Y781017D01*
X137783Y780517D01*
Y780017D01*
X137950Y779517D01*
X138367Y779017D01*
X138867Y778683D01*
X139450Y778600D01*
X140033Y778767D01*
X140617Y779267D01*
G01X143633Y778600D02*
Y781933D01*
G01Y781267D02*
X144050Y781600D01*
X144467Y781850D01*
X145050Y781933D01*
X145467Y781850D01*
X145967Y781600D01*
G01X150400Y781933D02*
Y778600D01*
G01Y783267D02*
X150233Y783350D01*
Y783517D01*
X150400Y783600D01*
X150567Y783517D01*
Y783350D01*
X150400Y783267D01*
G01X157333Y781517D02*
X156750Y781850D01*
X156250Y781933D01*
X155583Y781767D01*
X155083Y781433D01*
X154750Y780850D01*
X154667Y780267D01*
X154750Y779683D01*
X155083Y779183D01*
X155583Y778767D01*
X156250Y778600D01*
X156833Y778767D01*
X157333Y779100D01*
G01X165533Y778600D02*
Y783600D01*
X167533D01*
X168200Y783350D01*
X168700Y782767D01*
X168867Y782100D01*
X168700Y781433D01*
X168283Y780933D01*
X167533Y780683D01*
X165533D01*
G01X171550Y780850D02*
X174217D01*
X173967Y781433D01*
X173550Y781767D01*
X172967Y781933D01*
X172383Y781850D01*
X171883Y781600D01*
X171550Y781017D01*
X171383Y780517D01*
Y780017D01*
X171550Y779517D01*
X171967Y779017D01*
X172467Y778683D01*
X173050Y778600D01*
X173633Y778767D01*
X174217Y779267D01*
G01X177233Y778600D02*
Y781933D01*
G01Y781267D02*
X177650Y781600D01*
X178067Y781850D01*
X178650Y781933D01*
X179067Y781850D01*
X179567Y781600D01*
G01X183500Y778600D02*
Y782850D01*
X183667Y783267D01*
X184000Y783517D01*
X184500Y783600D01*
X185000Y783433D01*
X185250Y783017D01*
G01X184250Y781600D02*
X182583D01*
G01X189600Y778600D02*
X189100Y778683D01*
X188600Y779017D01*
X188267Y779600D01*
X188100Y780267D01*
X188267Y780933D01*
X188600Y781517D01*
X189100Y781850D01*
X189600Y781933D01*
X190100Y781850D01*
X190600Y781517D01*
X190933Y780933D01*
X191017Y780267D01*
X190933Y779600D01*
X190600Y779017D01*
X190100Y778683D01*
X189600Y778600D01*
G01X194033D02*
Y781933D01*
G01Y781267D02*
X194450Y781600D01*
X194867Y781850D01*
X195450Y781933D01*
X195867Y781850D01*
X196367Y781600D01*
G01X198300Y778600D02*
Y781933D01*
G01Y781017D02*
X198550Y781433D01*
X198967Y781767D01*
X199550Y781933D01*
X200133Y781767D01*
X200550Y781433D01*
X200800Y781017D01*
Y778600D01*
G01Y781017D02*
X201050Y781433D01*
X201467Y781767D01*
X202050Y781933D01*
X202633Y781767D01*
X203050Y781433D01*
X203300Y780933D01*
Y778600D01*
G01X207900D02*
Y781933D01*
G01Y781350D02*
X207567Y781683D01*
X207067Y781850D01*
X206483Y781933D01*
X205900Y781767D01*
X205400Y781433D01*
X205067Y780933D01*
X204900Y780267D01*
X205067Y779600D01*
X205400Y779100D01*
X205900Y778767D01*
X206483Y778600D01*
X207067Y778683D01*
X207567Y778933D01*
X207900Y779267D01*
G01X210583Y778600D02*
Y781933D01*
G01Y781100D02*
X210917Y781517D01*
X211417Y781850D01*
X212083Y781933D01*
X212667Y781850D01*
X213167Y781517D01*
X213417Y780933D01*
Y778600D01*
G01X218933Y781517D02*
X218350Y781850D01*
X217850Y781933D01*
X217183Y781767D01*
X216683Y781433D01*
X216350Y780850D01*
X216267Y780267D01*
X216350Y779683D01*
X216683Y779183D01*
X217183Y778767D01*
X217850Y778600D01*
X218433Y778767D01*
X218933Y779100D01*
G01X221950Y780850D02*
X224617D01*
X224367Y781433D01*
X223950Y781767D01*
X223367Y781933D01*
X222783Y781850D01*
X222283Y781600D01*
X221950Y781017D01*
X221783Y780517D01*
Y780017D01*
X221950Y779517D01*
X222367Y779017D01*
X222867Y778683D01*
X223450Y778600D01*
X224033Y778767D01*
X224617Y779267D01*
G01X232650D02*
X233317Y778850D01*
X234067Y778600D01*
X234733D01*
X235400Y778850D01*
X235900Y779267D01*
X236150Y779850D01*
X235983Y780433D01*
X235567Y780933D01*
X234817Y781267D01*
X233817Y781433D01*
X233233Y781767D01*
X232983Y782350D01*
X233150Y782933D01*
X233567Y783350D01*
X234150Y783600D01*
X234733D01*
X235317Y783433D01*
X235817Y783017D01*
G01X238500Y776933D02*
Y781933D01*
G01Y781183D02*
X238917Y781600D01*
X239333Y781850D01*
X240000Y781933D01*
X240583Y781850D01*
X241167Y781433D01*
X241417Y780850D01*
X241500Y780267D01*
X241417Y779683D01*
X241167Y779100D01*
X240667Y778767D01*
X240000Y778600D01*
X239417Y778683D01*
X238833Y778933D01*
X238500Y779267D01*
G01X244350Y780850D02*
X247017D01*
X246767Y781433D01*
X246350Y781767D01*
X245767Y781933D01*
X245183Y781850D01*
X244683Y781600D01*
X244350Y781017D01*
X244183Y780517D01*
Y780017D01*
X244350Y779517D01*
X244767Y779017D01*
X245267Y778683D01*
X245850Y778600D01*
X246433Y778767D01*
X247017Y779267D01*
G01X252533Y781517D02*
X251950Y781850D01*
X251450Y781933D01*
X250783Y781767D01*
X250283Y781433D01*
X249950Y780850D01*
X249867Y780267D01*
X249950Y779683D01*
X250283Y779183D01*
X250783Y778767D01*
X251450Y778600D01*
X252033Y778767D01*
X252533Y779100D01*
G01X256800Y781933D02*
Y778600D01*
G01Y783267D02*
X256633Y783350D01*
Y783517D01*
X256800Y783600D01*
X256967Y783517D01*
Y783350D01*
X256800Y783267D01*
G01X261900Y778600D02*
Y782850D01*
X262067Y783267D01*
X262400Y783517D01*
X262900Y783600D01*
X263400Y783433D01*
X263650Y783017D01*
G01X262650Y781600D02*
X260983D01*
G01X268000Y781933D02*
Y778600D01*
G01Y783267D02*
X267833Y783350D01*
Y783517D01*
X268000Y783600D01*
X268167Y783517D01*
Y783350D01*
X268000Y783267D01*
G01X274933Y781517D02*
X274350Y781850D01*
X273850Y781933D01*
X273183Y781767D01*
X272683Y781433D01*
X272350Y780850D01*
X272267Y780267D01*
X272350Y779683D01*
X272683Y779183D01*
X273183Y778767D01*
X273850Y778600D01*
X274433Y778767D01*
X274933Y779100D01*
G01X280700Y778600D02*
Y781933D01*
G01Y781350D02*
X280367Y781683D01*
X279867Y781850D01*
X279283Y781933D01*
X278700Y781767D01*
X278200Y781433D01*
X277867Y780933D01*
X277700Y780267D01*
X277867Y779600D01*
X278200Y779100D01*
X278700Y778767D01*
X279283Y778600D01*
X279867Y778683D01*
X280367Y778933D01*
X280700Y779267D01*
G01X284800Y783600D02*
Y778600D01*
G01X283633Y781933D02*
X285967D01*
G01X290400D02*
Y778600D01*
G01Y783267D02*
X290233Y783350D01*
Y783517D01*
X290400Y783600D01*
X290567Y783517D01*
Y783350D01*
X290400Y783267D01*
G01X296000Y778600D02*
X295500Y778683D01*
X295000Y779017D01*
X294667Y779600D01*
X294500Y780267D01*
X294667Y780933D01*
X295000Y781517D01*
X295500Y781850D01*
X296000Y781933D01*
X296500Y781850D01*
X297000Y781517D01*
X297333Y780933D01*
X297417Y780267D01*
X297333Y779600D01*
X297000Y779017D01*
X296500Y778683D01*
X296000Y778600D01*
G01X300183D02*
Y781933D01*
G01Y781100D02*
X300517Y781517D01*
X301017Y781850D01*
X301683Y781933D01*
X302267Y781850D01*
X302767Y781517D01*
X303017Y780933D01*
Y778600D01*
G01X312300D02*
Y782850D01*
X312467Y783267D01*
X312800Y783517D01*
X313300Y783600D01*
X313800Y783433D01*
X314050Y783017D01*
G01X313050Y781600D02*
X311383D01*
G01X318400Y778600D02*
X317900Y778683D01*
X317400Y779017D01*
X317067Y779600D01*
X316900Y780267D01*
X317067Y780933D01*
X317400Y781517D01*
X317900Y781850D01*
X318400Y781933D01*
X318900Y781850D01*
X319400Y781517D01*
X319733Y780933D01*
X319817Y780267D01*
X319733Y779600D01*
X319400Y779017D01*
X318900Y778683D01*
X318400Y778600D01*
G01X322833D02*
Y781933D01*
G01Y781267D02*
X323250Y781600D01*
X323667Y781850D01*
X324250Y781933D01*
X324667Y781850D01*
X325167Y781600D01*
G01X333533Y778600D02*
Y783600D01*
X335533D01*
X336200Y783350D01*
X336700Y782767D01*
X336867Y782100D01*
X336700Y781433D01*
X336283Y780933D01*
X335533Y780683D01*
X333533D01*
G01X339633Y778600D02*
Y781933D01*
G01Y781267D02*
X340050Y781600D01*
X340467Y781850D01*
X341050Y781933D01*
X341467Y781850D01*
X341967Y781600D01*
G01X346400Y781933D02*
Y778600D01*
G01Y783267D02*
X346233Y783350D01*
Y783517D01*
X346400Y783600D01*
X346567Y783517D01*
Y783350D01*
X346400Y783267D01*
G01X350583Y778600D02*
Y781933D01*
G01Y781100D02*
X350917Y781517D01*
X351417Y781850D01*
X352083Y781933D01*
X352667Y781850D01*
X353167Y781517D01*
X353417Y780933D01*
Y778600D01*
G01X357600Y783600D02*
Y778600D01*
G01X356433Y781933D02*
X358767D01*
G01X361950Y780850D02*
X364617D01*
X364367Y781433D01*
X363950Y781767D01*
X363367Y781933D01*
X362783Y781850D01*
X362283Y781600D01*
X361950Y781017D01*
X361783Y780517D01*
Y780017D01*
X361950Y779517D01*
X362367Y779017D01*
X362867Y778683D01*
X363450Y778600D01*
X364033Y778767D01*
X364617Y779267D01*
G01X370300Y783600D02*
Y778600D01*
G01Y779350D02*
X369967Y778933D01*
X369467Y778683D01*
X368883Y778600D01*
X368217Y778767D01*
X367717Y779183D01*
X367383Y779683D01*
X367300Y780267D01*
X367383Y780850D01*
X367717Y781350D01*
X368217Y781767D01*
X368883Y781933D01*
X369467Y781850D01*
X369883Y781683D01*
X370300Y781350D01*
G01X380667Y781267D02*
X381000Y781517D01*
X381250Y781933D01*
X381417Y782517D01*
X381250Y783017D01*
X380917Y783350D01*
X380333Y783600D01*
X378083D01*
Y778600D01*
X380833D01*
X381417Y778933D01*
X381750Y779433D01*
X381917Y780017D01*
X381750Y780600D01*
X381250Y781100D01*
X380667Y781267D01*
X378083D01*
G01X385600Y778600D02*
X385100Y778683D01*
X384600Y779017D01*
X384267Y779600D01*
X384100Y780267D01*
X384267Y780933D01*
X384600Y781517D01*
X385100Y781850D01*
X385600Y781933D01*
X386100Y781850D01*
X386600Y781517D01*
X386933Y780933D01*
X387017Y780267D01*
X386933Y779600D01*
X386600Y779017D01*
X386100Y778683D01*
X385600Y778600D01*
G01X392700D02*
Y781933D01*
G01Y781350D02*
X392367Y781683D01*
X391867Y781850D01*
X391283Y781933D01*
X390700Y781767D01*
X390200Y781433D01*
X389867Y780933D01*
X389700Y780267D01*
X389867Y779600D01*
X390200Y779100D01*
X390700Y778767D01*
X391283Y778600D01*
X391867Y778683D01*
X392367Y778933D01*
X392700Y779267D01*
G01X395633Y778600D02*
Y781933D01*
G01Y781267D02*
X396050Y781600D01*
X396467Y781850D01*
X397050Y781933D01*
X397467Y781850D01*
X397967Y781600D01*
G01X403900Y783600D02*
Y778600D01*
G01Y779350D02*
X403567Y778933D01*
X403067Y778683D01*
X402483Y778600D01*
X401817Y778767D01*
X401317Y779183D01*
X400983Y779683D01*
X400900Y780267D01*
X400983Y780850D01*
X401317Y781350D01*
X401817Y781767D01*
X402483Y781933D01*
X403067Y781850D01*
X403483Y781683D01*
X403900Y781350D01*
G01X406750Y779183D02*
X407167Y778850D01*
X407750Y778600D01*
X408250D01*
X408750Y778767D01*
X409083Y779017D01*
X409250Y779350D01*
X409167Y779850D01*
X408833Y780100D01*
X407333Y780600D01*
X407000Y781183D01*
X407167Y781600D01*
X407500Y781850D01*
X408000Y781933D01*
X408500Y781850D01*
X409000Y781600D01*
G01X71000Y791500D02*
X73000D01*
G01X72000D02*
Y786500D01*
G01X71000D02*
X73000D01*
G01X75933D02*
Y791500D01*
X77933D01*
X78600Y791250D01*
X79100Y790667D01*
X79267Y790000D01*
X79100Y789333D01*
X78683Y788833D01*
X77933Y788583D01*
X75933D01*
G01X85033Y791083D02*
X84533Y791333D01*
X83950Y791500D01*
X83283D01*
X82533Y791250D01*
X81950Y790833D01*
X81533Y790333D01*
X81200Y789500D01*
X81117Y788750D01*
X81283Y788000D01*
X81533Y787500D01*
X82033Y787000D01*
X82617Y786667D01*
X83200Y786500D01*
X83783D01*
X84367Y786667D01*
X84867Y786917D01*
X85283Y787250D01*
G01X87717Y788167D02*
X89883D01*
G01X92317Y786500D02*
X94400Y791500D01*
X96483Y786500D01*
G01X95733Y788250D02*
X93067D01*
G01X98917Y788167D02*
X101083D01*
G01X104017Y788583D02*
X104600Y789167D01*
X105100Y789500D01*
X105767Y789667D01*
X106350Y789500D01*
X106767Y789167D01*
X107100Y788667D01*
X107183Y788083D01*
X107100Y787583D01*
X106767Y787083D01*
X106267Y786667D01*
X105683Y786500D01*
X105017Y786667D01*
X104433Y787167D01*
X104100Y787917D01*
X104017Y788750D01*
X104183Y789833D01*
X104433Y790417D01*
X104850Y791000D01*
X105433Y791417D01*
X106017Y791500D01*
X106600Y791333D01*
X107017Y790917D01*
G01X111200Y791500D02*
X110533Y791333D01*
X110033Y790917D01*
X109700Y790417D01*
X109450Y789750D01*
X109367Y789000D01*
X109450Y788250D01*
X109700Y787583D01*
X110033Y787083D01*
X110533Y786667D01*
X111200Y786500D01*
X111867Y786667D01*
X112367Y787083D01*
X112700Y787583D01*
X112950Y788250D01*
X113033Y789000D01*
X112950Y789750D01*
X112700Y790417D01*
X112367Y790917D01*
X111867Y791333D01*
X111200Y791500D01*
G01X116800D02*
X116133Y791333D01*
X115633Y790917D01*
X115300Y790417D01*
X115050Y789750D01*
X114967Y789000D01*
X115050Y788250D01*
X115300Y787583D01*
X115633Y787083D01*
X116133Y786667D01*
X116800Y786500D01*
X117467Y786667D01*
X117967Y787083D01*
X118300Y787583D01*
X118550Y788250D01*
X118633Y789000D01*
X118550Y789750D01*
X118300Y790417D01*
X117967Y790917D01*
X117467Y791333D01*
X116800Y791500D01*
G01X125917Y786500D02*
X128000Y791500D01*
X130083Y786500D01*
G01X129333Y788250D02*
X126667D01*
G01X134933Y789417D02*
X134350Y789750D01*
X133850Y789833D01*
X133183Y789667D01*
X132683Y789333D01*
X132350Y788750D01*
X132267Y788167D01*
X132350Y787583D01*
X132683Y787083D01*
X133183Y786667D01*
X133850Y786500D01*
X134433Y786667D01*
X134933Y787000D01*
G01X140533Y789417D02*
X139950Y789750D01*
X139450Y789833D01*
X138783Y789667D01*
X138283Y789333D01*
X137950Y788750D01*
X137867Y788167D01*
X137950Y787583D01*
X138283Y787083D01*
X138783Y786667D01*
X139450Y786500D01*
X140033Y786667D01*
X140533Y787000D01*
G01X143550Y788750D02*
X146217D01*
X145967Y789333D01*
X145550Y789667D01*
X144967Y789833D01*
X144383Y789750D01*
X143883Y789500D01*
X143550Y788917D01*
X143383Y788417D01*
Y787917D01*
X143550Y787417D01*
X143967Y786917D01*
X144467Y786583D01*
X145050Y786500D01*
X145633Y786667D01*
X146217Y787167D01*
G01X148900Y784833D02*
Y789833D01*
G01Y789083D02*
X149317Y789500D01*
X149733Y789750D01*
X150400Y789833D01*
X150983Y789750D01*
X151567Y789333D01*
X151817Y788750D01*
X151900Y788167D01*
X151817Y787583D01*
X151567Y787000D01*
X151067Y786667D01*
X150400Y786500D01*
X149817Y786583D01*
X149233Y786833D01*
X148900Y787167D01*
G01X156000Y791500D02*
Y786500D01*
G01X154833Y789833D02*
X157167D01*
G01X163100Y786500D02*
Y789833D01*
G01Y789250D02*
X162767Y789583D01*
X162267Y789750D01*
X161683Y789833D01*
X161100Y789667D01*
X160600Y789333D01*
X160267Y788833D01*
X160100Y788167D01*
X160267Y787500D01*
X160600Y787000D01*
X161100Y786667D01*
X161683Y786500D01*
X162267Y786583D01*
X162767Y786833D01*
X163100Y787167D01*
G01X165700Y786500D02*
Y791500D01*
G01Y789000D02*
X166117Y789500D01*
X166617Y789750D01*
X167117Y789833D01*
X167867Y789667D01*
X168367Y789333D01*
X168700Y788750D01*
Y788083D01*
X168533Y787417D01*
X168200Y786917D01*
X167617Y786583D01*
X167117Y786500D01*
X166617Y786583D01*
X166117Y786833D01*
X165700Y787250D01*
G01X172800Y789833D02*
Y786500D01*
G01Y791167D02*
X172633Y791250D01*
Y791417D01*
X172800Y791500D01*
X172967Y791417D01*
Y791250D01*
X172800Y791167D01*
G01X178400Y786500D02*
Y791500D01*
G01X184000Y789833D02*
Y786500D01*
G01Y791167D02*
X183833Y791250D01*
Y791417D01*
X184000Y791500D01*
X184167Y791417D01*
Y791250D01*
X184000Y791167D01*
G01X189600Y791500D02*
Y786500D01*
G01X188433Y789833D02*
X190767D01*
G01X193450Y785000D02*
X193950Y784833D01*
X194617Y785000D01*
X195033Y785333D01*
X195367Y785750D01*
X195867Y787083D01*
X196950Y789833D01*
G01X194283D02*
X195867Y787083D01*
G01X206400Y786500D02*
X205900Y786583D01*
X205400Y786917D01*
X205067Y787500D01*
X204900Y788167D01*
X205067Y788833D01*
X205400Y789417D01*
X205900Y789750D01*
X206400Y789833D01*
X206900Y789750D01*
X207400Y789417D01*
X207733Y788833D01*
X207817Y788167D01*
X207733Y787500D01*
X207400Y786917D01*
X206900Y786583D01*
X206400Y786500D01*
G01X211500D02*
Y790750D01*
X211667Y791167D01*
X212000Y791417D01*
X212500Y791500D01*
X213000Y791333D01*
X213250Y790917D01*
G01X212250Y789500D02*
X210583D01*
G01X221533Y786500D02*
Y791500D01*
X223533D01*
X224200Y791250D01*
X224700Y790667D01*
X224867Y790000D01*
X224700Y789333D01*
X224283Y788833D01*
X223533Y788583D01*
X221533D01*
G01X227633Y786500D02*
Y789833D01*
G01Y789167D02*
X228050Y789500D01*
X228467Y789750D01*
X229050Y789833D01*
X229467Y789750D01*
X229967Y789500D01*
G01X234400Y789833D02*
Y786500D01*
G01Y791167D02*
X234233Y791250D01*
Y791417D01*
X234400Y791500D01*
X234567Y791417D01*
Y791250D01*
X234400Y791167D01*
G01X238583Y786500D02*
Y789833D01*
G01Y789000D02*
X238917Y789417D01*
X239417Y789750D01*
X240083Y789833D01*
X240667Y789750D01*
X241167Y789417D01*
X241417Y788833D01*
Y786500D01*
G01X245600Y791500D02*
Y786500D01*
G01X244433Y789833D02*
X246767D01*
G01X249950Y788750D02*
X252617D01*
X252367Y789333D01*
X251950Y789667D01*
X251367Y789833D01*
X250783Y789750D01*
X250283Y789500D01*
X249950Y788917D01*
X249783Y788417D01*
Y787917D01*
X249950Y787417D01*
X250367Y786917D01*
X250867Y786583D01*
X251450Y786500D01*
X252033Y786667D01*
X252617Y787167D01*
G01X258300Y791500D02*
Y786500D01*
G01Y787250D02*
X257967Y786833D01*
X257467Y786583D01*
X256883Y786500D01*
X256217Y786667D01*
X255717Y787083D01*
X255383Y787583D01*
X255300Y788167D01*
X255383Y788750D01*
X255717Y789250D01*
X256217Y789667D01*
X256883Y789833D01*
X257467Y789750D01*
X257883Y789583D01*
X258300Y789250D01*
G01X268667Y789167D02*
X269000Y789417D01*
X269250Y789833D01*
X269417Y790417D01*
X269250Y790917D01*
X268917Y791250D01*
X268333Y791500D01*
X266083D01*
Y786500D01*
X268833D01*
X269417Y786833D01*
X269750Y787333D01*
X269917Y787917D01*
X269750Y788500D01*
X269250Y789000D01*
X268667Y789167D01*
X266083D01*
G01X273600Y786500D02*
X273100Y786583D01*
X272600Y786917D01*
X272267Y787500D01*
X272100Y788167D01*
X272267Y788833D01*
X272600Y789417D01*
X273100Y789750D01*
X273600Y789833D01*
X274100Y789750D01*
X274600Y789417D01*
X274933Y788833D01*
X275017Y788167D01*
X274933Y787500D01*
X274600Y786917D01*
X274100Y786583D01*
X273600Y786500D01*
G01X280700D02*
Y789833D01*
G01Y789250D02*
X280367Y789583D01*
X279867Y789750D01*
X279283Y789833D01*
X278700Y789667D01*
X278200Y789333D01*
X277867Y788833D01*
X277700Y788167D01*
X277867Y787500D01*
X278200Y787000D01*
X278700Y786667D01*
X279283Y786500D01*
X279867Y786583D01*
X280367Y786833D01*
X280700Y787167D01*
G01X283633Y786500D02*
Y789833D01*
G01Y789167D02*
X284050Y789500D01*
X284467Y789750D01*
X285050Y789833D01*
X285467Y789750D01*
X285967Y789500D01*
G01X291900Y791500D02*
Y786500D01*
G01Y787250D02*
X291567Y786833D01*
X291067Y786583D01*
X290483Y786500D01*
X289817Y786667D01*
X289317Y787083D01*
X288983Y787583D01*
X288900Y788167D01*
X288983Y788750D01*
X289317Y789250D01*
X289817Y789667D01*
X290483Y789833D01*
X291067Y789750D01*
X291483Y789583D01*
X291900Y789250D01*
G01X294750Y787083D02*
X295167Y786750D01*
X295750Y786500D01*
X296250D01*
X296750Y786667D01*
X297083Y786917D01*
X297250Y787250D01*
X297167Y787750D01*
X296833Y788000D01*
X295333Y788500D01*
X295000Y789083D01*
X295167Y789500D01*
X295500Y789750D01*
X296000Y789833D01*
X296500Y789750D01*
X297000Y789500D01*
G01X57833Y806500D02*
Y811500D01*
X59833D01*
X60500Y811250D01*
X61000Y810667D01*
X61167Y810000D01*
X61000Y809333D01*
X60583Y808833D01*
X59833Y808583D01*
X57833D01*
G01X65100Y806500D02*
Y811500D01*
G01X69450Y808750D02*
X72117D01*
X71867Y809333D01*
X71450Y809667D01*
X70867Y809833D01*
X70283Y809750D01*
X69783Y809500D01*
X69450Y808917D01*
X69283Y808417D01*
Y807917D01*
X69450Y807417D01*
X69867Y806917D01*
X70367Y806583D01*
X70950Y806500D01*
X71533Y806667D01*
X72117Y807167D01*
G01X77800Y806500D02*
Y809833D01*
G01Y809250D02*
X77467Y809583D01*
X76967Y809750D01*
X76383Y809833D01*
X75800Y809667D01*
X75300Y809333D01*
X74967Y808833D01*
X74800Y808167D01*
X74967Y807500D01*
X75300Y807000D01*
X75800Y806667D01*
X76383Y806500D01*
X76967Y806583D01*
X77467Y806833D01*
X77800Y807167D01*
G01X80650Y807083D02*
X81067Y806750D01*
X81650Y806500D01*
X82150D01*
X82650Y806667D01*
X82983Y806917D01*
X83150Y807250D01*
X83067Y807750D01*
X82733Y808000D01*
X81233Y808500D01*
X80900Y809083D01*
X81067Y809500D01*
X81400Y809750D01*
X81900Y809833D01*
X82400Y809750D01*
X82900Y809500D01*
G01X86250Y808750D02*
X88917D01*
X88667Y809333D01*
X88250Y809667D01*
X87667Y809833D01*
X87083Y809750D01*
X86583Y809500D01*
X86250Y808917D01*
X86083Y808417D01*
Y807917D01*
X86250Y807417D01*
X86667Y806917D01*
X87167Y806583D01*
X87750Y806500D01*
X88333Y806667D01*
X88917Y807167D01*
G01X98200Y806500D02*
Y810750D01*
X98367Y811167D01*
X98700Y811417D01*
X99200Y811500D01*
X99700Y811333D01*
X99950Y810917D01*
G01X98950Y809500D02*
X97283D01*
G01X104300Y806500D02*
X103800Y806583D01*
X103300Y806917D01*
X102967Y807500D01*
X102800Y808167D01*
X102967Y808833D01*
X103300Y809417D01*
X103800Y809750D01*
X104300Y809833D01*
X104800Y809750D01*
X105300Y809417D01*
X105633Y808833D01*
X105717Y808167D01*
X105633Y807500D01*
X105300Y806917D01*
X104800Y806583D01*
X104300Y806500D01*
G01X109900D02*
Y811500D01*
G01X115500Y806500D02*
Y811500D01*
G01X121100Y806500D02*
X120600Y806583D01*
X120100Y806917D01*
X119767Y807500D01*
X119600Y808167D01*
X119767Y808833D01*
X120100Y809417D01*
X120600Y809750D01*
X121100Y809833D01*
X121600Y809750D01*
X122100Y809417D01*
X122433Y808833D01*
X122517Y808167D01*
X122433Y807500D01*
X122100Y806917D01*
X121600Y806583D01*
X121100Y806500D01*
G01X124617Y809833D02*
X125617Y806500D01*
X126700Y809833D01*
X127783Y806500D01*
X128783Y809833D01*
G01X137900Y811500D02*
Y806500D01*
G01X136733Y809833D02*
X139067D01*
G01X142083Y806500D02*
Y811500D01*
G01Y809083D02*
X142500Y809500D01*
X142917Y809750D01*
X143583Y809833D01*
X144083Y809750D01*
X144667Y809417D01*
X144917Y808917D01*
Y806500D01*
G01X147850Y808750D02*
X150517D01*
X150267Y809333D01*
X149850Y809667D01*
X149267Y809833D01*
X148683Y809750D01*
X148183Y809500D01*
X147850Y808917D01*
X147683Y808417D01*
Y807917D01*
X147850Y807417D01*
X148267Y806917D01*
X148767Y806583D01*
X149350Y806500D01*
X149933Y806667D01*
X150517Y807167D01*
G01X159050Y807083D02*
X159467Y806750D01*
X160050Y806500D01*
X160550D01*
X161050Y806667D01*
X161383Y806917D01*
X161550Y807250D01*
X161467Y807750D01*
X161133Y808000D01*
X159633Y808500D01*
X159300Y809083D01*
X159467Y809500D01*
X159800Y809750D01*
X160300Y809833D01*
X160800Y809750D01*
X161300Y809500D01*
G01X164400Y804833D02*
Y809833D01*
G01Y809083D02*
X164817Y809500D01*
X165233Y809750D01*
X165900Y809833D01*
X166483Y809750D01*
X167067Y809333D01*
X167317Y808750D01*
X167400Y808167D01*
X167317Y807583D01*
X167067Y807000D01*
X166567Y806667D01*
X165900Y806500D01*
X165317Y806583D01*
X164733Y806833D01*
X164400Y807167D01*
G01X170250Y808750D02*
X172917D01*
X172667Y809333D01*
X172250Y809667D01*
X171667Y809833D01*
X171083Y809750D01*
X170583Y809500D01*
X170250Y808917D01*
X170083Y808417D01*
Y807917D01*
X170250Y807417D01*
X170667Y806917D01*
X171167Y806583D01*
X171750Y806500D01*
X172333Y806667D01*
X172917Y807167D01*
G01X178433Y809417D02*
X177850Y809750D01*
X177350Y809833D01*
X176683Y809667D01*
X176183Y809333D01*
X175850Y808750D01*
X175767Y808167D01*
X175850Y807583D01*
X176183Y807083D01*
X176683Y806667D01*
X177350Y806500D01*
X177933Y806667D01*
X178433Y807000D01*
G01X182700Y809833D02*
Y806500D01*
G01Y811167D02*
X182533Y811250D01*
Y811417D01*
X182700Y811500D01*
X182867Y811417D01*
Y811250D01*
X182700Y811167D01*
G01X187800Y806500D02*
Y810750D01*
X187967Y811167D01*
X188300Y811417D01*
X188800Y811500D01*
X189300Y811333D01*
X189550Y810917D01*
G01X188550Y809500D02*
X186883D01*
G01X193900Y809833D02*
Y806500D01*
G01Y811167D02*
X193733Y811250D01*
Y811417D01*
X193900Y811500D01*
X194067Y811417D01*
Y811250D01*
X193900Y811167D01*
G01X200833Y809417D02*
X200250Y809750D01*
X199750Y809833D01*
X199083Y809667D01*
X198583Y809333D01*
X198250Y808750D01*
X198167Y808167D01*
X198250Y807583D01*
X198583Y807083D01*
X199083Y806667D01*
X199750Y806500D01*
X200333Y806667D01*
X200833Y807000D01*
G01X206600Y806500D02*
Y809833D01*
G01Y809250D02*
X206267Y809583D01*
X205767Y809750D01*
X205183Y809833D01*
X204600Y809667D01*
X204100Y809333D01*
X203767Y808833D01*
X203600Y808167D01*
X203767Y807500D01*
X204100Y807000D01*
X204600Y806667D01*
X205183Y806500D01*
X205767Y806583D01*
X206267Y806833D01*
X206600Y807167D01*
G01X210700Y811500D02*
Y806500D01*
G01X209533Y809833D02*
X211867D01*
G01X216300D02*
Y806500D01*
G01Y811167D02*
X216133Y811250D01*
Y811417D01*
X216300Y811500D01*
X216467Y811417D01*
Y811250D01*
X216300Y811167D01*
G01X221900Y806500D02*
X221400Y806583D01*
X220900Y806917D01*
X220567Y807500D01*
X220400Y808167D01*
X220567Y808833D01*
X220900Y809417D01*
X221400Y809750D01*
X221900Y809833D01*
X222400Y809750D01*
X222900Y809417D01*
X223233Y808833D01*
X223317Y808167D01*
X223233Y807500D01*
X222900Y806917D01*
X222400Y806583D01*
X221900Y806500D01*
G01X226083D02*
Y809833D01*
G01Y809000D02*
X226417Y809417D01*
X226917Y809750D01*
X227583Y809833D01*
X228167Y809750D01*
X228667Y809417D01*
X228917Y808833D01*
Y806500D01*
G01X240200Y811500D02*
Y806500D01*
G01Y807250D02*
X239867Y806833D01*
X239367Y806583D01*
X238783Y806500D01*
X238117Y806667D01*
X237617Y807083D01*
X237283Y807583D01*
X237200Y808167D01*
X237283Y808750D01*
X237617Y809250D01*
X238117Y809667D01*
X238783Y809833D01*
X239367Y809750D01*
X239783Y809583D01*
X240200Y809250D01*
G01X244300Y806500D02*
X243800Y806583D01*
X243300Y806917D01*
X242967Y807500D01*
X242800Y808167D01*
X242967Y808833D01*
X243300Y809417D01*
X243800Y809750D01*
X244300Y809833D01*
X244800Y809750D01*
X245300Y809417D01*
X245633Y808833D01*
X245717Y808167D01*
X245633Y807500D01*
X245300Y806917D01*
X244800Y806583D01*
X244300Y806500D01*
G01X251233Y809417D02*
X250650Y809750D01*
X250150Y809833D01*
X249483Y809667D01*
X248983Y809333D01*
X248650Y808750D01*
X248567Y808167D01*
X248650Y807583D01*
X248983Y807083D01*
X249483Y806667D01*
X250150Y806500D01*
X250733Y806667D01*
X251233Y807000D01*
G01X254083Y809833D02*
Y807500D01*
X254417Y806917D01*
X254917Y806583D01*
X255500Y806500D01*
X256083Y806583D01*
X256583Y806917D01*
X256917Y807500D01*
G01Y806500D02*
Y809833D01*
G01X258600Y806500D02*
Y809833D01*
G01Y808917D02*
X258850Y809333D01*
X259267Y809667D01*
X259850Y809833D01*
X260433Y809667D01*
X260850Y809333D01*
X261100Y808917D01*
Y806500D01*
G01Y808917D02*
X261350Y809333D01*
X261767Y809667D01*
X262350Y809833D01*
X262933Y809667D01*
X263350Y809333D01*
X263600Y808833D01*
Y806500D01*
G01X265450Y808750D02*
X268117D01*
X267867Y809333D01*
X267450Y809667D01*
X266867Y809833D01*
X266283Y809750D01*
X265783Y809500D01*
X265450Y808917D01*
X265283Y808417D01*
Y807917D01*
X265450Y807417D01*
X265867Y806917D01*
X266367Y806583D01*
X266950Y806500D01*
X267533Y806667D01*
X268117Y807167D01*
G01X270883Y806500D02*
Y809833D01*
G01Y809000D02*
X271217Y809417D01*
X271717Y809750D01*
X272383Y809833D01*
X272967Y809750D01*
X273467Y809417D01*
X273717Y808833D01*
Y806500D01*
G01X277900Y811500D02*
Y806500D01*
G01X276733Y809833D02*
X279067D01*
G01X282250Y807083D02*
X282667Y806750D01*
X283250Y806500D01*
X283750D01*
X284250Y806667D01*
X284583Y806917D01*
X284750Y807250D01*
X284667Y807750D01*
X284333Y808000D01*
X282833Y808500D01*
X282500Y809083D01*
X282667Y809500D01*
X283000Y809750D01*
X283500Y809833D01*
X284000Y809750D01*
X284500Y809500D01*
G01X294700Y809833D02*
Y806500D01*
G01Y811167D02*
X294533Y811250D01*
Y811417D01*
X294700Y811500D01*
X294867Y811417D01*
Y811250D01*
X294700Y811167D01*
G01X298883Y806500D02*
Y809833D01*
G01Y809000D02*
X299217Y809417D01*
X299717Y809750D01*
X300383Y809833D01*
X300967Y809750D01*
X301467Y809417D01*
X301717Y808833D01*
Y806500D01*
G01X312833Y809417D02*
X312250Y809750D01*
X311750Y809833D01*
X311083Y809667D01*
X310583Y809333D01*
X310250Y808750D01*
X310167Y808167D01*
X310250Y807583D01*
X310583Y807083D01*
X311083Y806667D01*
X311750Y806500D01*
X312333Y806667D01*
X312833Y807000D01*
G01X317100Y806500D02*
Y811500D01*
G01X324200Y806500D02*
Y809833D01*
G01Y809250D02*
X323867Y809583D01*
X323367Y809750D01*
X322783Y809833D01*
X322200Y809667D01*
X321700Y809333D01*
X321367Y808833D01*
X321200Y808167D01*
X321367Y807500D01*
X321700Y807000D01*
X322200Y806667D01*
X322783Y806500D01*
X323367Y806583D01*
X323867Y806833D01*
X324200Y807167D01*
G01X327050Y807083D02*
X327467Y806750D01*
X328050Y806500D01*
X328550D01*
X329050Y806667D01*
X329383Y806917D01*
X329550Y807250D01*
X329467Y807750D01*
X329133Y808000D01*
X327633Y808500D01*
X327300Y809083D01*
X327467Y809500D01*
X327800Y809750D01*
X328300Y809833D01*
X328800Y809750D01*
X329300Y809500D01*
G01X332650Y807083D02*
X333067Y806750D01*
X333650Y806500D01*
X334150D01*
X334650Y806667D01*
X334983Y806917D01*
X335150Y807250D01*
X335067Y807750D01*
X334733Y808000D01*
X333233Y808500D01*
X332900Y809083D01*
X333067Y809500D01*
X333400Y809750D01*
X333900Y809833D01*
X334400Y809750D01*
X334900Y809500D01*
G01X343517Y810667D02*
X344017Y811167D01*
X344600Y811417D01*
X345267Y811500D01*
X346100Y811333D01*
X346683Y810917D01*
X346850Y810417D01*
X346767Y809917D01*
X346433Y809500D01*
X344767Y808667D01*
X344017Y808083D01*
X343517Y807250D01*
X343350Y806500D01*
X346850D01*
G01X357800D02*
Y809833D01*
G01Y809250D02*
X357467Y809583D01*
X356967Y809750D01*
X356383Y809833D01*
X355800Y809667D01*
X355300Y809333D01*
X354967Y808833D01*
X354800Y808167D01*
X354967Y807500D01*
X355300Y807000D01*
X355800Y806667D01*
X356383Y806500D01*
X356967Y806583D01*
X357467Y806833D01*
X357800Y807167D01*
G01X360483Y806500D02*
Y809833D01*
G01Y809000D02*
X360817Y809417D01*
X361317Y809750D01*
X361983Y809833D01*
X362567Y809750D01*
X363067Y809417D01*
X363317Y808833D01*
Y806500D01*
G01X369000Y811500D02*
Y806500D01*
G01Y807250D02*
X368667Y806833D01*
X368167Y806583D01*
X367583Y806500D01*
X366917Y806667D01*
X366417Y807083D01*
X366083Y807583D01*
X366000Y808167D01*
X366083Y808750D01*
X366417Y809250D01*
X366917Y809667D01*
X367583Y809833D01*
X368167Y809750D01*
X368583Y809583D01*
X369000Y809250D01*
G01X378700Y811500D02*
Y806500D01*
G01X377533Y809833D02*
X379867D01*
G01X382883Y806500D02*
Y811500D01*
G01Y809083D02*
X383300Y809500D01*
X383717Y809750D01*
X384383Y809833D01*
X384883Y809750D01*
X385467Y809417D01*
X385717Y808917D01*
Y806500D01*
G01X388650Y808750D02*
X391317D01*
X391067Y809333D01*
X390650Y809667D01*
X390067Y809833D01*
X389483Y809750D01*
X388983Y809500D01*
X388650Y808917D01*
X388483Y808417D01*
Y807917D01*
X388650Y807417D01*
X389067Y806917D01*
X389567Y806583D01*
X390150Y806500D01*
X390733Y806667D01*
X391317Y807167D01*
G01X401100Y806500D02*
Y811500D01*
G01X408200Y806500D02*
Y809833D01*
G01Y809250D02*
X407867Y809583D01*
X407367Y809750D01*
X406783Y809833D01*
X406200Y809667D01*
X405700Y809333D01*
X405367Y808833D01*
X405200Y808167D01*
X405367Y807500D01*
X405700Y807000D01*
X406200Y806667D01*
X406783Y806500D01*
X407367Y806583D01*
X407867Y806833D01*
X408200Y807167D01*
G01X412300Y811500D02*
Y806500D01*
G01X411133Y809833D02*
X413467D01*
G01X416650Y808750D02*
X419317D01*
X419067Y809333D01*
X418650Y809667D01*
X418067Y809833D01*
X417483Y809750D01*
X416983Y809500D01*
X416650Y808917D01*
X416483Y808417D01*
Y807917D01*
X416650Y807417D01*
X417067Y806917D01*
X417567Y806583D01*
X418150Y806500D01*
X418733Y806667D01*
X419317Y807167D01*
G01X422250Y807083D02*
X422667Y806750D01*
X423250Y806500D01*
X423750D01*
X424250Y806667D01*
X424583Y806917D01*
X424750Y807250D01*
X424667Y807750D01*
X424333Y808000D01*
X422833Y808500D01*
X422500Y809083D01*
X422667Y809500D01*
X423000Y809750D01*
X423500Y809833D01*
X424000Y809750D01*
X424500Y809500D01*
G01X429100Y811500D02*
Y806500D01*
G01X427933Y809833D02*
X430267D01*
G01X438800D02*
X440300Y806500D01*
X441800Y809833D01*
G01X444650Y808750D02*
X447317D01*
X447067Y809333D01*
X446650Y809667D01*
X446067Y809833D01*
X445483Y809750D01*
X444983Y809500D01*
X444650Y808917D01*
X444483Y808417D01*
Y807917D01*
X444650Y807417D01*
X445067Y806917D01*
X445567Y806583D01*
X446150Y806500D01*
X446733Y806667D01*
X447317Y807167D01*
G01X450333Y806500D02*
Y809833D01*
G01Y809167D02*
X450750Y809500D01*
X451167Y809750D01*
X451750Y809833D01*
X452167Y809750D01*
X452667Y809500D01*
G01X455850Y807083D02*
X456267Y806750D01*
X456850Y806500D01*
X457350D01*
X457850Y806667D01*
X458183Y806917D01*
X458350Y807250D01*
X458267Y807750D01*
X457933Y808000D01*
X456433Y808500D01*
X456100Y809083D01*
X456267Y809500D01*
X456600Y809750D01*
X457100Y809833D01*
X457600Y809750D01*
X458100Y809500D01*
G01X462700Y809833D02*
Y806500D01*
G01Y811167D02*
X462533Y811250D01*
Y811417D01*
X462700Y811500D01*
X462867Y811417D01*
Y811250D01*
X462700Y811167D01*
G01X468300Y806500D02*
X467800Y806583D01*
X467300Y806917D01*
X466967Y807500D01*
X466800Y808167D01*
X466967Y808833D01*
X467300Y809417D01*
X467800Y809750D01*
X468300Y809833D01*
X468800Y809750D01*
X469300Y809417D01*
X469633Y808833D01*
X469717Y808167D01*
X469633Y807500D01*
X469300Y806917D01*
X468800Y806583D01*
X468300Y806500D01*
G01X472483D02*
Y809833D01*
G01Y809000D02*
X472817Y809417D01*
X473317Y809750D01*
X473983Y809833D01*
X474567Y809750D01*
X475067Y809417D01*
X475317Y808833D01*
Y806500D01*
G01X485100Y809833D02*
Y806500D01*
G01Y811167D02*
X484933Y811250D01*
Y811417D01*
X485100Y811500D01*
X485267Y811417D01*
Y811250D01*
X485100Y811167D01*
G01X489450Y807083D02*
X489867Y806750D01*
X490450Y806500D01*
X490950D01*
X491450Y806667D01*
X491783Y806917D01*
X491950Y807250D01*
X491867Y807750D01*
X491533Y808000D01*
X490033Y808500D01*
X489700Y809083D01*
X489867Y809500D01*
X490200Y809750D01*
X490700Y809833D01*
X491200Y809750D01*
X491700Y809500D01*
G01X500733Y806500D02*
Y809833D01*
G01Y809167D02*
X501150Y809500D01*
X501567Y809750D01*
X502150Y809833D01*
X502567Y809750D01*
X503067Y809500D01*
G01X506250Y808750D02*
X508917D01*
X508667Y809333D01*
X508250Y809667D01*
X507667Y809833D01*
X507083Y809750D01*
X506583Y809500D01*
X506250Y808917D01*
X506083Y808417D01*
Y807917D01*
X506250Y807417D01*
X506667Y806917D01*
X507167Y806583D01*
X507750Y806500D01*
X508333Y806667D01*
X508917Y807167D01*
G01X514600Y804833D02*
Y809833D01*
G01Y809083D02*
X514183Y809500D01*
X513683Y809750D01*
X513100Y809833D01*
X512600Y809750D01*
X512017Y809333D01*
X511683Y808750D01*
X511600Y808167D01*
X511683Y807583D01*
X512017Y807000D01*
X512600Y806583D01*
X513100Y806500D01*
X513683Y806583D01*
X514183Y806833D01*
X514600Y807250D01*
G01X517283Y809833D02*
Y807500D01*
X517617Y806917D01*
X518117Y806583D01*
X518700Y806500D01*
X519283Y806583D01*
X519783Y806917D01*
X520117Y807500D01*
G01Y806500D02*
Y809833D01*
G01X524300D02*
Y806500D01*
G01Y811167D02*
X524133Y811250D01*
Y811417D01*
X524300Y811500D01*
X524467Y811417D01*
Y811250D01*
X524300Y811167D01*
G01X528733Y806500D02*
Y809833D01*
G01Y809167D02*
X529150Y809500D01*
X529567Y809750D01*
X530150Y809833D01*
X530567Y809750D01*
X531067Y809500D01*
G01X534250Y808750D02*
X536917D01*
X536667Y809333D01*
X536250Y809667D01*
X535667Y809833D01*
X535083Y809750D01*
X534583Y809500D01*
X534250Y808917D01*
X534083Y808417D01*
Y807917D01*
X534250Y807417D01*
X534667Y806917D01*
X535167Y806583D01*
X535750Y806500D01*
X536333Y806667D01*
X536917Y807167D01*
G01X542600Y811500D02*
Y806500D01*
G01Y807250D02*
X542267Y806833D01*
X541767Y806583D01*
X541183Y806500D01*
X540517Y806667D01*
X540017Y807083D01*
X539683Y807583D01*
X539600Y808167D01*
X539683Y808750D01*
X540017Y809250D01*
X540517Y809667D01*
X541183Y809833D01*
X541767Y809750D01*
X542183Y809583D01*
X542600Y809250D01*
G01X546533Y805583D02*
X546867Y806667D01*
G01X114000Y17000D02*
Y12000D01*
G01X112083Y17000D02*
X115917D01*
G01X117517Y15333D02*
X118517Y12000D01*
X119600Y15333D01*
X120683Y12000D01*
X121683Y15333D01*
G01X125200D02*
Y12000D01*
G01Y16667D02*
X125033Y16750D01*
Y16917D01*
X125200Y17000D01*
X125367Y16917D01*
Y16750D01*
X125200Y16667D01*
G01X129550Y12583D02*
X129967Y12250D01*
X130550Y12000D01*
X131050D01*
X131550Y12167D01*
X131883Y12417D01*
X132050Y12750D01*
X131967Y13250D01*
X131633Y13500D01*
X130133Y14000D01*
X129800Y14583D01*
X129967Y15000D01*
X130300Y15250D01*
X130800Y15333D01*
X131300Y15250D01*
X131800Y15000D01*
G01X136400Y17000D02*
Y12000D01*
G01X135233Y15333D02*
X137567D01*
G01X149100Y12000D02*
Y15333D01*
G01Y14750D02*
X148767Y15083D01*
X148267Y15250D01*
X147683Y15333D01*
X147100Y15167D01*
X146600Y14833D01*
X146267Y14333D01*
X146100Y13667D01*
X146267Y13000D01*
X146600Y12500D01*
X147100Y12167D01*
X147683Y12000D01*
X148267Y12083D01*
X148767Y12333D01*
X149100Y12667D01*
G01X151783Y12000D02*
Y15333D01*
G01Y14500D02*
X152117Y14917D01*
X152617Y15250D01*
X153283Y15333D01*
X153867Y15250D01*
X154367Y14917D01*
X154617Y14333D01*
Y12000D01*
G01X160300Y17000D02*
Y12000D01*
G01Y12750D02*
X159967Y12333D01*
X159467Y12083D01*
X158883Y12000D01*
X158217Y12167D01*
X157717Y12583D01*
X157383Y13083D01*
X157300Y13667D01*
X157383Y14250D01*
X157717Y14750D01*
X158217Y15167D01*
X158883Y15333D01*
X159467Y15250D01*
X159883Y15083D01*
X160300Y14750D01*
G01X168500Y12000D02*
Y17000D01*
G01Y14500D02*
X168917Y15000D01*
X169417Y15250D01*
X169917Y15333D01*
X170667Y15167D01*
X171167Y14833D01*
X171500Y14250D01*
Y13583D01*
X171333Y12917D01*
X171000Y12417D01*
X170417Y12083D01*
X169917Y12000D01*
X169417Y12083D01*
X168917Y12333D01*
X168500Y12750D01*
G01X175600Y12000D02*
X175100Y12083D01*
X174600Y12417D01*
X174267Y13000D01*
X174100Y13667D01*
X174267Y14333D01*
X174600Y14917D01*
X175100Y15250D01*
X175600Y15333D01*
X176100Y15250D01*
X176600Y14917D01*
X176933Y14333D01*
X177017Y13667D01*
X176933Y13000D01*
X176600Y12417D01*
X176100Y12083D01*
X175600Y12000D01*
G01X179117Y15333D02*
X180117Y12000D01*
X181200Y15333D01*
X182283Y12000D01*
X183283Y15333D01*
G01X112333Y48000D02*
Y53000D01*
X114417D01*
X115083Y52750D01*
X115500Y52417D01*
X115667Y51750D01*
X115500Y51083D01*
X115000Y50667D01*
X114417Y50417D01*
X112333D01*
G01X114417D02*
X115667Y48000D01*
G01X119600D02*
X119100Y48083D01*
X118600Y48417D01*
X118267Y49000D01*
X118100Y49667D01*
X118267Y50333D01*
X118600Y50917D01*
X119100Y51250D01*
X119600Y51333D01*
X120100Y51250D01*
X120600Y50917D01*
X120933Y50333D01*
X121017Y49667D01*
X120933Y49000D01*
X120600Y48417D01*
X120100Y48083D01*
X119600Y48000D01*
G01X123783Y51333D02*
Y49000D01*
X124117Y48417D01*
X124617Y48083D01*
X125200Y48000D01*
X125783Y48083D01*
X126283Y48417D01*
X126617Y49000D01*
G01Y48000D02*
Y51333D01*
G01X130800Y53000D02*
Y48000D01*
G01X129633Y51333D02*
X131967D01*
G01X136400D02*
Y48000D01*
G01Y52667D02*
X136233Y52750D01*
Y52917D01*
X136400Y53000D01*
X136567Y52917D01*
Y52750D01*
X136400Y52667D01*
G01X140583Y48000D02*
Y51333D01*
G01Y50500D02*
X140917Y50917D01*
X141417Y51250D01*
X142083Y51333D01*
X142667Y51250D01*
X143167Y50917D01*
X143417Y50333D01*
Y48000D01*
G01X146433Y46750D02*
X147017Y46417D01*
X147683Y46333D01*
X148267Y46417D01*
X148767Y46833D01*
X149100Y47417D01*
Y51333D01*
G01Y50667D02*
X148767Y51000D01*
X148267Y51250D01*
X147683Y51333D01*
X147017Y51167D01*
X146600Y50833D01*
X146267Y50250D01*
X146100Y49667D01*
X146183Y49167D01*
X146517Y48583D01*
X147017Y48167D01*
X147683Y48000D01*
X148183Y48083D01*
X148767Y48417D01*
X149100Y48750D01*
G01X158800Y53000D02*
Y48000D01*
G01X157633Y51333D02*
X159967D01*
G01X164400Y48000D02*
X163900Y48083D01*
X163400Y48417D01*
X163067Y49000D01*
X162900Y49667D01*
X163067Y50333D01*
X163400Y50917D01*
X163900Y51250D01*
X164400Y51333D01*
X164900Y51250D01*
X165400Y50917D01*
X165733Y50333D01*
X165817Y49667D01*
X165733Y49000D01*
X165400Y48417D01*
X164900Y48083D01*
X164400Y48000D01*
G01X170000D02*
Y53000D01*
G01X174350Y50250D02*
X177017D01*
X176767Y50833D01*
X176350Y51167D01*
X175767Y51333D01*
X175183Y51250D01*
X174683Y51000D01*
X174350Y50417D01*
X174183Y49917D01*
Y49417D01*
X174350Y48917D01*
X174767Y48417D01*
X175267Y48083D01*
X175850Y48000D01*
X176433Y48167D01*
X177017Y48667D01*
G01X180033Y48000D02*
Y51333D01*
G01Y50667D02*
X180450Y51000D01*
X180867Y51250D01*
X181450Y51333D01*
X181867Y51250D01*
X182367Y51000D01*
G01X188300Y48000D02*
Y51333D01*
G01Y50750D02*
X187967Y51083D01*
X187467Y51250D01*
X186883Y51333D01*
X186300Y51167D01*
X185800Y50833D01*
X185467Y50333D01*
X185300Y49667D01*
X185467Y49000D01*
X185800Y48500D01*
X186300Y48167D01*
X186883Y48000D01*
X187467Y48083D01*
X187967Y48333D01*
X188300Y48667D01*
G01X190983Y48000D02*
Y51333D01*
G01Y50500D02*
X191317Y50917D01*
X191817Y51250D01*
X192483Y51333D01*
X193067Y51250D01*
X193567Y50917D01*
X193817Y50333D01*
Y48000D01*
G01X199333Y50917D02*
X198750Y51250D01*
X198250Y51333D01*
X197583Y51167D01*
X197083Y50833D01*
X196750Y50250D01*
X196667Y49667D01*
X196750Y49083D01*
X197083Y48583D01*
X197583Y48167D01*
X198250Y48000D01*
X198833Y48167D01*
X199333Y48500D01*
G01X202350Y50250D02*
X205017D01*
X204767Y50833D01*
X204350Y51167D01*
X203767Y51333D01*
X203183Y51250D01*
X202683Y51000D01*
X202350Y50417D01*
X202183Y49917D01*
Y49417D01*
X202350Y48917D01*
X202767Y48417D01*
X203267Y48083D01*
X203850Y48000D01*
X204433Y48167D01*
X205017Y48667D01*
G01X103500Y678500D02*
Y0D01*
G01Y27000D02*
X694500D01*
G01X112333Y81500D02*
Y76500D01*
X115667D01*
G01X119600D02*
X119100Y76583D01*
X118600Y76917D01*
X118267Y77500D01*
X118100Y78167D01*
X118267Y78833D01*
X118600Y79417D01*
X119100Y79750D01*
X119600Y79833D01*
X120100Y79750D01*
X120600Y79417D01*
X120933Y78833D01*
X121017Y78167D01*
X120933Y77500D01*
X120600Y76917D01*
X120100Y76583D01*
X119600Y76500D01*
G01X124033Y75250D02*
X124617Y74917D01*
X125283Y74833D01*
X125867Y74917D01*
X126367Y75333D01*
X126700Y75917D01*
Y79833D01*
G01Y79167D02*
X126367Y79500D01*
X125867Y79750D01*
X125283Y79833D01*
X124617Y79667D01*
X124200Y79333D01*
X123867Y78750D01*
X123700Y78167D01*
X123783Y77667D01*
X124117Y77083D01*
X124617Y76667D01*
X125283Y76500D01*
X125783Y76583D01*
X126367Y76917D01*
X126700Y77250D01*
G01X130800Y76500D02*
X130300Y76583D01*
X129800Y76917D01*
X129467Y77500D01*
X129300Y78167D01*
X129467Y78833D01*
X129800Y79417D01*
X130300Y79750D01*
X130800Y79833D01*
X131300Y79750D01*
X131800Y79417D01*
X132133Y78833D01*
X132217Y78167D01*
X132133Y77500D01*
X131800Y76917D01*
X131300Y76583D01*
X130800Y76500D01*
G01X114000Y105500D02*
Y100500D01*
G01X112833Y103833D02*
X115167D01*
G01X118183Y100500D02*
Y105500D01*
G01Y103083D02*
X118600Y103500D01*
X119017Y103750D01*
X119683Y103833D01*
X120183Y103750D01*
X120767Y103417D01*
X121017Y102917D01*
Y100500D01*
G01X125200Y103833D02*
Y100500D01*
G01Y105167D02*
X125033Y105250D01*
Y105417D01*
X125200Y105500D01*
X125367Y105417D01*
Y105250D01*
X125200Y105167D01*
G01X132133Y103417D02*
X131550Y103750D01*
X131050Y103833D01*
X130383Y103667D01*
X129883Y103333D01*
X129550Y102750D01*
X129467Y102167D01*
X129550Y101583D01*
X129883Y101083D01*
X130383Y100667D01*
X131050Y100500D01*
X131633Y100667D01*
X132133Y101000D01*
G01X134983Y100500D02*
Y105500D01*
G01X137650Y103833D02*
X134983Y101917D01*
G01X136067Y102667D02*
X137817Y100500D01*
G01X140583D02*
Y103833D01*
G01Y103000D02*
X140917Y103417D01*
X141417Y103750D01*
X142083Y103833D01*
X142667Y103750D01*
X143167Y103417D01*
X143417Y102833D01*
Y100500D01*
G01X146350Y102750D02*
X149017D01*
X148767Y103333D01*
X148350Y103667D01*
X147767Y103833D01*
X147183Y103750D01*
X146683Y103500D01*
X146350Y102917D01*
X146183Y102417D01*
Y101917D01*
X146350Y101417D01*
X146767Y100917D01*
X147267Y100583D01*
X147850Y100500D01*
X148433Y100667D01*
X149017Y101167D01*
G01X151950Y101083D02*
X152367Y100750D01*
X152950Y100500D01*
X153450D01*
X153950Y100667D01*
X154283Y100917D01*
X154450Y101250D01*
X154367Y101750D01*
X154033Y102000D01*
X152533Y102500D01*
X152200Y103083D01*
X152367Y103500D01*
X152700Y103750D01*
X153200Y103833D01*
X153700Y103750D01*
X154200Y103500D01*
G01X157550Y101083D02*
X157967Y100750D01*
X158550Y100500D01*
X159050D01*
X159550Y100667D01*
X159883Y100917D01*
X160050Y101250D01*
X159967Y101750D01*
X159633Y102000D01*
X158133Y102500D01*
X157800Y103083D01*
X157967Y103500D01*
X158300Y103750D01*
X158800Y103833D01*
X159300Y103750D01*
X159800Y103500D01*
G01X114000Y126500D02*
Y121500D01*
G01X112833Y124833D02*
X115167D01*
G01X118183Y121500D02*
Y126500D01*
G01Y124083D02*
X118600Y124500D01*
X119017Y124750D01*
X119683Y124833D01*
X120183Y124750D01*
X120767Y124417D01*
X121017Y123917D01*
Y121500D01*
G01X125200Y124833D02*
Y121500D01*
G01Y126167D02*
X125033Y126250D01*
Y126417D01*
X125200Y126500D01*
X125367Y126417D01*
Y126250D01*
X125200Y126167D01*
G01X132133Y124417D02*
X131550Y124750D01*
X131050Y124833D01*
X130383Y124667D01*
X129883Y124333D01*
X129550Y123750D01*
X129467Y123167D01*
X129550Y122583D01*
X129883Y122083D01*
X130383Y121667D01*
X131050Y121500D01*
X131633Y121667D01*
X132133Y122000D01*
G01X134983Y121500D02*
Y126500D01*
G01X137650Y124833D02*
X134983Y122917D01*
G01X136067Y123667D02*
X137817Y121500D01*
G01X140583D02*
Y124833D01*
G01Y124000D02*
X140917Y124417D01*
X141417Y124750D01*
X142083Y124833D01*
X142667Y124750D01*
X143167Y124417D01*
X143417Y123833D01*
Y121500D01*
G01X146350Y123750D02*
X149017D01*
X148767Y124333D01*
X148350Y124667D01*
X147767Y124833D01*
X147183Y124750D01*
X146683Y124500D01*
X146350Y123917D01*
X146183Y123417D01*
Y122917D01*
X146350Y122417D01*
X146767Y121917D01*
X147267Y121583D01*
X147850Y121500D01*
X148433Y121667D01*
X149017Y122167D01*
G01X151950Y122083D02*
X152367Y121750D01*
X152950Y121500D01*
X153450D01*
X153950Y121667D01*
X154283Y121917D01*
X154450Y122250D01*
X154367Y122750D01*
X154033Y123000D01*
X152533Y123500D01*
X152200Y124083D01*
X152367Y124500D01*
X152700Y124750D01*
X153200Y124833D01*
X153700Y124750D01*
X154200Y124500D01*
G01X157550Y122083D02*
X157967Y121750D01*
X158550Y121500D01*
X159050D01*
X159550Y121667D01*
X159883Y121917D01*
X160050Y122250D01*
X159967Y122750D01*
X159633Y123000D01*
X158133Y123500D01*
X157800Y124083D01*
X157967Y124500D01*
X158300Y124750D01*
X158800Y124833D01*
X159300Y124750D01*
X159800Y124500D01*
G01X119183Y139333D02*
X118350Y140167D01*
X117933Y141000D01*
Y144333D01*
X118350Y145167D01*
X119183Y146000D01*
G01X123450Y141667D02*
X124117Y141250D01*
X124867Y141000D01*
X125533D01*
X126200Y141250D01*
X126700Y141667D01*
X126950Y142250D01*
X126783Y142833D01*
X126367Y143333D01*
X125617Y143667D01*
X124617Y143833D01*
X124033Y144167D01*
X123783Y144750D01*
X123950Y145333D01*
X124367Y145750D01*
X124950Y146000D01*
X125533D01*
X126117Y145833D01*
X126617Y145417D01*
G01X128633Y141000D02*
Y146000D01*
X130800Y141833D01*
X132967Y146000D01*
Y141000D01*
G01X134567D02*
Y146000D01*
X136233D01*
X136900Y145750D01*
X137400Y145417D01*
X137817Y144917D01*
X138150Y144333D01*
X138233Y143500D01*
X138150Y142667D01*
X137817Y142083D01*
X137400Y141583D01*
X136900Y141250D01*
X136233Y141000D01*
X134567D01*
G01X142417Y139333D02*
X143250Y140167D01*
X143667Y141000D01*
Y144333D01*
X143250Y145167D01*
X142417Y146000D01*
G01X103500Y132000D02*
X694500D01*
G01X103500Y87000D02*
X694500D01*
G01X111833Y168000D02*
Y173000D01*
X114000Y168833D01*
X116167Y173000D01*
Y168000D01*
G01X121100D02*
Y171333D01*
G01Y170750D02*
X120767Y171083D01*
X120267Y171250D01*
X119683Y171333D01*
X119100Y171167D01*
X118600Y170833D01*
X118267Y170333D01*
X118100Y169667D01*
X118267Y169000D01*
X118600Y168500D01*
X119100Y168167D01*
X119683Y168000D01*
X120267Y168083D01*
X120767Y168333D01*
X121100Y168667D01*
G01X124033Y168000D02*
Y171333D01*
G01Y170667D02*
X124450Y171000D01*
X124867Y171250D01*
X125450Y171333D01*
X125867Y171250D01*
X126367Y171000D01*
G01X129383Y168000D02*
Y173000D01*
G01X132050Y171333D02*
X129383Y169417D01*
G01X130467Y170167D02*
X132217Y168000D01*
G01X136817Y166333D02*
X137650Y167167D01*
X138067Y168000D01*
Y171333D01*
X137650Y172167D01*
X136817Y173000D01*
G01X114500Y181000D02*
X116167D01*
Y179500D01*
X115667Y179000D01*
X115083Y178667D01*
X114250Y178500D01*
X113417Y178667D01*
X112833Y179000D01*
X112333Y179500D01*
X112000Y180083D01*
X111833Y180750D01*
Y181333D01*
X112000Y181833D01*
X112333Y182417D01*
X112833Y182917D01*
X113333Y183250D01*
X114000Y183500D01*
X114583D01*
X115250Y183333D01*
X115750Y183000D01*
G01X119600Y178500D02*
X119100Y178583D01*
X118600Y178917D01*
X118267Y179500D01*
X118100Y180167D01*
X118267Y180833D01*
X118600Y181417D01*
X119100Y181750D01*
X119600Y181833D01*
X120100Y181750D01*
X120600Y181417D01*
X120933Y180833D01*
X121017Y180167D01*
X120933Y179500D01*
X120600Y178917D01*
X120100Y178583D01*
X119600Y178500D01*
G01X125200D02*
Y183500D01*
G01X132300D02*
Y178500D01*
G01Y179250D02*
X131967Y178833D01*
X131467Y178583D01*
X130883Y178500D01*
X130217Y178667D01*
X129717Y179083D01*
X129383Y179583D01*
X129300Y180167D01*
X129383Y180750D01*
X129717Y181250D01*
X130217Y181667D01*
X130883Y181833D01*
X131467Y181750D01*
X131883Y181583D01*
X132300Y181250D01*
G01X135150Y180750D02*
X137817D01*
X137567Y181333D01*
X137150Y181667D01*
X136567Y181833D01*
X135983Y181750D01*
X135483Y181500D01*
X135150Y180917D01*
X134983Y180417D01*
Y179917D01*
X135150Y179417D01*
X135567Y178917D01*
X136067Y178583D01*
X136650Y178500D01*
X137233Y178667D01*
X137817Y179167D01*
G01X140583Y178500D02*
Y181833D01*
G01Y181000D02*
X140917Y181417D01*
X141417Y181750D01*
X142083Y181833D01*
X142667Y181750D01*
X143167Y181417D01*
X143417Y180833D01*
Y178500D01*
G01X152700D02*
Y182750D01*
X152867Y183167D01*
X153200Y183417D01*
X153700Y183500D01*
X154200Y183333D01*
X154450Y182917D01*
G01X153450Y181500D02*
X151783D01*
G01X158800Y181833D02*
Y178500D01*
G01Y183167D02*
X158633Y183250D01*
Y183417D01*
X158800Y183500D01*
X158967Y183417D01*
Y183250D01*
X158800Y183167D01*
G01X162983Y178500D02*
Y181833D01*
G01Y181000D02*
X163317Y181417D01*
X163817Y181750D01*
X164483Y181833D01*
X165067Y181750D01*
X165567Y181417D01*
X165817Y180833D01*
Y178500D01*
G01X168833Y177250D02*
X169417Y176917D01*
X170083Y176833D01*
X170667Y176917D01*
X171167Y177333D01*
X171500Y177917D01*
Y181833D01*
G01Y181167D02*
X171167Y181500D01*
X170667Y181750D01*
X170083Y181833D01*
X169417Y181667D01*
X169000Y181333D01*
X168667Y180750D01*
X168500Y180167D01*
X168583Y179667D01*
X168917Y179083D01*
X169417Y178667D01*
X170083Y178500D01*
X170583Y178583D01*
X171167Y178917D01*
X171500Y179250D01*
G01X174350Y180750D02*
X177017D01*
X176767Y181333D01*
X176350Y181667D01*
X175767Y181833D01*
X175183Y181750D01*
X174683Y181500D01*
X174350Y180917D01*
X174183Y180417D01*
Y179917D01*
X174350Y179417D01*
X174767Y178917D01*
X175267Y178583D01*
X175850Y178500D01*
X176433Y178667D01*
X177017Y179167D01*
G01X180033Y178500D02*
Y181833D01*
G01Y181167D02*
X180450Y181500D01*
X180867Y181750D01*
X181450Y181833D01*
X181867Y181750D01*
X182367Y181500D01*
G01X190733Y178500D02*
Y183500D01*
X192733D01*
X193400Y183250D01*
X193900Y182667D01*
X194067Y182000D01*
X193900Y181333D01*
X193483Y180833D01*
X192733Y180583D01*
X190733D01*
G01X195917Y178500D02*
X198000Y183500D01*
X200083Y178500D01*
G01X199333Y180250D02*
X196667D01*
G01X201767Y178500D02*
Y183500D01*
X203433D01*
X204100Y183250D01*
X204600Y182917D01*
X205017Y182417D01*
X205350Y181833D01*
X205433Y181000D01*
X205350Y180167D01*
X205017Y179583D01*
X204600Y179083D01*
X204100Y178750D01*
X203433Y178500D01*
X201767D01*
G01X213300Y178333D02*
X216300Y183500D01*
G01X218817Y178500D02*
Y183500D01*
X221983D01*
G01X220817Y181083D02*
X218817D01*
G01X226000Y181833D02*
Y178500D01*
G01Y183167D02*
X225833Y183250D01*
Y183417D01*
X226000Y183500D01*
X226167Y183417D01*
Y183250D01*
X226000Y183167D01*
G01X233100Y183500D02*
Y178500D01*
G01Y179250D02*
X232767Y178833D01*
X232267Y178583D01*
X231683Y178500D01*
X231017Y178667D01*
X230517Y179083D01*
X230183Y179583D01*
X230100Y180167D01*
X230183Y180750D01*
X230517Y181250D01*
X231017Y181667D01*
X231683Y181833D01*
X232267Y181750D01*
X232683Y181583D01*
X233100Y181250D01*
G01X235783Y181833D02*
Y179500D01*
X236117Y178917D01*
X236617Y178583D01*
X237200Y178500D01*
X237783Y178583D01*
X238283Y178917D01*
X238617Y179500D01*
G01Y178500D02*
Y181833D01*
G01X244133Y181417D02*
X243550Y181750D01*
X243050Y181833D01*
X242383Y181667D01*
X241883Y181333D01*
X241550Y180750D01*
X241467Y180167D01*
X241550Y179583D01*
X241883Y179083D01*
X242383Y178667D01*
X243050Y178500D01*
X243633Y178667D01*
X244133Y179000D01*
G01X248400Y181833D02*
Y178500D01*
G01Y183167D02*
X248233Y183250D01*
Y183417D01*
X248400Y183500D01*
X248567Y183417D01*
Y183250D01*
X248400Y183167D01*
G01X255500Y178500D02*
Y181833D01*
G01Y181250D02*
X255167Y181583D01*
X254667Y181750D01*
X254083Y181833D01*
X253500Y181667D01*
X253000Y181333D01*
X252667Y180833D01*
X252500Y180167D01*
X252667Y179500D01*
X253000Y179000D01*
X253500Y178667D01*
X254083Y178500D01*
X254667Y178583D01*
X255167Y178833D01*
X255500Y179167D01*
G01X259600Y178500D02*
Y183500D01*
G01X113583Y185833D02*
X112750Y186667D01*
X112333Y187500D01*
Y190833D01*
X112750Y191667D01*
X113583Y192500D01*
G01X117100Y187500D02*
Y190833D01*
G01Y189917D02*
X117350Y190333D01*
X117767Y190667D01*
X118350Y190833D01*
X118933Y190667D01*
X119350Y190333D01*
X119600Y189917D01*
Y187500D01*
G01Y189917D02*
X119850Y190333D01*
X120267Y190667D01*
X120850Y190833D01*
X121433Y190667D01*
X121850Y190333D01*
X122100Y189833D01*
Y187500D01*
G01X123950Y189750D02*
X126617D01*
X126367Y190333D01*
X125950Y190667D01*
X125367Y190833D01*
X124783Y190750D01*
X124283Y190500D01*
X123950Y189917D01*
X123783Y189417D01*
Y188917D01*
X123950Y188417D01*
X124367Y187917D01*
X124867Y187583D01*
X125450Y187500D01*
X126033Y187667D01*
X126617Y188167D01*
G01X132300Y187500D02*
Y190833D01*
G01Y190250D02*
X131967Y190583D01*
X131467Y190750D01*
X130883Y190833D01*
X130300Y190667D01*
X129800Y190333D01*
X129467Y189833D01*
X129300Y189167D01*
X129467Y188500D01*
X129800Y188000D01*
X130300Y187667D01*
X130883Y187500D01*
X131467Y187583D01*
X131967Y187833D01*
X132300Y188167D01*
G01X135150Y188083D02*
X135567Y187750D01*
X136150Y187500D01*
X136650D01*
X137150Y187667D01*
X137483Y187917D01*
X137650Y188250D01*
X137567Y188750D01*
X137233Y189000D01*
X135733Y189500D01*
X135400Y190083D01*
X135567Y190500D01*
X135900Y190750D01*
X136400Y190833D01*
X136900Y190750D01*
X137400Y190500D01*
G01X140583Y190833D02*
Y188500D01*
X140917Y187917D01*
X141417Y187583D01*
X142000Y187500D01*
X142583Y187583D01*
X143083Y187917D01*
X143417Y188500D01*
G01Y187500D02*
Y190833D01*
G01X146433Y187500D02*
Y190833D01*
G01Y190167D02*
X146850Y190500D01*
X147267Y190750D01*
X147850Y190833D01*
X148267Y190750D01*
X148767Y190500D01*
G01X151950Y189750D02*
X154617D01*
X154367Y190333D01*
X153950Y190667D01*
X153367Y190833D01*
X152783Y190750D01*
X152283Y190500D01*
X151950Y189917D01*
X151783Y189417D01*
Y188917D01*
X151950Y188417D01*
X152367Y187917D01*
X152867Y187583D01*
X153450Y187500D01*
X154033Y187667D01*
X154617Y188167D01*
G01X164400Y192500D02*
Y187500D01*
G01X163233Y190833D02*
X165567D01*
G01X170000Y187500D02*
X169500Y187583D01*
X169000Y187917D01*
X168667Y188500D01*
X168500Y189167D01*
X168667Y189833D01*
X169000Y190417D01*
X169500Y190750D01*
X170000Y190833D01*
X170500Y190750D01*
X171000Y190417D01*
X171333Y189833D01*
X171417Y189167D01*
X171333Y188500D01*
X171000Y187917D01*
X170500Y187583D01*
X170000Y187500D01*
G01X174100Y185833D02*
Y190833D01*
G01Y190083D02*
X174517Y190500D01*
X174933Y190750D01*
X175600Y190833D01*
X176183Y190750D01*
X176767Y190333D01*
X177017Y189750D01*
X177100Y189167D01*
X177017Y188583D01*
X176767Y188000D01*
X176267Y187667D01*
X175600Y187500D01*
X175017Y187583D01*
X174433Y187833D01*
X174100Y188167D01*
G01X185550Y188083D02*
X185967Y187750D01*
X186550Y187500D01*
X187050D01*
X187550Y187667D01*
X187883Y187917D01*
X188050Y188250D01*
X187967Y188750D01*
X187633Y189000D01*
X186133Y189500D01*
X185800Y190083D01*
X185967Y190500D01*
X186300Y190750D01*
X186800Y190833D01*
X187300Y190750D01*
X187800Y190500D01*
G01X192400Y190833D02*
Y187500D01*
G01Y192167D02*
X192233Y192250D01*
Y192417D01*
X192400Y192500D01*
X192567Y192417D01*
Y192250D01*
X192400Y192167D01*
G01X196750Y190833D02*
X199250D01*
X196750Y187500D01*
X199250D01*
G01X202350Y189750D02*
X205017D01*
X204767Y190333D01*
X204350Y190667D01*
X203767Y190833D01*
X203183Y190750D01*
X202683Y190500D01*
X202350Y189917D01*
X202183Y189417D01*
Y188917D01*
X202350Y188417D01*
X202767Y187917D01*
X203267Y187583D01*
X203850Y187500D01*
X204433Y187667D01*
X205017Y188167D01*
G01X214800Y187500D02*
X214300Y187583D01*
X213800Y187917D01*
X213467Y188500D01*
X213300Y189167D01*
X213467Y189833D01*
X213800Y190417D01*
X214300Y190750D01*
X214800Y190833D01*
X215300Y190750D01*
X215800Y190417D01*
X216133Y189833D01*
X216217Y189167D01*
X216133Y188500D01*
X215800Y187917D01*
X215300Y187583D01*
X214800Y187500D01*
G01X219900D02*
Y191750D01*
X220067Y192167D01*
X220400Y192417D01*
X220900Y192500D01*
X221400Y192333D01*
X221650Y191917D01*
G01X220650Y190500D02*
X218983D01*
G01X229933Y187500D02*
Y192500D01*
X231933D01*
X232600Y192250D01*
X233100Y191667D01*
X233267Y191000D01*
X233100Y190333D01*
X232683Y189833D01*
X231933Y189583D01*
X229933D01*
G01X235117Y187500D02*
X237200Y192500D01*
X239283Y187500D01*
G01X238533Y189250D02*
X235867D01*
G01X240967Y187500D02*
Y192500D01*
X242633D01*
X243300Y192250D01*
X243800Y191917D01*
X244217Y191417D01*
X244550Y190833D01*
X244633Y190000D01*
X244550Y189167D01*
X244217Y188583D01*
X243800Y188083D01*
X243300Y187750D01*
X242633Y187500D01*
X240967D01*
G01X252500Y187333D02*
X255500Y192500D01*
G01X112250Y153667D02*
X112917Y153250D01*
X113667Y153000D01*
X114333D01*
X115000Y153250D01*
X115500Y153667D01*
X115750Y154250D01*
X115583Y154833D01*
X115167Y155333D01*
X114417Y155667D01*
X113417Y155833D01*
X112833Y156167D01*
X112583Y156750D01*
X112750Y157333D01*
X113167Y157750D01*
X113750Y158000D01*
X114333D01*
X114917Y157833D01*
X115417Y157417D01*
G01X119600Y153000D02*
X119100Y153083D01*
X118600Y153417D01*
X118267Y154000D01*
X118100Y154667D01*
X118267Y155333D01*
X118600Y155917D01*
X119100Y156250D01*
X119600Y156333D01*
X120100Y156250D01*
X120600Y155917D01*
X120933Y155333D01*
X121017Y154667D01*
X120933Y154000D01*
X120600Y153417D01*
X120100Y153083D01*
X119600Y153000D01*
G01X125200D02*
Y158000D01*
G01X132300D02*
Y153000D01*
G01Y153750D02*
X131967Y153333D01*
X131467Y153083D01*
X130883Y153000D01*
X130217Y153167D01*
X129717Y153583D01*
X129383Y154083D01*
X129300Y154667D01*
X129383Y155250D01*
X129717Y155750D01*
X130217Y156167D01*
X130883Y156333D01*
X131467Y156250D01*
X131883Y156083D01*
X132300Y155750D01*
G01X135150Y155250D02*
X137817D01*
X137567Y155833D01*
X137150Y156167D01*
X136567Y156333D01*
X135983Y156250D01*
X135483Y156000D01*
X135150Y155417D01*
X134983Y154917D01*
Y154417D01*
X135150Y153917D01*
X135567Y153417D01*
X136067Y153083D01*
X136650Y153000D01*
X137233Y153167D01*
X137817Y153667D01*
G01X140833Y153000D02*
Y156333D01*
G01Y155667D02*
X141250Y156000D01*
X141667Y156250D01*
X142250Y156333D01*
X142667Y156250D01*
X143167Y156000D01*
G01X150700Y153000D02*
Y156333D01*
G01Y155417D02*
X150950Y155833D01*
X151367Y156167D01*
X151950Y156333D01*
X152533Y156167D01*
X152950Y155833D01*
X153200Y155417D01*
Y153000D01*
G01Y155417D02*
X153450Y155833D01*
X153867Y156167D01*
X154450Y156333D01*
X155033Y156167D01*
X155450Y155833D01*
X155700Y155333D01*
Y153000D01*
G01X160300D02*
Y156333D01*
G01Y155750D02*
X159967Y156083D01*
X159467Y156250D01*
X158883Y156333D01*
X158300Y156167D01*
X157800Y155833D01*
X157467Y155333D01*
X157300Y154667D01*
X157467Y154000D01*
X157800Y153500D01*
X158300Y153167D01*
X158883Y153000D01*
X159467Y153083D01*
X159967Y153333D01*
X160300Y153667D01*
G01X163150Y153583D02*
X163567Y153250D01*
X164150Y153000D01*
X164650D01*
X165150Y153167D01*
X165483Y153417D01*
X165650Y153750D01*
X165567Y154250D01*
X165233Y154500D01*
X163733Y155000D01*
X163400Y155583D01*
X163567Y156000D01*
X163900Y156250D01*
X164400Y156333D01*
X164900Y156250D01*
X165400Y156000D01*
G01X168583Y153000D02*
Y158000D01*
G01X171250Y156333D02*
X168583Y154417D01*
G01X169667Y155167D02*
X171417Y153000D01*
G01X182700Y158000D02*
Y153000D01*
G01Y153750D02*
X182367Y153333D01*
X181867Y153083D01*
X181283Y153000D01*
X180617Y153167D01*
X180117Y153583D01*
X179783Y154083D01*
X179700Y154667D01*
X179783Y155250D01*
X180117Y155750D01*
X180617Y156167D01*
X181283Y156333D01*
X181867Y156250D01*
X182283Y156083D01*
X182700Y155750D01*
G01X185550Y155250D02*
X188217D01*
X187967Y155833D01*
X187550Y156167D01*
X186967Y156333D01*
X186383Y156250D01*
X185883Y156000D01*
X185550Y155417D01*
X185383Y154917D01*
Y154417D01*
X185550Y153917D01*
X185967Y153417D01*
X186467Y153083D01*
X187050Y153000D01*
X187633Y153167D01*
X188217Y153667D01*
G01X191900Y153000D02*
Y157250D01*
X192067Y157667D01*
X192400Y157917D01*
X192900Y158000D01*
X193400Y157833D01*
X193650Y157417D01*
G01X192650Y156000D02*
X190983D01*
G01X198000Y156333D02*
Y153000D01*
G01Y157667D02*
X197833Y157750D01*
Y157917D01*
X198000Y158000D01*
X198167Y157917D01*
Y157750D01*
X198000Y157667D01*
G01X202183Y153000D02*
Y156333D01*
G01Y155500D02*
X202517Y155917D01*
X203017Y156250D01*
X203683Y156333D01*
X204267Y156250D01*
X204767Y155917D01*
X205017Y155333D01*
Y153000D01*
G01X207950Y155250D02*
X210617D01*
X210367Y155833D01*
X209950Y156167D01*
X209367Y156333D01*
X208783Y156250D01*
X208283Y156000D01*
X207950Y155417D01*
X207783Y154917D01*
Y154417D01*
X207950Y153917D01*
X208367Y153417D01*
X208867Y153083D01*
X209450Y153000D01*
X210033Y153167D01*
X210617Y153667D01*
G01X218900Y151333D02*
Y156333D01*
G01Y155583D02*
X219317Y156000D01*
X219733Y156250D01*
X220400Y156333D01*
X220983Y156250D01*
X221567Y155833D01*
X221817Y155250D01*
X221900Y154667D01*
X221817Y154083D01*
X221567Y153500D01*
X221067Y153167D01*
X220400Y153000D01*
X219817Y153083D01*
X219233Y153333D01*
X218900Y153667D01*
G01X227500Y153000D02*
Y156333D01*
G01Y155750D02*
X227167Y156083D01*
X226667Y156250D01*
X226083Y156333D01*
X225500Y156167D01*
X225000Y155833D01*
X224667Y155333D01*
X224500Y154667D01*
X224667Y154000D01*
X225000Y153500D01*
X225500Y153167D01*
X226083Y153000D01*
X226667Y153083D01*
X227167Y153333D01*
X227500Y153667D01*
G01X233100Y158000D02*
Y153000D01*
G01Y153750D02*
X232767Y153333D01*
X232267Y153083D01*
X231683Y153000D01*
X231017Y153167D01*
X230517Y153583D01*
X230183Y154083D01*
X230100Y154667D01*
X230183Y155250D01*
X230517Y155750D01*
X231017Y156167D01*
X231683Y156333D01*
X232267Y156250D01*
X232683Y156083D01*
X233100Y155750D01*
G01X112333Y198000D02*
Y203000D01*
X114333D01*
X115000Y202750D01*
X115500Y202167D01*
X115667Y201500D01*
X115500Y200833D01*
X115083Y200333D01*
X114333Y200083D01*
X112333D01*
G01X117517Y198000D02*
X119600Y203000D01*
X121683Y198000D01*
G01X120933Y199750D02*
X118267D01*
G01X123367Y198000D02*
Y203000D01*
X125033D01*
X125700Y202750D01*
X126200Y202417D01*
X126617Y201917D01*
X126950Y201333D01*
X127033Y200500D01*
X126950Y199667D01*
X126617Y199083D01*
X126200Y198583D01*
X125700Y198250D01*
X125033Y198000D01*
X123367D01*
G01X135150Y198583D02*
X135567Y198250D01*
X136150Y198000D01*
X136650D01*
X137150Y198167D01*
X137483Y198417D01*
X137650Y198750D01*
X137567Y199250D01*
X137233Y199500D01*
X135733Y200000D01*
X135400Y200583D01*
X135567Y201000D01*
X135900Y201250D01*
X136400Y201333D01*
X136900Y201250D01*
X137400Y201000D01*
G01X142000Y201333D02*
Y198000D01*
G01Y202667D02*
X141833Y202750D01*
Y202917D01*
X142000Y203000D01*
X142167Y202917D01*
Y202750D01*
X142000Y202667D01*
G01X146350Y201333D02*
X148850D01*
X146350Y198000D01*
X148850D01*
G01X151950Y200250D02*
X154617D01*
X154367Y200833D01*
X153950Y201167D01*
X153367Y201333D01*
X152783Y201250D01*
X152283Y201000D01*
X151950Y200417D01*
X151783Y199917D01*
Y199417D01*
X151950Y198917D01*
X152367Y198417D01*
X152867Y198083D01*
X153450Y198000D01*
X154033Y198167D01*
X154617Y198667D01*
G01X114000Y231500D02*
Y226500D01*
G01X112083Y231500D02*
X115917D01*
G01X118433Y226500D02*
Y229833D01*
G01Y229167D02*
X118850Y229500D01*
X119267Y229750D01*
X119850Y229833D01*
X120267Y229750D01*
X120767Y229500D01*
G01X126700Y226500D02*
Y229833D01*
G01Y229250D02*
X126367Y229583D01*
X125867Y229750D01*
X125283Y229833D01*
X124700Y229667D01*
X124200Y229333D01*
X123867Y228833D01*
X123700Y228167D01*
X123867Y227500D01*
X124200Y227000D01*
X124700Y226667D01*
X125283Y226500D01*
X125867Y226583D01*
X126367Y226833D01*
X126700Y227167D01*
G01X132133Y229417D02*
X131550Y229750D01*
X131050Y229833D01*
X130383Y229667D01*
X129883Y229333D01*
X129550Y228750D01*
X129467Y228167D01*
X129550Y227583D01*
X129883Y227083D01*
X130383Y226667D01*
X131050Y226500D01*
X131633Y226667D01*
X132133Y227000D01*
G01X135150Y228750D02*
X137817D01*
X137567Y229333D01*
X137150Y229667D01*
X136567Y229833D01*
X135983Y229750D01*
X135483Y229500D01*
X135150Y228917D01*
X134983Y228417D01*
Y227917D01*
X135150Y227417D01*
X135567Y226917D01*
X136067Y226583D01*
X136650Y226500D01*
X137233Y226667D01*
X137817Y227167D01*
G01X145517Y229833D02*
X146517Y226500D01*
X147600Y229833D01*
X148683Y226500D01*
X149683Y229833D01*
G01X153200D02*
Y226500D01*
G01Y231167D02*
X153033Y231250D01*
Y231417D01*
X153200Y231500D01*
X153367Y231417D01*
Y231250D01*
X153200Y231167D01*
G01X160300Y231500D02*
Y226500D01*
G01Y227250D02*
X159967Y226833D01*
X159467Y226583D01*
X158883Y226500D01*
X158217Y226667D01*
X157717Y227083D01*
X157383Y227583D01*
X157300Y228167D01*
X157383Y228750D01*
X157717Y229250D01*
X158217Y229667D01*
X158883Y229833D01*
X159467Y229750D01*
X159883Y229583D01*
X160300Y229250D01*
G01X164400Y231500D02*
Y226500D01*
G01X163233Y229833D02*
X165567D01*
G01X168583Y226500D02*
Y231500D01*
G01Y229083D02*
X169000Y229500D01*
X169417Y229750D01*
X170083Y229833D01*
X170583Y229750D01*
X171167Y229417D01*
X171417Y228917D01*
Y226500D01*
G01X103500Y207000D02*
X694500D01*
G01X112333Y258000D02*
Y263000D01*
X114417D01*
X115083Y262750D01*
X115500Y262417D01*
X115667Y261750D01*
X115500Y261083D01*
X115000Y260667D01*
X114417Y260417D01*
X112333D01*
G01X114417D02*
X115667Y258000D01*
G01X118350Y260250D02*
X121017D01*
X120767Y260833D01*
X120350Y261167D01*
X119767Y261333D01*
X119183Y261250D01*
X118683Y261000D01*
X118350Y260417D01*
X118183Y259917D01*
Y259417D01*
X118350Y258917D01*
X118767Y258417D01*
X119267Y258083D01*
X119850Y258000D01*
X120433Y258167D01*
X121017Y258667D01*
G01X125200Y258000D02*
Y263000D01*
G01X132300Y258000D02*
Y261333D01*
G01Y260750D02*
X131967Y261083D01*
X131467Y261250D01*
X130883Y261333D01*
X130300Y261167D01*
X129800Y260833D01*
X129467Y260333D01*
X129300Y259667D01*
X129467Y259000D01*
X129800Y258500D01*
X130300Y258167D01*
X130883Y258000D01*
X131467Y258083D01*
X131967Y258333D01*
X132300Y258667D01*
G01X136400Y263000D02*
Y258000D01*
G01X135233Y261333D02*
X137567D01*
G01X142000D02*
Y258000D01*
G01Y262667D02*
X141833Y262750D01*
Y262917D01*
X142000Y263000D01*
X142167Y262917D01*
Y262750D01*
X142000Y262667D01*
G01X146100Y261333D02*
X147600Y258000D01*
X149100Y261333D01*
G01X151950Y260250D02*
X154617D01*
X154367Y260833D01*
X153950Y261167D01*
X153367Y261333D01*
X152783Y261250D01*
X152283Y261000D01*
X151950Y260417D01*
X151783Y259917D01*
Y259417D01*
X151950Y258917D01*
X152367Y258417D01*
X152867Y258083D01*
X153450Y258000D01*
X154033Y258167D01*
X154617Y258667D01*
G01X162900Y256333D02*
Y261333D01*
G01Y260583D02*
X163317Y261000D01*
X163733Y261250D01*
X164400Y261333D01*
X164983Y261250D01*
X165567Y260833D01*
X165817Y260250D01*
X165900Y259667D01*
X165817Y259083D01*
X165567Y258500D01*
X165067Y258167D01*
X164400Y258000D01*
X163817Y258083D01*
X163233Y258333D01*
X162900Y258667D01*
G01X170000Y258000D02*
X169500Y258083D01*
X169000Y258417D01*
X168667Y259000D01*
X168500Y259667D01*
X168667Y260333D01*
X169000Y260917D01*
X169500Y261250D01*
X170000Y261333D01*
X170500Y261250D01*
X171000Y260917D01*
X171333Y260333D01*
X171417Y259667D01*
X171333Y259000D01*
X171000Y258417D01*
X170500Y258083D01*
X170000Y258000D01*
G01X174350Y258583D02*
X174767Y258250D01*
X175350Y258000D01*
X175850D01*
X176350Y258167D01*
X176683Y258417D01*
X176850Y258750D01*
X176767Y259250D01*
X176433Y259500D01*
X174933Y260000D01*
X174600Y260583D01*
X174767Y261000D01*
X175100Y261250D01*
X175600Y261333D01*
X176100Y261250D01*
X176600Y261000D01*
G01X181200Y261333D02*
Y258000D01*
G01Y262667D02*
X181033Y262750D01*
Y262917D01*
X181200Y263000D01*
X181367Y262917D01*
Y262750D01*
X181200Y262667D01*
G01X186800Y263000D02*
Y258000D01*
G01X185633Y261333D02*
X187967D01*
G01X192400D02*
Y258000D01*
G01Y262667D02*
X192233Y262750D01*
Y262917D01*
X192400Y263000D01*
X192567Y262917D01*
Y262750D01*
X192400Y262667D01*
G01X198000Y258000D02*
X197500Y258083D01*
X197000Y258417D01*
X196667Y259000D01*
X196500Y259667D01*
X196667Y260333D01*
X197000Y260917D01*
X197500Y261250D01*
X198000Y261333D01*
X198500Y261250D01*
X199000Y260917D01*
X199333Y260333D01*
X199417Y259667D01*
X199333Y259000D01*
X199000Y258417D01*
X198500Y258083D01*
X198000Y258000D01*
G01X202183D02*
Y261333D01*
G01Y260500D02*
X202517Y260917D01*
X203017Y261250D01*
X203683Y261333D01*
X204267Y261250D01*
X204767Y260917D01*
X205017Y260333D01*
Y258000D01*
G01X114000Y290000D02*
Y285000D01*
G01X112833Y288333D02*
X115167D01*
G01X118183Y285000D02*
Y290000D01*
G01Y287583D02*
X118600Y288000D01*
X119017Y288250D01*
X119683Y288333D01*
X120183Y288250D01*
X120767Y287917D01*
X121017Y287417D01*
Y285000D01*
G01X125200Y288333D02*
Y285000D01*
G01Y289667D02*
X125033Y289750D01*
Y289917D01*
X125200Y290000D01*
X125367Y289917D01*
Y289750D01*
X125200Y289667D01*
G01X132133Y287917D02*
X131550Y288250D01*
X131050Y288333D01*
X130383Y288167D01*
X129883Y287833D01*
X129550Y287250D01*
X129467Y286667D01*
X129550Y286083D01*
X129883Y285583D01*
X130383Y285167D01*
X131050Y285000D01*
X131633Y285167D01*
X132133Y285500D01*
G01X134983Y285000D02*
Y290000D01*
G01X137650Y288333D02*
X134983Y286417D01*
G01X136067Y287167D02*
X137817Y285000D01*
G01X140583D02*
Y288333D01*
G01Y287500D02*
X140917Y287917D01*
X141417Y288250D01*
X142083Y288333D01*
X142667Y288250D01*
X143167Y287917D01*
X143417Y287333D01*
Y285000D01*
G01X146350Y287250D02*
X149017D01*
X148767Y287833D01*
X148350Y288167D01*
X147767Y288333D01*
X147183Y288250D01*
X146683Y288000D01*
X146350Y287417D01*
X146183Y286917D01*
Y286417D01*
X146350Y285917D01*
X146767Y285417D01*
X147267Y285083D01*
X147850Y285000D01*
X148433Y285167D01*
X149017Y285667D01*
G01X151950Y285583D02*
X152367Y285250D01*
X152950Y285000D01*
X153450D01*
X153950Y285167D01*
X154283Y285417D01*
X154450Y285750D01*
X154367Y286250D01*
X154033Y286500D01*
X152533Y287000D01*
X152200Y287583D01*
X152367Y288000D01*
X152700Y288250D01*
X153200Y288333D01*
X153700Y288250D01*
X154200Y288000D01*
G01X157550Y285583D02*
X157967Y285250D01*
X158550Y285000D01*
X159050D01*
X159550Y285167D01*
X159883Y285417D01*
X160050Y285750D01*
X159967Y286250D01*
X159633Y286500D01*
X158133Y287000D01*
X157800Y287583D01*
X157967Y288000D01*
X158300Y288250D01*
X158800Y288333D01*
X159300Y288250D01*
X159800Y288000D01*
G01X171500Y285000D02*
Y288333D01*
G01Y287750D02*
X171167Y288083D01*
X170667Y288250D01*
X170083Y288333D01*
X169500Y288167D01*
X169000Y287833D01*
X168667Y287333D01*
X168500Y286667D01*
X168667Y286000D01*
X169000Y285500D01*
X169500Y285167D01*
X170083Y285000D01*
X170667Y285083D01*
X171167Y285333D01*
X171500Y285667D01*
G01X175100Y285000D02*
Y289250D01*
X175267Y289667D01*
X175600Y289917D01*
X176100Y290000D01*
X176600Y289833D01*
X176850Y289417D01*
G01X175850Y288000D02*
X174183D01*
G01X181200Y290000D02*
Y285000D01*
G01X180033Y288333D02*
X182367D01*
G01X185550Y287250D02*
X188217D01*
X187967Y287833D01*
X187550Y288167D01*
X186967Y288333D01*
X186383Y288250D01*
X185883Y288000D01*
X185550Y287417D01*
X185383Y286917D01*
Y286417D01*
X185550Y285917D01*
X185967Y285417D01*
X186467Y285083D01*
X187050Y285000D01*
X187633Y285167D01*
X188217Y285667D01*
G01X191233Y285000D02*
Y288333D01*
G01Y287667D02*
X191650Y288000D01*
X192067Y288250D01*
X192650Y288333D01*
X193067Y288250D01*
X193567Y288000D01*
G01X202100Y283333D02*
Y288333D01*
G01Y287583D02*
X202517Y288000D01*
X202933Y288250D01*
X203600Y288333D01*
X204183Y288250D01*
X204767Y287833D01*
X205017Y287250D01*
X205100Y286667D01*
X205017Y286083D01*
X204767Y285500D01*
X204267Y285167D01*
X203600Y285000D01*
X203017Y285083D01*
X202433Y285333D01*
X202100Y285667D01*
G01X209200Y285000D02*
Y290000D01*
G01X216300Y285000D02*
Y288333D01*
G01Y287750D02*
X215967Y288083D01*
X215467Y288250D01*
X214883Y288333D01*
X214300Y288167D01*
X213800Y287833D01*
X213467Y287333D01*
X213300Y286667D01*
X213467Y286000D01*
X213800Y285500D01*
X214300Y285167D01*
X214883Y285000D01*
X215467Y285083D01*
X215967Y285333D01*
X216300Y285667D01*
G01X220400Y290000D02*
Y285000D01*
G01X219233Y288333D02*
X221567D01*
G01X226000D02*
Y285000D01*
G01Y289667D02*
X225833Y289750D01*
Y289917D01*
X226000Y290000D01*
X226167Y289917D01*
Y289750D01*
X226000Y289667D01*
G01X230183Y285000D02*
Y288333D01*
G01Y287500D02*
X230517Y287917D01*
X231017Y288250D01*
X231683Y288333D01*
X232267Y288250D01*
X232767Y287917D01*
X233017Y287333D01*
Y285000D01*
G01X236033Y283750D02*
X236617Y283417D01*
X237283Y283333D01*
X237867Y283417D01*
X238367Y283833D01*
X238700Y284417D01*
Y288333D01*
G01Y287667D02*
X238367Y288000D01*
X237867Y288250D01*
X237283Y288333D01*
X236617Y288167D01*
X236200Y287833D01*
X235867Y287250D01*
X235700Y286667D01*
X235783Y286167D01*
X236117Y285583D01*
X236617Y285167D01*
X237283Y285000D01*
X237783Y285083D01*
X238367Y285417D01*
X238700Y285750D01*
G01X115667Y297000D02*
X112333D01*
Y302000D01*
X115667D01*
G01X114333Y299583D02*
X112333D01*
G01X118350Y300333D02*
X120850Y297000D01*
G01Y300333D02*
X118350Y297000D01*
G01X125200Y302000D02*
Y297000D01*
G01X124033Y300333D02*
X126367D01*
G01X129550Y299250D02*
X132217D01*
X131967Y299833D01*
X131550Y300167D01*
X130967Y300333D01*
X130383Y300250D01*
X129883Y300000D01*
X129550Y299417D01*
X129383Y298917D01*
Y298417D01*
X129550Y297917D01*
X129967Y297417D01*
X130467Y297083D01*
X131050Y297000D01*
X131633Y297167D01*
X132217Y297667D01*
G01X135233Y297000D02*
Y300333D01*
G01Y299667D02*
X135650Y300000D01*
X136067Y300250D01*
X136650Y300333D01*
X137067Y300250D01*
X137567Y300000D01*
G01X140583Y297000D02*
Y300333D01*
G01Y299500D02*
X140917Y299917D01*
X141417Y300250D01*
X142083Y300333D01*
X142667Y300250D01*
X143167Y299917D01*
X143417Y299333D01*
Y297000D01*
G01X149100D02*
Y300333D01*
G01Y299750D02*
X148767Y300083D01*
X148267Y300250D01*
X147683Y300333D01*
X147100Y300167D01*
X146600Y299833D01*
X146267Y299333D01*
X146100Y298667D01*
X146267Y298000D01*
X146600Y297500D01*
X147100Y297167D01*
X147683Y297000D01*
X148267Y297083D01*
X148767Y297333D01*
X149100Y297667D01*
G01X153200Y297000D02*
Y302000D01*
G01X165733Y299917D02*
X165150Y300250D01*
X164650Y300333D01*
X163983Y300167D01*
X163483Y299833D01*
X163150Y299250D01*
X163067Y298667D01*
X163150Y298083D01*
X163483Y297583D01*
X163983Y297167D01*
X164650Y297000D01*
X165233Y297167D01*
X165733Y297500D01*
G01X170000Y297000D02*
X169500Y297083D01*
X169000Y297417D01*
X168667Y298000D01*
X168500Y298667D01*
X168667Y299333D01*
X169000Y299917D01*
X169500Y300250D01*
X170000Y300333D01*
X170500Y300250D01*
X171000Y299917D01*
X171333Y299333D01*
X171417Y298667D01*
X171333Y298000D01*
X171000Y297417D01*
X170500Y297083D01*
X170000Y297000D01*
G01X174183D02*
Y300333D01*
G01Y299500D02*
X174517Y299917D01*
X175017Y300250D01*
X175683Y300333D01*
X176267Y300250D01*
X176767Y299917D01*
X177017Y299333D01*
Y297000D01*
G01X182700Y302000D02*
Y297000D01*
G01Y297750D02*
X182367Y297333D01*
X181867Y297083D01*
X181283Y297000D01*
X180617Y297167D01*
X180117Y297583D01*
X179783Y298083D01*
X179700Y298667D01*
X179783Y299250D01*
X180117Y299750D01*
X180617Y300167D01*
X181283Y300333D01*
X181867Y300250D01*
X182283Y300083D01*
X182700Y299750D01*
G01X185383Y300333D02*
Y298000D01*
X185717Y297417D01*
X186217Y297083D01*
X186800Y297000D01*
X187383Y297083D01*
X187883Y297417D01*
X188217Y298000D01*
G01Y297000D02*
Y300333D01*
G01X193733Y299917D02*
X193150Y300250D01*
X192650Y300333D01*
X191983Y300167D01*
X191483Y299833D01*
X191150Y299250D01*
X191067Y298667D01*
X191150Y298083D01*
X191483Y297583D01*
X191983Y297167D01*
X192650Y297000D01*
X193233Y297167D01*
X193733Y297500D01*
G01X198000Y302000D02*
Y297000D01*
G01X196833Y300333D02*
X199167D01*
G01X203600Y297000D02*
X203100Y297083D01*
X202600Y297417D01*
X202267Y298000D01*
X202100Y298667D01*
X202267Y299333D01*
X202600Y299917D01*
X203100Y300250D01*
X203600Y300333D01*
X204100Y300250D01*
X204600Y299917D01*
X204933Y299333D01*
X205017Y298667D01*
X204933Y298000D01*
X204600Y297417D01*
X204100Y297083D01*
X203600Y297000D01*
G01X208033D02*
Y300333D01*
G01Y299667D02*
X208450Y300000D01*
X208867Y300250D01*
X209450Y300333D01*
X209867Y300250D01*
X210367Y300000D01*
G01X112333Y401000D02*
Y406000D01*
X114333D01*
X115000Y405750D01*
X115500Y405167D01*
X115667Y404500D01*
X115500Y403833D01*
X115083Y403333D01*
X114333Y403083D01*
X112333D01*
G01X119600Y406000D02*
Y401000D01*
G01X117683Y406000D02*
X121517D01*
G01X123450Y401000D02*
Y406000D01*
G01X126950D02*
Y401000D01*
G01Y403500D02*
X123450D01*
G01X135233Y401000D02*
Y404333D01*
G01Y403667D02*
X135650Y404000D01*
X136067Y404250D01*
X136650Y404333D01*
X137067Y404250D01*
X137567Y404000D01*
G01X140750Y403250D02*
X143417D01*
X143167Y403833D01*
X142750Y404167D01*
X142167Y404333D01*
X141583Y404250D01*
X141083Y404000D01*
X140750Y403417D01*
X140583Y402917D01*
Y402417D01*
X140750Y401917D01*
X141167Y401417D01*
X141667Y401083D01*
X142250Y401000D01*
X142833Y401167D01*
X143417Y401667D01*
G01X146433Y399750D02*
X147017Y399417D01*
X147683Y399333D01*
X148267Y399417D01*
X148767Y399833D01*
X149100Y400417D01*
Y404333D01*
G01Y403667D02*
X148767Y404000D01*
X148267Y404250D01*
X147683Y404333D01*
X147017Y404167D01*
X146600Y403833D01*
X146267Y403250D01*
X146100Y402667D01*
X146183Y402167D01*
X146517Y401583D01*
X147017Y401167D01*
X147683Y401000D01*
X148183Y401083D01*
X148767Y401417D01*
X149100Y401750D01*
G01X153200Y404333D02*
Y401000D01*
G01Y405667D02*
X153033Y405750D01*
Y405917D01*
X153200Y406000D01*
X153367Y405917D01*
Y405750D01*
X153200Y405667D01*
G01X157550Y401583D02*
X157967Y401250D01*
X158550Y401000D01*
X159050D01*
X159550Y401167D01*
X159883Y401417D01*
X160050Y401750D01*
X159967Y402250D01*
X159633Y402500D01*
X158133Y403000D01*
X157800Y403583D01*
X157967Y404000D01*
X158300Y404250D01*
X158800Y404333D01*
X159300Y404250D01*
X159800Y404000D01*
G01X164400Y406000D02*
Y401000D01*
G01X163233Y404333D02*
X165567D01*
G01X168833Y401000D02*
Y404333D01*
G01Y403667D02*
X169250Y404000D01*
X169667Y404250D01*
X170250Y404333D01*
X170667Y404250D01*
X171167Y404000D01*
G01X177100Y401000D02*
Y404333D01*
G01Y403750D02*
X176767Y404083D01*
X176267Y404250D01*
X175683Y404333D01*
X175100Y404167D01*
X174600Y403833D01*
X174267Y403333D01*
X174100Y402667D01*
X174267Y402000D01*
X174600Y401500D01*
X175100Y401167D01*
X175683Y401000D01*
X176267Y401083D01*
X176767Y401333D01*
X177100Y401667D01*
G01X181200Y406000D02*
Y401000D01*
G01X180033Y404333D02*
X182367D01*
G01X186800D02*
Y401000D01*
G01Y405667D02*
X186633Y405750D01*
Y405917D01*
X186800Y406000D01*
X186967Y405917D01*
Y405750D01*
X186800Y405667D01*
G01X192400Y401000D02*
X191900Y401083D01*
X191400Y401417D01*
X191067Y402000D01*
X190900Y402667D01*
X191067Y403333D01*
X191400Y403917D01*
X191900Y404250D01*
X192400Y404333D01*
X192900Y404250D01*
X193400Y403917D01*
X193733Y403333D01*
X193817Y402667D01*
X193733Y402000D01*
X193400Y401417D01*
X192900Y401083D01*
X192400Y401000D01*
G01X196583D02*
Y404333D01*
G01Y403500D02*
X196917Y403917D01*
X197417Y404250D01*
X198083Y404333D01*
X198667Y404250D01*
X199167Y403917D01*
X199417Y403333D01*
Y401000D01*
G01X112167Y429500D02*
Y434500D01*
X113833D01*
X114500Y434250D01*
X115000Y433917D01*
X115417Y433417D01*
X115750Y432833D01*
X115833Y432000D01*
X115750Y431167D01*
X115417Y430583D01*
X115000Y430083D01*
X114500Y429750D01*
X113833Y429500D01*
X112167D01*
G01X118350Y431750D02*
X121017D01*
X120767Y432333D01*
X120350Y432667D01*
X119767Y432833D01*
X119183Y432750D01*
X118683Y432500D01*
X118350Y431917D01*
X118183Y431417D01*
Y430917D01*
X118350Y430417D01*
X118767Y429917D01*
X119267Y429583D01*
X119850Y429500D01*
X120433Y429667D01*
X121017Y430167D01*
G01X123700Y427833D02*
Y432833D01*
G01Y432083D02*
X124117Y432500D01*
X124533Y432750D01*
X125200Y432833D01*
X125783Y432750D01*
X126367Y432333D01*
X126617Y431750D01*
X126700Y431167D01*
X126617Y430583D01*
X126367Y430000D01*
X125867Y429667D01*
X125200Y429500D01*
X124617Y429583D01*
X124033Y429833D01*
X123700Y430167D01*
G01X130800Y434500D02*
Y429500D01*
G01X129633Y432833D02*
X131967D01*
G01X134983Y429500D02*
Y434500D01*
G01Y432083D02*
X135400Y432500D01*
X135817Y432750D01*
X136483Y432833D01*
X136983Y432750D01*
X137567Y432417D01*
X137817Y431917D01*
Y429500D01*
G01X148933Y432417D02*
X148350Y432750D01*
X147850Y432833D01*
X147183Y432667D01*
X146683Y432333D01*
X146350Y431750D01*
X146267Y431167D01*
X146350Y430583D01*
X146683Y430083D01*
X147183Y429667D01*
X147850Y429500D01*
X148433Y429667D01*
X148933Y430000D01*
G01X153200Y429500D02*
X152700Y429583D01*
X152200Y429917D01*
X151867Y430500D01*
X151700Y431167D01*
X151867Y431833D01*
X152200Y432417D01*
X152700Y432750D01*
X153200Y432833D01*
X153700Y432750D01*
X154200Y432417D01*
X154533Y431833D01*
X154617Y431167D01*
X154533Y430500D01*
X154200Y429917D01*
X153700Y429583D01*
X153200Y429500D01*
G01X157383D02*
Y432833D01*
G01Y432000D02*
X157717Y432417D01*
X158217Y432750D01*
X158883Y432833D01*
X159467Y432750D01*
X159967Y432417D01*
X160217Y431833D01*
Y429500D01*
G01X164400Y434500D02*
Y429500D01*
G01X163233Y432833D02*
X165567D01*
G01X168833Y429500D02*
Y432833D01*
G01Y432167D02*
X169250Y432500D01*
X169667Y432750D01*
X170250Y432833D01*
X170667Y432750D01*
X171167Y432500D01*
G01X175600Y429500D02*
X175100Y429583D01*
X174600Y429917D01*
X174267Y430500D01*
X174100Y431167D01*
X174267Y431833D01*
X174600Y432417D01*
X175100Y432750D01*
X175600Y432833D01*
X176100Y432750D01*
X176600Y432417D01*
X176933Y431833D01*
X177017Y431167D01*
X176933Y430500D01*
X176600Y429917D01*
X176100Y429583D01*
X175600Y429500D01*
G01X181200D02*
Y434500D01*
G01X190983Y429500D02*
Y434500D01*
G01Y432083D02*
X191400Y432500D01*
X191817Y432750D01*
X192483Y432833D01*
X192983Y432750D01*
X193567Y432417D01*
X193817Y431917D01*
Y429500D01*
G01X198000D02*
X197500Y429583D01*
X197000Y429917D01*
X196667Y430500D01*
X196500Y431167D01*
X196667Y431833D01*
X197000Y432417D01*
X197500Y432750D01*
X198000Y432833D01*
X198500Y432750D01*
X199000Y432417D01*
X199333Y431833D01*
X199417Y431167D01*
X199333Y430500D01*
X199000Y429917D01*
X198500Y429583D01*
X198000Y429500D01*
G01X203600D02*
Y434500D01*
G01X207950Y431750D02*
X210617D01*
X210367Y432333D01*
X209950Y432667D01*
X209367Y432833D01*
X208783Y432750D01*
X208283Y432500D01*
X207950Y431917D01*
X207783Y431417D01*
Y430917D01*
X207950Y430417D01*
X208367Y429917D01*
X208867Y429583D01*
X209450Y429500D01*
X210033Y429667D01*
X210617Y430167D01*
G01X112333Y451500D02*
Y456500D01*
X114417D01*
X115083Y456250D01*
X115500Y455917D01*
X115667Y455250D01*
X115500Y454583D01*
X115000Y454167D01*
X114417Y453917D01*
X112333D01*
G01X114417D02*
X115667Y451500D01*
G01X119600D02*
X119100Y451583D01*
X118600Y451917D01*
X118267Y452500D01*
X118100Y453167D01*
X118267Y453833D01*
X118600Y454417D01*
X119100Y454750D01*
X119600Y454833D01*
X120100Y454750D01*
X120600Y454417D01*
X120933Y453833D01*
X121017Y453167D01*
X120933Y452500D01*
X120600Y451917D01*
X120100Y451583D01*
X119600Y451500D01*
G01X123783Y454833D02*
Y452500D01*
X124117Y451917D01*
X124617Y451583D01*
X125200Y451500D01*
X125783Y451583D01*
X126283Y451917D01*
X126617Y452500D01*
G01Y451500D02*
Y454833D01*
G01X129633Y450250D02*
X130217Y449917D01*
X130883Y449833D01*
X131467Y449917D01*
X131967Y450333D01*
X132300Y450917D01*
Y454833D01*
G01Y454167D02*
X131967Y454500D01*
X131467Y454750D01*
X130883Y454833D01*
X130217Y454667D01*
X129800Y454333D01*
X129467Y453750D01*
X129300Y453167D01*
X129383Y452667D01*
X129717Y452083D01*
X130217Y451667D01*
X130883Y451500D01*
X131383Y451583D01*
X131967Y451917D01*
X132300Y452250D01*
G01X134983Y451500D02*
Y456500D01*
G01Y454083D02*
X135400Y454500D01*
X135817Y454750D01*
X136483Y454833D01*
X136983Y454750D01*
X137567Y454417D01*
X137817Y453917D01*
Y451500D01*
G01X140583D02*
Y454833D01*
G01Y454000D02*
X140917Y454417D01*
X141417Y454750D01*
X142083Y454833D01*
X142667Y454750D01*
X143167Y454417D01*
X143417Y453833D01*
Y451500D01*
G01X146350Y453750D02*
X149017D01*
X148767Y454333D01*
X148350Y454667D01*
X147767Y454833D01*
X147183Y454750D01*
X146683Y454500D01*
X146350Y453917D01*
X146183Y453417D01*
Y452917D01*
X146350Y452417D01*
X146767Y451917D01*
X147267Y451583D01*
X147850Y451500D01*
X148433Y451667D01*
X149017Y452167D01*
G01X151950Y452083D02*
X152367Y451750D01*
X152950Y451500D01*
X153450D01*
X153950Y451667D01*
X154283Y451917D01*
X154450Y452250D01*
X154367Y452750D01*
X154033Y453000D01*
X152533Y453500D01*
X152200Y454083D01*
X152367Y454500D01*
X152700Y454750D01*
X153200Y454833D01*
X153700Y454750D01*
X154200Y454500D01*
G01X157550Y452083D02*
X157967Y451750D01*
X158550Y451500D01*
X159050D01*
X159550Y451667D01*
X159883Y451917D01*
X160050Y452250D01*
X159967Y452750D01*
X159633Y453000D01*
X158133Y453500D01*
X157800Y454083D01*
X157967Y454500D01*
X158300Y454750D01*
X158800Y454833D01*
X159300Y454750D01*
X159800Y454500D01*
G01X103500Y445500D02*
X694500D01*
G01X104000Y460500D02*
X694500D01*
G01X103500Y418500D02*
X694500D01*
G01X112250Y525000D02*
Y530000D01*
G01X115750D02*
Y525000D01*
G01Y527500D02*
X112250D01*
G01X119600Y525000D02*
X119100Y525083D01*
X118600Y525417D01*
X118267Y526000D01*
X118100Y526667D01*
X118267Y527333D01*
X118600Y527917D01*
X119100Y528250D01*
X119600Y528333D01*
X120100Y528250D01*
X120600Y527917D01*
X120933Y527333D01*
X121017Y526667D01*
X120933Y526000D01*
X120600Y525417D01*
X120100Y525083D01*
X119600Y525000D01*
G01X125200D02*
Y530000D01*
G01X129550Y527250D02*
X132217D01*
X131967Y527833D01*
X131550Y528167D01*
X130967Y528333D01*
X130383Y528250D01*
X129883Y528000D01*
X129550Y527417D01*
X129383Y526917D01*
Y526417D01*
X129550Y525917D01*
X129967Y525417D01*
X130467Y525083D01*
X131050Y525000D01*
X131633Y525167D01*
X132217Y525667D01*
G01X140750Y525583D02*
X141167Y525250D01*
X141750Y525000D01*
X142250D01*
X142750Y525167D01*
X143083Y525417D01*
X143250Y525750D01*
X143167Y526250D01*
X142833Y526500D01*
X141333Y527000D01*
X141000Y527583D01*
X141167Y528000D01*
X141500Y528250D01*
X142000Y528333D01*
X142500Y528250D01*
X143000Y528000D01*
G01X147600Y528333D02*
Y525000D01*
G01Y529667D02*
X147433Y529750D01*
Y529917D01*
X147600Y530000D01*
X147767Y529917D01*
Y529750D01*
X147600Y529667D01*
G01X151950Y528333D02*
X154450D01*
X151950Y525000D01*
X154450D01*
G01X157550Y527250D02*
X160217D01*
X159967Y527833D01*
X159550Y528167D01*
X158967Y528333D01*
X158383Y528250D01*
X157883Y528000D01*
X157550Y527417D01*
X157383Y526917D01*
Y526417D01*
X157550Y525917D01*
X157967Y525417D01*
X158467Y525083D01*
X159050Y525000D01*
X159633Y525167D01*
X160217Y525667D01*
G01X112250Y600000D02*
Y605000D01*
G01X115750D02*
Y600000D01*
G01Y602500D02*
X112250D01*
G01X119600Y600000D02*
X119100Y600083D01*
X118600Y600417D01*
X118267Y601000D01*
X118100Y601667D01*
X118267Y602333D01*
X118600Y602917D01*
X119100Y603250D01*
X119600Y603333D01*
X120100Y603250D01*
X120600Y602917D01*
X120933Y602333D01*
X121017Y601667D01*
X120933Y601000D01*
X120600Y600417D01*
X120100Y600083D01*
X119600Y600000D01*
G01X125200D02*
Y605000D01*
G01X129550Y602250D02*
X132217D01*
X131967Y602833D01*
X131550Y603167D01*
X130967Y603333D01*
X130383Y603250D01*
X129883Y603000D01*
X129550Y602417D01*
X129383Y601917D01*
Y601417D01*
X129550Y600917D01*
X129967Y600417D01*
X130467Y600083D01*
X131050Y600000D01*
X131633Y600167D01*
X132217Y600667D01*
G01X140500Y598333D02*
Y603333D01*
G01Y602583D02*
X140917Y603000D01*
X141333Y603250D01*
X142000Y603333D01*
X142583Y603250D01*
X143167Y602833D01*
X143417Y602250D01*
X143500Y601667D01*
X143417Y601083D01*
X143167Y600500D01*
X142667Y600167D01*
X142000Y600000D01*
X141417Y600083D01*
X140833Y600333D01*
X140500Y600667D01*
G01X147600Y600000D02*
X147100Y600083D01*
X146600Y600417D01*
X146267Y601000D01*
X146100Y601667D01*
X146267Y602333D01*
X146600Y602917D01*
X147100Y603250D01*
X147600Y603333D01*
X148100Y603250D01*
X148600Y602917D01*
X148933Y602333D01*
X149017Y601667D01*
X148933Y601000D01*
X148600Y600417D01*
X148100Y600083D01*
X147600Y600000D01*
G01X151950Y600583D02*
X152367Y600250D01*
X152950Y600000D01*
X153450D01*
X153950Y600167D01*
X154283Y600417D01*
X154450Y600750D01*
X154367Y601250D01*
X154033Y601500D01*
X152533Y602000D01*
X152200Y602583D01*
X152367Y603000D01*
X152700Y603250D01*
X153200Y603333D01*
X153700Y603250D01*
X154200Y603000D01*
G01X158800Y603333D02*
Y600000D01*
G01Y604667D02*
X158633Y604750D01*
Y604917D01*
X158800Y605000D01*
X158967Y604917D01*
Y604750D01*
X158800Y604667D01*
G01X164400Y605000D02*
Y600000D01*
G01X163233Y603333D02*
X165567D01*
G01X170000D02*
Y600000D01*
G01Y604667D02*
X169833Y604750D01*
Y604917D01*
X170000Y605000D01*
X170167Y604917D01*
Y604750D01*
X170000Y604667D01*
G01X175600Y600000D02*
X175100Y600083D01*
X174600Y600417D01*
X174267Y601000D01*
X174100Y601667D01*
X174267Y602333D01*
X174600Y602917D01*
X175100Y603250D01*
X175600Y603333D01*
X176100Y603250D01*
X176600Y602917D01*
X176933Y602333D01*
X177017Y601667D01*
X176933Y601000D01*
X176600Y600417D01*
X176100Y600083D01*
X175600Y600000D01*
G01X179783D02*
Y603333D01*
G01Y602500D02*
X180117Y602917D01*
X180617Y603250D01*
X181283Y603333D01*
X181867Y603250D01*
X182367Y602917D01*
X182617Y602333D01*
Y600000D01*
G01X192400Y605000D02*
Y600000D01*
G01X191233Y603333D02*
X193567D01*
G01X198000Y600000D02*
X197500Y600083D01*
X197000Y600417D01*
X196667Y601000D01*
X196500Y601667D01*
X196667Y602333D01*
X197000Y602917D01*
X197500Y603250D01*
X198000Y603333D01*
X198500Y603250D01*
X199000Y602917D01*
X199333Y602333D01*
X199417Y601667D01*
X199333Y601000D01*
X199000Y600417D01*
X198500Y600083D01*
X198000Y600000D01*
G01X203600D02*
Y605000D01*
G01X207950Y602250D02*
X210617D01*
X210367Y602833D01*
X209950Y603167D01*
X209367Y603333D01*
X208783Y603250D01*
X208283Y603000D01*
X207950Y602417D01*
X207783Y601917D01*
Y601417D01*
X207950Y600917D01*
X208367Y600417D01*
X208867Y600083D01*
X209450Y600000D01*
X210033Y600167D01*
X210617Y600667D01*
G01X213633Y600000D02*
Y603333D01*
G01Y602667D02*
X214050Y603000D01*
X214467Y603250D01*
X215050Y603333D01*
X215467Y603250D01*
X215967Y603000D01*
G01X221900Y600000D02*
Y603333D01*
G01Y602750D02*
X221567Y603083D01*
X221067Y603250D01*
X220483Y603333D01*
X219900Y603167D01*
X219400Y602833D01*
X219067Y602333D01*
X218900Y601667D01*
X219067Y601000D01*
X219400Y600500D01*
X219900Y600167D01*
X220483Y600000D01*
X221067Y600083D01*
X221567Y600333D01*
X221900Y600667D01*
G01X224583Y600000D02*
Y603333D01*
G01Y602500D02*
X224917Y602917D01*
X225417Y603250D01*
X226083Y603333D01*
X226667Y603250D01*
X227167Y602917D01*
X227417Y602333D01*
Y600000D01*
G01X232933Y602917D02*
X232350Y603250D01*
X231850Y603333D01*
X231183Y603167D01*
X230683Y602833D01*
X230350Y602250D01*
X230267Y601667D01*
X230350Y601083D01*
X230683Y600583D01*
X231183Y600167D01*
X231850Y600000D01*
X232433Y600167D01*
X232933Y600500D01*
G01X235950Y602250D02*
X238617D01*
X238367Y602833D01*
X237950Y603167D01*
X237367Y603333D01*
X236783Y603250D01*
X236283Y603000D01*
X235950Y602417D01*
X235783Y601917D01*
Y601417D01*
X235950Y600917D01*
X236367Y600417D01*
X236867Y600083D01*
X237450Y600000D01*
X238033Y600167D01*
X238617Y600667D01*
G01X111917Y616500D02*
X114000Y621500D01*
X116083Y616500D01*
G01X115333Y618250D02*
X112667D01*
G01X118183Y616500D02*
Y619833D01*
G01Y619000D02*
X118517Y619417D01*
X119017Y619750D01*
X119683Y619833D01*
X120267Y619750D01*
X120767Y619417D01*
X121017Y618833D01*
Y616500D01*
G01X125200Y621500D02*
Y616500D01*
G01X124033Y619833D02*
X126367D01*
G01X130800D02*
Y616500D01*
G01Y621167D02*
X130633Y621250D01*
Y621417D01*
X130800Y621500D01*
X130967Y621417D01*
Y621250D01*
X130800Y621167D01*
G01X135317Y618167D02*
X137483D01*
G01X146100Y614833D02*
Y619833D01*
G01Y619083D02*
X146517Y619500D01*
X146933Y619750D01*
X147600Y619833D01*
X148183Y619750D01*
X148767Y619333D01*
X149017Y618750D01*
X149100Y618167D01*
X149017Y617583D01*
X148767Y617000D01*
X148267Y616667D01*
X147600Y616500D01*
X147017Y616583D01*
X146433Y616833D01*
X146100Y617167D01*
G01X154700Y616500D02*
Y619833D01*
G01Y619250D02*
X154367Y619583D01*
X153867Y619750D01*
X153283Y619833D01*
X152700Y619667D01*
X152200Y619333D01*
X151867Y618833D01*
X151700Y618167D01*
X151867Y617500D01*
X152200Y617000D01*
X152700Y616667D01*
X153283Y616500D01*
X153867Y616583D01*
X154367Y616833D01*
X154700Y617167D01*
G01X160300Y621500D02*
Y616500D01*
G01Y617250D02*
X159967Y616833D01*
X159467Y616583D01*
X158883Y616500D01*
X158217Y616667D01*
X157717Y617083D01*
X157383Y617583D01*
X157300Y618167D01*
X157383Y618750D01*
X157717Y619250D01*
X158217Y619667D01*
X158883Y619833D01*
X159467Y619750D01*
X159883Y619583D01*
X160300Y619250D01*
G01X112083Y634500D02*
Y639500D01*
X115917Y634500D01*
Y639500D01*
G01X119600Y634500D02*
X119100Y634583D01*
X118600Y634917D01*
X118267Y635500D01*
X118100Y636167D01*
X118267Y636833D01*
X118600Y637417D01*
X119100Y637750D01*
X119600Y637833D01*
X120100Y637750D01*
X120600Y637417D01*
X120933Y636833D01*
X121017Y636167D01*
X120933Y635500D01*
X120600Y634917D01*
X120100Y634583D01*
X119600Y634500D01*
G01X123783D02*
Y637833D01*
G01Y637000D02*
X124117Y637417D01*
X124617Y637750D01*
X125283Y637833D01*
X125867Y637750D01*
X126367Y637417D01*
X126617Y636833D01*
Y634500D01*
G01X129717Y636167D02*
X131883D01*
G01X135900Y634500D02*
Y638750D01*
X136067Y639167D01*
X136400Y639417D01*
X136900Y639500D01*
X137400Y639333D01*
X137650Y638917D01*
G01X136650Y637500D02*
X134983D01*
G01X140583Y637833D02*
Y635500D01*
X140917Y634917D01*
X141417Y634583D01*
X142000Y634500D01*
X142583Y634583D01*
X143083Y634917D01*
X143417Y635500D01*
G01Y634500D02*
Y637833D01*
G01X146183Y634500D02*
Y637833D01*
G01Y637000D02*
X146517Y637417D01*
X147017Y637750D01*
X147683Y637833D01*
X148267Y637750D01*
X148767Y637417D01*
X149017Y636833D01*
Y634500D01*
G01X154533Y637417D02*
X153950Y637750D01*
X153450Y637833D01*
X152783Y637667D01*
X152283Y637333D01*
X151950Y636750D01*
X151867Y636167D01*
X151950Y635583D01*
X152283Y635083D01*
X152783Y634667D01*
X153450Y634500D01*
X154033Y634667D01*
X154533Y635000D01*
G01X158800Y639500D02*
Y634500D01*
G01X157633Y637833D02*
X159967D01*
G01X164400D02*
Y634500D01*
G01Y639167D02*
X164233Y639250D01*
Y639417D01*
X164400Y639500D01*
X164567Y639417D01*
Y639250D01*
X164400Y639167D01*
G01X170000Y634500D02*
X169500Y634583D01*
X169000Y634917D01*
X168667Y635500D01*
X168500Y636167D01*
X168667Y636833D01*
X169000Y637417D01*
X169500Y637750D01*
X170000Y637833D01*
X170500Y637750D01*
X171000Y637417D01*
X171333Y636833D01*
X171417Y636167D01*
X171333Y635500D01*
X171000Y634917D01*
X170500Y634583D01*
X170000Y634500D01*
G01X174183D02*
Y637833D01*
G01Y637000D02*
X174517Y637417D01*
X175017Y637750D01*
X175683Y637833D01*
X176267Y637750D01*
X176767Y637417D01*
X177017Y636833D01*
Y634500D01*
G01X182700D02*
Y637833D01*
G01Y637250D02*
X182367Y637583D01*
X181867Y637750D01*
X181283Y637833D01*
X180700Y637667D01*
X180200Y637333D01*
X179867Y636833D01*
X179700Y636167D01*
X179867Y635500D01*
X180200Y635000D01*
X180700Y634667D01*
X181283Y634500D01*
X181867Y634583D01*
X182367Y634833D01*
X182700Y635167D01*
G01X186800Y634500D02*
Y639500D01*
G01X196500Y632833D02*
Y637833D01*
G01Y637083D02*
X196917Y637500D01*
X197333Y637750D01*
X198000Y637833D01*
X198583Y637750D01*
X199167Y637333D01*
X199417Y636750D01*
X199500Y636167D01*
X199417Y635583D01*
X199167Y635000D01*
X198667Y634667D01*
X198000Y634500D01*
X197417Y634583D01*
X196833Y634833D01*
X196500Y635167D01*
G01X205100Y634500D02*
Y637833D01*
G01Y637250D02*
X204767Y637583D01*
X204267Y637750D01*
X203683Y637833D01*
X203100Y637667D01*
X202600Y637333D01*
X202267Y636833D01*
X202100Y636167D01*
X202267Y635500D01*
X202600Y635000D01*
X203100Y634667D01*
X203683Y634500D01*
X204267Y634583D01*
X204767Y634833D01*
X205100Y635167D01*
G01X210700Y639500D02*
Y634500D01*
G01Y635250D02*
X210367Y634833D01*
X209867Y634583D01*
X209283Y634500D01*
X208617Y634667D01*
X208117Y635083D01*
X207783Y635583D01*
X207700Y636167D01*
X207783Y636750D01*
X208117Y637250D01*
X208617Y637667D01*
X209283Y637833D01*
X209867Y637750D01*
X210283Y637583D01*
X210700Y637250D01*
G01X103500Y595500D02*
X694500D01*
G01X103500Y625500D02*
X694500D01*
G01X160333Y668083D02*
X159833Y668333D01*
X159250Y668500D01*
X158583D01*
X157833Y668250D01*
X157250Y667833D01*
X156833Y667333D01*
X156500Y666500D01*
X156417Y665750D01*
X156583Y665000D01*
X156833Y664500D01*
X157333Y664000D01*
X157917Y663667D01*
X158500Y663500D01*
X159083D01*
X159667Y663667D01*
X160167Y663917D01*
X160583Y664250D01*
G01X164100Y663500D02*
Y668500D01*
G01X171200Y663500D02*
Y666833D01*
G01Y666250D02*
X170867Y666583D01*
X170367Y666750D01*
X169783Y666833D01*
X169200Y666667D01*
X168700Y666333D01*
X168367Y665833D01*
X168200Y665167D01*
X168367Y664500D01*
X168700Y664000D01*
X169200Y663667D01*
X169783Y663500D01*
X170367Y663583D01*
X170867Y663833D01*
X171200Y664167D01*
G01X174050Y664083D02*
X174467Y663750D01*
X175050Y663500D01*
X175550D01*
X176050Y663667D01*
X176383Y663917D01*
X176550Y664250D01*
X176467Y664750D01*
X176133Y665000D01*
X174633Y665500D01*
X174300Y666083D01*
X174467Y666500D01*
X174800Y666750D01*
X175300Y666833D01*
X175800Y666750D01*
X176300Y666500D01*
G01X179650Y664083D02*
X180067Y663750D01*
X180650Y663500D01*
X181150D01*
X181650Y663667D01*
X181983Y663917D01*
X182150Y664250D01*
X182067Y664750D01*
X181733Y665000D01*
X180233Y665500D01*
X179900Y666083D01*
X180067Y666500D01*
X180400Y666750D01*
X180900Y666833D01*
X181400Y666750D01*
X181900Y666500D01*
G01X186500Y666833D02*
Y663500D01*
G01Y668167D02*
X186333Y668250D01*
Y668417D01*
X186500Y668500D01*
X186667Y668417D01*
Y668250D01*
X186500Y668167D01*
G01X191600Y663500D02*
Y667750D01*
X191767Y668167D01*
X192100Y668417D01*
X192600Y668500D01*
X193100Y668333D01*
X193350Y667917D01*
G01X192350Y666500D02*
X190683D01*
G01X195950Y662000D02*
X196450Y661833D01*
X197117Y662000D01*
X197533Y662333D01*
X197867Y662750D01*
X198367Y664083D01*
X199450Y666833D01*
G01X196783D02*
X198367Y664083D01*
G01X272500Y15500D02*
Y10500D01*
G01X270583Y15500D02*
X274417D01*
G01X276017Y13833D02*
X277017Y10500D01*
X278100Y13833D01*
X279183Y10500D01*
X280183Y13833D01*
G01X283700D02*
Y10500D01*
G01Y15167D02*
X283533Y15250D01*
Y15417D01*
X283700Y15500D01*
X283867Y15417D01*
Y15250D01*
X283700Y15167D01*
G01X288050Y11083D02*
X288467Y10750D01*
X289050Y10500D01*
X289550D01*
X290050Y10667D01*
X290383Y10917D01*
X290550Y11250D01*
X290467Y11750D01*
X290133Y12000D01*
X288633Y12500D01*
X288300Y13083D01*
X288467Y13500D01*
X288800Y13750D01*
X289300Y13833D01*
X289800Y13750D01*
X290300Y13500D01*
G01X294900Y15500D02*
Y10500D01*
G01X293733Y13833D02*
X296067D01*
G01X307600Y10500D02*
Y13833D01*
G01Y13250D02*
X307267Y13583D01*
X306767Y13750D01*
X306183Y13833D01*
X305600Y13667D01*
X305100Y13333D01*
X304767Y12833D01*
X304600Y12167D01*
X304767Y11500D01*
X305100Y11000D01*
X305600Y10667D01*
X306183Y10500D01*
X306767Y10583D01*
X307267Y10833D01*
X307600Y11167D01*
G01X310283Y10500D02*
Y13833D01*
G01Y13000D02*
X310617Y13417D01*
X311117Y13750D01*
X311783Y13833D01*
X312367Y13750D01*
X312867Y13417D01*
X313117Y12833D01*
Y10500D01*
G01X318800Y15500D02*
Y10500D01*
G01Y11250D02*
X318467Y10833D01*
X317967Y10583D01*
X317383Y10500D01*
X316717Y10667D01*
X316217Y11083D01*
X315883Y11583D01*
X315800Y12167D01*
X315883Y12750D01*
X316217Y13250D01*
X316717Y13667D01*
X317383Y13833D01*
X317967Y13750D01*
X318383Y13583D01*
X318800Y13250D01*
G01X327000Y10500D02*
Y15500D01*
G01Y13000D02*
X327417Y13500D01*
X327917Y13750D01*
X328417Y13833D01*
X329167Y13667D01*
X329667Y13333D01*
X330000Y12750D01*
Y12083D01*
X329833Y11417D01*
X329500Y10917D01*
X328917Y10583D01*
X328417Y10500D01*
X327917Y10583D01*
X327417Y10833D01*
X327000Y11250D01*
G01X334100Y10500D02*
X333600Y10583D01*
X333100Y10917D01*
X332767Y11500D01*
X332600Y12167D01*
X332767Y12833D01*
X333100Y13417D01*
X333600Y13750D01*
X334100Y13833D01*
X334600Y13750D01*
X335100Y13417D01*
X335433Y12833D01*
X335517Y12167D01*
X335433Y11500D01*
X335100Y10917D01*
X334600Y10583D01*
X334100Y10500D01*
G01X337617Y13833D02*
X338617Y10500D01*
X339700Y13833D01*
X340783Y10500D01*
X341783Y13833D01*
G01X273000Y34000D02*
X274667D01*
Y32500D01*
X274167Y32000D01*
X273583Y31667D01*
X272750Y31500D01*
X271917Y31667D01*
X271333Y32000D01*
X270833Y32500D01*
X270500Y33083D01*
X270333Y33750D01*
Y34333D01*
X270500Y34833D01*
X270833Y35417D01*
X271333Y35917D01*
X271833Y36250D01*
X272500Y36500D01*
X273083D01*
X273750Y36333D01*
X274250Y36000D01*
G01X276600Y31333D02*
X279600Y36500D01*
G01X282117Y31500D02*
Y36500D01*
X285283D01*
G01X284117Y34083D02*
X282117D01*
G01X293150Y32167D02*
X293817Y31750D01*
X294567Y31500D01*
X295233D01*
X295900Y31750D01*
X296400Y32167D01*
X296650Y32750D01*
X296483Y33333D01*
X296067Y33833D01*
X295317Y34167D01*
X294317Y34333D01*
X293733Y34667D01*
X293483Y35250D01*
X293650Y35833D01*
X294067Y36250D01*
X294650Y36500D01*
X295233D01*
X295817Y36333D01*
X296317Y35917D01*
G01X300500Y31500D02*
Y36500D01*
G01X306100Y31500D02*
X305600Y31583D01*
X305100Y31917D01*
X304767Y32500D01*
X304600Y33167D01*
X304767Y33833D01*
X305100Y34417D01*
X305600Y34750D01*
X306100Y34833D01*
X306600Y34750D01*
X307100Y34417D01*
X307433Y33833D01*
X307517Y33167D01*
X307433Y32500D01*
X307100Y31917D01*
X306600Y31583D01*
X306100Y31500D01*
G01X311700Y36500D02*
Y31500D01*
G01X310533Y34833D02*
X312867D01*
G01X271250Y48750D02*
X273917D01*
X273667Y49333D01*
X273250Y49667D01*
X272667Y49833D01*
X272083Y49750D01*
X271583Y49500D01*
X271250Y48917D01*
X271083Y48417D01*
Y47917D01*
X271250Y47417D01*
X271667Y46917D01*
X272167Y46583D01*
X272750Y46500D01*
X273333Y46667D01*
X273917Y47167D01*
G01X279600Y51500D02*
Y46500D01*
G01Y47250D02*
X279267Y46833D01*
X278767Y46583D01*
X278183Y46500D01*
X277517Y46667D01*
X277017Y47083D01*
X276683Y47583D01*
X276600Y48167D01*
X276683Y48750D01*
X277017Y49250D01*
X277517Y49667D01*
X278183Y49833D01*
X278767Y49750D01*
X279183Y49583D01*
X279600Y49250D01*
G01X282533Y45250D02*
X283117Y44917D01*
X283783Y44833D01*
X284367Y44917D01*
X284867Y45333D01*
X285200Y45917D01*
Y49833D01*
G01Y49167D02*
X284867Y49500D01*
X284367Y49750D01*
X283783Y49833D01*
X283117Y49667D01*
X282700Y49333D01*
X282367Y48750D01*
X282200Y48167D01*
X282283Y47667D01*
X282617Y47083D01*
X283117Y46667D01*
X283783Y46500D01*
X284283Y46583D01*
X284867Y46917D01*
X285200Y47250D01*
G01X288050Y48750D02*
X290717D01*
X290467Y49333D01*
X290050Y49667D01*
X289467Y49833D01*
X288883Y49750D01*
X288383Y49500D01*
X288050Y48917D01*
X287883Y48417D01*
Y47917D01*
X288050Y47417D01*
X288467Y46917D01*
X288967Y46583D01*
X289550Y46500D01*
X290133Y46667D01*
X290717Y47167D01*
G01X300500Y51500D02*
Y46500D01*
G01X299333Y49833D02*
X301667D01*
G01X306100Y46500D02*
X305600Y46583D01*
X305100Y46917D01*
X304767Y47500D01*
X304600Y48167D01*
X304767Y48833D01*
X305100Y49417D01*
X305600Y49750D01*
X306100Y49833D01*
X306600Y49750D01*
X307100Y49417D01*
X307433Y48833D01*
X307517Y48167D01*
X307433Y47500D01*
X307100Y46917D01*
X306600Y46583D01*
X306100Y46500D01*
G01X315883D02*
Y51500D01*
G01Y49083D02*
X316300Y49500D01*
X316717Y49750D01*
X317383Y49833D01*
X317883Y49750D01*
X318467Y49417D01*
X318717Y48917D01*
Y46500D01*
G01X322900D02*
X322400Y46583D01*
X321900Y46917D01*
X321567Y47500D01*
X321400Y48167D01*
X321567Y48833D01*
X321900Y49417D01*
X322400Y49750D01*
X322900Y49833D01*
X323400Y49750D01*
X323900Y49417D01*
X324233Y48833D01*
X324317Y48167D01*
X324233Y47500D01*
X323900Y46917D01*
X323400Y46583D01*
X322900Y46500D01*
G01X328500D02*
Y51500D01*
G01X332850Y48750D02*
X335517D01*
X335267Y49333D01*
X334850Y49667D01*
X334267Y49833D01*
X333683Y49750D01*
X333183Y49500D01*
X332850Y48917D01*
X332683Y48417D01*
Y47917D01*
X332850Y47417D01*
X333267Y46917D01*
X333767Y46583D01*
X334350Y46500D01*
X334933Y46667D01*
X335517Y47167D01*
G01X271250Y65250D02*
X273917D01*
X273667Y65833D01*
X273250Y66167D01*
X272667Y66333D01*
X272083Y66250D01*
X271583Y66000D01*
X271250Y65417D01*
X271083Y64917D01*
Y64417D01*
X271250Y63917D01*
X271667Y63417D01*
X272167Y63083D01*
X272750Y63000D01*
X273333Y63167D01*
X273917Y63667D01*
G01X279600Y68000D02*
Y63000D01*
G01Y63750D02*
X279267Y63333D01*
X278767Y63083D01*
X278183Y63000D01*
X277517Y63167D01*
X277017Y63583D01*
X276683Y64083D01*
X276600Y64667D01*
X276683Y65250D01*
X277017Y65750D01*
X277517Y66167D01*
X278183Y66333D01*
X278767Y66250D01*
X279183Y66083D01*
X279600Y65750D01*
G01X282533Y61750D02*
X283117Y61417D01*
X283783Y61333D01*
X284367Y61417D01*
X284867Y61833D01*
X285200Y62417D01*
Y66333D01*
G01Y65667D02*
X284867Y66000D01*
X284367Y66250D01*
X283783Y66333D01*
X283117Y66167D01*
X282700Y65833D01*
X282367Y65250D01*
X282200Y64667D01*
X282283Y64167D01*
X282617Y63583D01*
X283117Y63167D01*
X283783Y63000D01*
X284283Y63083D01*
X284867Y63417D01*
X285200Y63750D01*
G01X288050Y65250D02*
X290717D01*
X290467Y65833D01*
X290050Y66167D01*
X289467Y66333D01*
X288883Y66250D01*
X288383Y66000D01*
X288050Y65417D01*
X287883Y64917D01*
Y64417D01*
X288050Y63917D01*
X288467Y63417D01*
X288967Y63083D01*
X289550Y63000D01*
X290133Y63167D01*
X290717Y63667D01*
G01X300500Y68000D02*
Y63000D01*
G01X299333Y66333D02*
X301667D01*
G01X306100Y63000D02*
X305600Y63083D01*
X305100Y63417D01*
X304767Y64000D01*
X304600Y64667D01*
X304767Y65333D01*
X305100Y65917D01*
X305600Y66250D01*
X306100Y66333D01*
X306600Y66250D01*
X307100Y65917D01*
X307433Y65333D01*
X307517Y64667D01*
X307433Y64000D01*
X307100Y63417D01*
X306600Y63083D01*
X306100Y63000D01*
G01X316050Y65250D02*
X318717D01*
X318467Y65833D01*
X318050Y66167D01*
X317467Y66333D01*
X316883Y66250D01*
X316383Y66000D01*
X316050Y65417D01*
X315883Y64917D01*
Y64417D01*
X316050Y63917D01*
X316467Y63417D01*
X316967Y63083D01*
X317550Y63000D01*
X318133Y63167D01*
X318717Y63667D01*
G01X324400Y68000D02*
Y63000D01*
G01Y63750D02*
X324067Y63333D01*
X323567Y63083D01*
X322983Y63000D01*
X322317Y63167D01*
X321817Y63583D01*
X321483Y64083D01*
X321400Y64667D01*
X321483Y65250D01*
X321817Y65750D01*
X322317Y66167D01*
X322983Y66333D01*
X323567Y66250D01*
X323983Y66083D01*
X324400Y65750D01*
G01X327333Y61750D02*
X327917Y61417D01*
X328583Y61333D01*
X329167Y61417D01*
X329667Y61833D01*
X330000Y62417D01*
Y66333D01*
G01Y65667D02*
X329667Y66000D01*
X329167Y66250D01*
X328583Y66333D01*
X327917Y66167D01*
X327500Y65833D01*
X327167Y65250D01*
X327000Y64667D01*
X327083Y64167D01*
X327417Y63583D01*
X327917Y63167D01*
X328583Y63000D01*
X329083Y63083D01*
X329667Y63417D01*
X330000Y63750D01*
G01X332850Y65250D02*
X335517D01*
X335267Y65833D01*
X334850Y66167D01*
X334267Y66333D01*
X333683Y66250D01*
X333183Y66000D01*
X332850Y65417D01*
X332683Y64917D01*
Y64417D01*
X332850Y63917D01*
X333267Y63417D01*
X333767Y63083D01*
X334350Y63000D01*
X334933Y63167D01*
X335517Y63667D01*
G01X264000Y42000D02*
X694500D01*
G01X264000Y57000D02*
X694500D01*
G01X262500Y500D02*
Y445500D01*
G01X272500Y141500D02*
Y136500D01*
G01X270583Y141500D02*
X274417D01*
G01X276683Y136500D02*
Y141500D01*
G01Y139083D02*
X277100Y139500D01*
X277517Y139750D01*
X278183Y139833D01*
X278683Y139750D01*
X279267Y139417D01*
X279517Y138917D01*
Y136500D01*
G01X282450Y138750D02*
X285117D01*
X284867Y139333D01*
X284450Y139667D01*
X283867Y139833D01*
X283283Y139750D01*
X282783Y139500D01*
X282450Y138917D01*
X282283Y138417D01*
Y137917D01*
X282450Y137417D01*
X282867Y136917D01*
X283367Y136583D01*
X283950Y136500D01*
X284533Y136667D01*
X285117Y137167D01*
G01X294900Y136500D02*
Y141500D01*
G01X302000Y136500D02*
Y139833D01*
G01Y139250D02*
X301667Y139583D01*
X301167Y139750D01*
X300583Y139833D01*
X300000Y139667D01*
X299500Y139333D01*
X299167Y138833D01*
X299000Y138167D01*
X299167Y137500D01*
X299500Y137000D01*
X300000Y136667D01*
X300583Y136500D01*
X301167Y136583D01*
X301667Y136833D01*
X302000Y137167D01*
G01X304933Y136500D02*
Y139833D01*
G01Y139167D02*
X305350Y139500D01*
X305767Y139750D01*
X306350Y139833D01*
X306767Y139750D01*
X307267Y139500D01*
G01X310533Y135250D02*
X311117Y134917D01*
X311783Y134833D01*
X312367Y134917D01*
X312867Y135333D01*
X313200Y135917D01*
Y139833D01*
G01Y139167D02*
X312867Y139500D01*
X312367Y139750D01*
X311783Y139833D01*
X311117Y139667D01*
X310700Y139333D01*
X310367Y138750D01*
X310200Y138167D01*
X310283Y137667D01*
X310617Y137083D01*
X311117Y136667D01*
X311783Y136500D01*
X312283Y136583D01*
X312867Y136917D01*
X313200Y137250D01*
G01X316050Y138750D02*
X318717D01*
X318467Y139333D01*
X318050Y139667D01*
X317467Y139833D01*
X316883Y139750D01*
X316383Y139500D01*
X316050Y138917D01*
X315883Y138417D01*
Y137917D01*
X316050Y137417D01*
X316467Y136917D01*
X316967Y136583D01*
X317550Y136500D01*
X318133Y136667D01*
X318717Y137167D01*
G01X321650Y137083D02*
X322067Y136750D01*
X322650Y136500D01*
X323150D01*
X323650Y136667D01*
X323983Y136917D01*
X324150Y137250D01*
X324067Y137750D01*
X323733Y138000D01*
X322233Y138500D01*
X321900Y139083D01*
X322067Y139500D01*
X322400Y139750D01*
X322900Y139833D01*
X323400Y139750D01*
X323900Y139500D01*
G01X328500Y141500D02*
Y136500D01*
G01X327333Y139833D02*
X329667D01*
G01X341200Y141500D02*
Y136500D01*
G01Y137250D02*
X340867Y136833D01*
X340367Y136583D01*
X339783Y136500D01*
X339117Y136667D01*
X338617Y137083D01*
X338283Y137583D01*
X338200Y138167D01*
X338283Y138750D01*
X338617Y139250D01*
X339117Y139667D01*
X339783Y139833D01*
X340367Y139750D01*
X340783Y139583D01*
X341200Y139250D01*
G01X345300Y139833D02*
Y136500D01*
G01Y141167D02*
X345133Y141250D01*
Y141417D01*
X345300Y141500D01*
X345467Y141417D01*
Y141250D01*
X345300Y141167D01*
G01X348400Y136500D02*
Y139833D01*
G01Y138917D02*
X348650Y139333D01*
X349067Y139667D01*
X349650Y139833D01*
X350233Y139667D01*
X350650Y139333D01*
X350900Y138917D01*
Y136500D01*
G01Y138917D02*
X351150Y139333D01*
X351567Y139667D01*
X352150Y139833D01*
X352733Y139667D01*
X353150Y139333D01*
X353400Y138833D01*
Y136500D01*
G01X355250Y138750D02*
X357917D01*
X357667Y139333D01*
X357250Y139667D01*
X356667Y139833D01*
X356083Y139750D01*
X355583Y139500D01*
X355250Y138917D01*
X355083Y138417D01*
Y137917D01*
X355250Y137417D01*
X355667Y136917D01*
X356167Y136583D01*
X356750Y136500D01*
X357333Y136667D01*
X357917Y137167D01*
G01X360683Y136500D02*
Y139833D01*
G01Y139000D02*
X361017Y139417D01*
X361517Y139750D01*
X362183Y139833D01*
X362767Y139750D01*
X363267Y139417D01*
X363517Y138833D01*
Y136500D01*
G01X366450Y137083D02*
X366867Y136750D01*
X367450Y136500D01*
X367950D01*
X368450Y136667D01*
X368783Y136917D01*
X368950Y137250D01*
X368867Y137750D01*
X368533Y138000D01*
X367033Y138500D01*
X366700Y139083D01*
X366867Y139500D01*
X367200Y139750D01*
X367700Y139833D01*
X368200Y139750D01*
X368700Y139500D01*
G01X373300Y139833D02*
Y136500D01*
G01Y141167D02*
X373133Y141250D01*
Y141417D01*
X373300Y141500D01*
X373467Y141417D01*
Y141250D01*
X373300Y141167D01*
G01X378900Y136500D02*
X378400Y136583D01*
X377900Y136917D01*
X377567Y137500D01*
X377400Y138167D01*
X377567Y138833D01*
X377900Y139417D01*
X378400Y139750D01*
X378900Y139833D01*
X379400Y139750D01*
X379900Y139417D01*
X380233Y138833D01*
X380317Y138167D01*
X380233Y137500D01*
X379900Y136917D01*
X379400Y136583D01*
X378900Y136500D01*
G01X383083D02*
Y139833D01*
G01Y139000D02*
X383417Y139417D01*
X383917Y139750D01*
X384583Y139833D01*
X385167Y139750D01*
X385667Y139417D01*
X385917Y138833D01*
Y136500D01*
G01X395700D02*
X395200Y136583D01*
X394700Y136917D01*
X394367Y137500D01*
X394200Y138167D01*
X394367Y138833D01*
X394700Y139417D01*
X395200Y139750D01*
X395700Y139833D01*
X396200Y139750D01*
X396700Y139417D01*
X397033Y138833D01*
X397117Y138167D01*
X397033Y137500D01*
X396700Y136917D01*
X396200Y136583D01*
X395700Y136500D01*
G01X400800D02*
Y140750D01*
X400967Y141167D01*
X401300Y141417D01*
X401800Y141500D01*
X402300Y141333D01*
X402550Y140917D01*
G01X401550Y139500D02*
X399883D01*
G01X411000Y134833D02*
Y139833D01*
G01Y139083D02*
X411417Y139500D01*
X411833Y139750D01*
X412500Y139833D01*
X413083Y139750D01*
X413667Y139333D01*
X413917Y138750D01*
X414000Y138167D01*
X413917Y137583D01*
X413667Y137000D01*
X413167Y136667D01*
X412500Y136500D01*
X411917Y136583D01*
X411333Y136833D01*
X411000Y137167D01*
G01X419600Y136500D02*
Y139833D01*
G01Y139250D02*
X419267Y139583D01*
X418767Y139750D01*
X418183Y139833D01*
X417600Y139667D01*
X417100Y139333D01*
X416767Y138833D01*
X416600Y138167D01*
X416767Y137500D01*
X417100Y137000D01*
X417600Y136667D01*
X418183Y136500D01*
X418767Y136583D01*
X419267Y136833D01*
X419600Y137167D01*
G01X425200Y141500D02*
Y136500D01*
G01Y137250D02*
X424867Y136833D01*
X424367Y136583D01*
X423783Y136500D01*
X423117Y136667D01*
X422617Y137083D01*
X422283Y137583D01*
X422200Y138167D01*
X422283Y138750D01*
X422617Y139250D01*
X423117Y139667D01*
X423783Y139833D01*
X424367Y139750D01*
X424783Y139583D01*
X425200Y139250D01*
G01X434900Y136500D02*
X434400Y136583D01*
X433900Y136917D01*
X433567Y137500D01*
X433400Y138167D01*
X433567Y138833D01*
X433900Y139417D01*
X434400Y139750D01*
X434900Y139833D01*
X435400Y139750D01*
X435900Y139417D01*
X436233Y138833D01*
X436317Y138167D01*
X436233Y137500D01*
X435900Y136917D01*
X435400Y136583D01*
X434900Y136500D01*
G01X439333D02*
Y139833D01*
G01Y139167D02*
X439750Y139500D01*
X440167Y139750D01*
X440750Y139833D01*
X441167Y139750D01*
X441667Y139500D01*
G01X453200Y141500D02*
Y136500D01*
G01Y137250D02*
X452867Y136833D01*
X452367Y136583D01*
X451783Y136500D01*
X451117Y136667D01*
X450617Y137083D01*
X450283Y137583D01*
X450200Y138167D01*
X450283Y138750D01*
X450617Y139250D01*
X451117Y139667D01*
X451783Y139833D01*
X452367Y139750D01*
X452783Y139583D01*
X453200Y139250D01*
G01X457300Y139833D02*
Y136500D01*
G01Y141167D02*
X457133Y141250D01*
Y141417D01*
X457300Y141500D01*
X457467Y141417D01*
Y141250D01*
X457300Y141167D01*
G01X464400Y136500D02*
Y139833D01*
G01Y139250D02*
X464067Y139583D01*
X463567Y139750D01*
X462983Y139833D01*
X462400Y139667D01*
X461900Y139333D01*
X461567Y138833D01*
X461400Y138167D01*
X461567Y137500D01*
X461900Y137000D01*
X462400Y136667D01*
X462983Y136500D01*
X463567Y136583D01*
X464067Y136833D01*
X464400Y137167D01*
G01X466000Y136500D02*
Y139833D01*
G01Y138917D02*
X466250Y139333D01*
X466667Y139667D01*
X467250Y139833D01*
X467833Y139667D01*
X468250Y139333D01*
X468500Y138917D01*
Y136500D01*
G01Y138917D02*
X468750Y139333D01*
X469167Y139667D01*
X469750Y139833D01*
X470333Y139667D01*
X470750Y139333D01*
X471000Y138833D01*
Y136500D01*
G01X472850Y138750D02*
X475517D01*
X475267Y139333D01*
X474850Y139667D01*
X474267Y139833D01*
X473683Y139750D01*
X473183Y139500D01*
X472850Y138917D01*
X472683Y138417D01*
Y137917D01*
X472850Y137417D01*
X473267Y136917D01*
X473767Y136583D01*
X474350Y136500D01*
X474933Y136667D01*
X475517Y137167D01*
G01X479700Y141500D02*
Y136500D01*
G01X478533Y139833D02*
X480867D01*
G01X484050Y138750D02*
X486717D01*
X486467Y139333D01*
X486050Y139667D01*
X485467Y139833D01*
X484883Y139750D01*
X484383Y139500D01*
X484050Y138917D01*
X483883Y138417D01*
Y137917D01*
X484050Y137417D01*
X484467Y136917D01*
X484967Y136583D01*
X485550Y136500D01*
X486133Y136667D01*
X486717Y137167D01*
G01X489733Y136500D02*
Y139833D01*
G01Y139167D02*
X490150Y139500D01*
X490567Y139750D01*
X491150Y139833D01*
X491567Y139750D01*
X492067Y139500D01*
G01X503767Y136500D02*
X500433Y138167D01*
X503767Y139833D01*
G01X506617Y137417D02*
X508783D01*
G01Y138917D02*
X506617D01*
G01X518900Y136500D02*
Y141500D01*
X517900Y140500D01*
G01Y136500D02*
X519900D01*
G01X525500D02*
Y141500D01*
X522417Y137917D01*
X526583D01*
G01X533200Y136500D02*
Y139833D01*
G01Y138917D02*
X533450Y139333D01*
X533867Y139667D01*
X534450Y139833D01*
X535033Y139667D01*
X535450Y139333D01*
X535700Y138917D01*
Y136500D01*
G01Y138917D02*
X535950Y139333D01*
X536367Y139667D01*
X536950Y139833D01*
X537533Y139667D01*
X537950Y139333D01*
X538200Y138833D01*
Y136500D01*
G01X541300Y139833D02*
Y136500D01*
G01Y141167D02*
X541133Y141250D01*
Y141417D01*
X541300Y141500D01*
X541467Y141417D01*
Y141250D01*
X541300Y141167D01*
G01X546900Y136500D02*
Y141500D01*
G01X274000Y78000D02*
Y81333D01*
G01Y80750D02*
X273667Y81083D01*
X273167Y81250D01*
X272583Y81333D01*
X272000Y81167D01*
X271500Y80833D01*
X271167Y80333D01*
X271000Y79667D01*
X271167Y79000D01*
X271500Y78500D01*
X272000Y78167D01*
X272583Y78000D01*
X273167Y78083D01*
X273667Y78333D01*
X274000Y78667D01*
G01X279600Y83000D02*
Y78000D01*
G01Y78750D02*
X279267Y78333D01*
X278767Y78083D01*
X278183Y78000D01*
X277517Y78167D01*
X277017Y78583D01*
X276683Y79083D01*
X276600Y79667D01*
X276683Y80250D01*
X277017Y80750D01*
X277517Y81167D01*
X278183Y81333D01*
X278767Y81250D01*
X279183Y81083D01*
X279600Y80750D01*
G01X285200Y83000D02*
Y78000D01*
G01Y78750D02*
X284867Y78333D01*
X284367Y78083D01*
X283783Y78000D01*
X283117Y78167D01*
X282617Y78583D01*
X282283Y79083D01*
X282200Y79667D01*
X282283Y80250D01*
X282617Y80750D01*
X283117Y81167D01*
X283783Y81333D01*
X284367Y81250D01*
X284783Y81083D01*
X285200Y80750D01*
G01X293650Y78583D02*
X294067Y78250D01*
X294650Y78000D01*
X295150D01*
X295650Y78167D01*
X295983Y78417D01*
X296150Y78750D01*
X296067Y79250D01*
X295733Y79500D01*
X294233Y80000D01*
X293900Y80583D01*
X294067Y81000D01*
X294400Y81250D01*
X294900Y81333D01*
X295400Y81250D01*
X295900Y81000D01*
G01X299083Y81333D02*
Y79000D01*
X299417Y78417D01*
X299917Y78083D01*
X300500Y78000D01*
X301083Y78083D01*
X301583Y78417D01*
X301917Y79000D01*
G01Y78000D02*
Y81333D01*
G01X304600Y76333D02*
Y81333D01*
G01Y80583D02*
X305017Y81000D01*
X305433Y81250D01*
X306100Y81333D01*
X306683Y81250D01*
X307267Y80833D01*
X307517Y80250D01*
X307600Y79667D01*
X307517Y79083D01*
X307267Y78500D01*
X306767Y78167D01*
X306100Y78000D01*
X305517Y78083D01*
X304933Y78333D01*
X304600Y78667D01*
G01X310200Y76333D02*
Y81333D01*
G01Y80583D02*
X310617Y81000D01*
X311033Y81250D01*
X311700Y81333D01*
X312283Y81250D01*
X312867Y80833D01*
X313117Y80250D01*
X313200Y79667D01*
X313117Y79083D01*
X312867Y78500D01*
X312367Y78167D01*
X311700Y78000D01*
X311117Y78083D01*
X310533Y78333D01*
X310200Y78667D01*
G01X317300Y78000D02*
Y83000D01*
G01X322900Y81333D02*
Y78000D01*
G01Y82667D02*
X322733Y82750D01*
Y82917D01*
X322900Y83000D01*
X323067Y82917D01*
Y82750D01*
X322900Y82667D01*
G01X327250Y80250D02*
X329917D01*
X329667Y80833D01*
X329250Y81167D01*
X328667Y81333D01*
X328083Y81250D01*
X327583Y81000D01*
X327250Y80417D01*
X327083Y79917D01*
Y79417D01*
X327250Y78917D01*
X327667Y78417D01*
X328167Y78083D01*
X328750Y78000D01*
X329333Y78167D01*
X329917Y78667D01*
G01X332933Y78000D02*
Y81333D01*
G01Y80667D02*
X333350Y81000D01*
X333767Y81250D01*
X334350Y81333D01*
X334767Y81250D01*
X335267Y81000D01*
G01X339700Y81333D02*
X340533Y82375D01*
Y83000D01*
X339908D01*
Y82375D01*
X340533D01*
G01X344050Y78583D02*
X344467Y78250D01*
X345050Y78000D01*
X345550D01*
X346050Y78167D01*
X346383Y78417D01*
X346550Y78750D01*
X346467Y79250D01*
X346133Y79500D01*
X344633Y80000D01*
X344300Y80583D01*
X344467Y81000D01*
X344800Y81250D01*
X345300Y81333D01*
X345800Y81250D01*
X346300Y81000D01*
G01X354833Y83000D02*
Y78000D01*
X358167D01*
G01X362100D02*
X361600Y78083D01*
X361100Y78417D01*
X360767Y79000D01*
X360600Y79667D01*
X360767Y80333D01*
X361100Y80917D01*
X361600Y81250D01*
X362100Y81333D01*
X362600Y81250D01*
X363100Y80917D01*
X363433Y80333D01*
X363517Y79667D01*
X363433Y79000D01*
X363100Y78417D01*
X362600Y78083D01*
X362100Y78000D01*
G01X366533Y76750D02*
X367117Y76417D01*
X367783Y76333D01*
X368367Y76417D01*
X368867Y76833D01*
X369200Y77417D01*
Y81333D01*
G01Y80667D02*
X368867Y81000D01*
X368367Y81250D01*
X367783Y81333D01*
X367117Y81167D01*
X366700Y80833D01*
X366367Y80250D01*
X366200Y79667D01*
X366283Y79167D01*
X366617Y78583D01*
X367117Y78167D01*
X367783Y78000D01*
X368283Y78083D01*
X368867Y78417D01*
X369200Y78750D01*
G01X373300Y78000D02*
X372800Y78083D01*
X372300Y78417D01*
X371967Y79000D01*
X371800Y79667D01*
X371967Y80333D01*
X372300Y80917D01*
X372800Y81250D01*
X373300Y81333D01*
X373800Y81250D01*
X374300Y80917D01*
X374633Y80333D01*
X374717Y79667D01*
X374633Y79000D01*
X374300Y78417D01*
X373800Y78083D01*
X373300Y78000D01*
G01X386000D02*
Y81333D01*
G01Y80750D02*
X385667Y81083D01*
X385167Y81250D01*
X384583Y81333D01*
X384000Y81167D01*
X383500Y80833D01*
X383167Y80333D01*
X383000Y79667D01*
X383167Y79000D01*
X383500Y78500D01*
X384000Y78167D01*
X384583Y78000D01*
X385167Y78083D01*
X385667Y78333D01*
X386000Y78667D01*
G01X388683Y78000D02*
Y81333D01*
G01Y80500D02*
X389017Y80917D01*
X389517Y81250D01*
X390183Y81333D01*
X390767Y81250D01*
X391267Y80917D01*
X391517Y80333D01*
Y78000D01*
G01X397200Y83000D02*
Y78000D01*
G01Y78750D02*
X396867Y78333D01*
X396367Y78083D01*
X395783Y78000D01*
X395117Y78167D01*
X394617Y78583D01*
X394283Y79083D01*
X394200Y79667D01*
X394283Y80250D01*
X394617Y80750D01*
X395117Y81167D01*
X395783Y81333D01*
X396367Y81250D01*
X396783Y81083D01*
X397200Y80750D01*
G01X405067Y83000D02*
Y79417D01*
X405400Y78667D01*
X406067Y78167D01*
X406900Y78000D01*
X407733Y78167D01*
X408400Y78667D01*
X408733Y79417D01*
Y83000D01*
G01X410833D02*
Y78000D01*
X414167D01*
G01X423200D02*
Y82250D01*
X423367Y82667D01*
X423700Y82917D01*
X424200Y83000D01*
X424700Y82833D01*
X424950Y82417D01*
G01X423950Y81000D02*
X422283D01*
G01X429300Y81333D02*
Y78000D01*
G01Y82667D02*
X429133Y82750D01*
Y82917D01*
X429300Y83000D01*
X429467Y82917D01*
Y82750D01*
X429300Y82667D01*
G01X434900Y78000D02*
Y83000D01*
G01X439250Y80250D02*
X441917D01*
X441667Y80833D01*
X441250Y81167D01*
X440667Y81333D01*
X440083Y81250D01*
X439583Y81000D01*
X439250Y80417D01*
X439083Y79917D01*
Y79417D01*
X439250Y78917D01*
X439667Y78417D01*
X440167Y78083D01*
X440750Y78000D01*
X441333Y78167D01*
X441917Y78667D01*
G01X449783Y78000D02*
Y83000D01*
X453617Y78000D01*
Y83000D01*
G01X455883Y81333D02*
Y79000D01*
X456217Y78417D01*
X456717Y78083D01*
X457300Y78000D01*
X457883Y78083D01*
X458383Y78417D01*
X458717Y79000D01*
G01Y78000D02*
Y81333D01*
G01X460400Y78000D02*
Y81333D01*
G01Y80417D02*
X460650Y80833D01*
X461067Y81167D01*
X461650Y81333D01*
X462233Y81167D01*
X462650Y80833D01*
X462900Y80417D01*
Y78000D01*
G01Y80417D02*
X463150Y80833D01*
X463567Y81167D01*
X464150Y81333D01*
X464733Y81167D01*
X465150Y80833D01*
X465400Y80333D01*
Y78000D01*
G01X467000D02*
Y83000D01*
G01Y80500D02*
X467417Y81000D01*
X467917Y81250D01*
X468417Y81333D01*
X469167Y81167D01*
X469667Y80833D01*
X470000Y80250D01*
Y79583D01*
X469833Y78917D01*
X469500Y78417D01*
X468917Y78083D01*
X468417Y78000D01*
X467917Y78083D01*
X467417Y78333D01*
X467000Y78750D01*
G01X472850Y80250D02*
X475517D01*
X475267Y80833D01*
X474850Y81167D01*
X474267Y81333D01*
X473683Y81250D01*
X473183Y81000D01*
X472850Y80417D01*
X472683Y79917D01*
Y79417D01*
X472850Y78917D01*
X473267Y78417D01*
X473767Y78083D01*
X474350Y78000D01*
X474933Y78167D01*
X475517Y78667D01*
G01X478533Y78000D02*
Y81333D01*
G01Y80667D02*
X478950Y81000D01*
X479367Y81250D01*
X479950Y81333D01*
X480367Y81250D01*
X480867Y81000D01*
G01X490900Y81333D02*
Y78000D01*
G01Y82667D02*
X490733Y82750D01*
Y82917D01*
X490900Y83000D01*
X491067Y82917D01*
Y82750D01*
X490900Y82667D01*
G01X495083Y78000D02*
Y81333D01*
G01Y80500D02*
X495417Y80917D01*
X495917Y81250D01*
X496583Y81333D01*
X497167Y81250D01*
X497667Y80917D01*
X497917Y80333D01*
Y78000D01*
G01X506450Y78583D02*
X506867Y78250D01*
X507450Y78000D01*
X507950D01*
X508450Y78167D01*
X508783Y78417D01*
X508950Y78750D01*
X508867Y79250D01*
X508533Y79500D01*
X507033Y80000D01*
X506700Y80583D01*
X506867Y81000D01*
X507200Y81250D01*
X507700Y81333D01*
X508200Y81250D01*
X508700Y81000D01*
G01X513300Y81333D02*
Y78000D01*
G01Y82667D02*
X513133Y82750D01*
Y82917D01*
X513300Y83000D01*
X513467Y82917D01*
Y82750D01*
X513300Y82667D01*
G01X518900Y78000D02*
Y83000D01*
G01X523083Y78000D02*
Y83000D01*
G01X525750Y81333D02*
X523083Y79417D01*
G01X524167Y80167D02*
X525917Y78000D01*
G01X528850Y78583D02*
X529267Y78250D01*
X529850Y78000D01*
X530350D01*
X530850Y78167D01*
X531183Y78417D01*
X531350Y78750D01*
X531267Y79250D01*
X530933Y79500D01*
X529433Y80000D01*
X529100Y80583D01*
X529267Y81000D01*
X529600Y81250D01*
X530100Y81333D01*
X530600Y81250D01*
X531100Y81000D01*
G01X537033Y80917D02*
X536450Y81250D01*
X535950Y81333D01*
X535283Y81167D01*
X534783Y80833D01*
X534450Y80250D01*
X534367Y79667D01*
X534450Y79083D01*
X534783Y78583D01*
X535283Y78167D01*
X535950Y78000D01*
X536533Y78167D01*
X537033Y78500D01*
G01X540133Y78000D02*
Y81333D01*
G01Y80667D02*
X540550Y81000D01*
X540967Y81250D01*
X541550Y81333D01*
X541967Y81250D01*
X542467Y81000D01*
G01X545650Y80250D02*
X548317D01*
X548067Y80833D01*
X547650Y81167D01*
X547067Y81333D01*
X546483Y81250D01*
X545983Y81000D01*
X545650Y80417D01*
X545483Y79917D01*
Y79417D01*
X545650Y78917D01*
X546067Y78417D01*
X546567Y78083D01*
X547150Y78000D01*
X547733Y78167D01*
X548317Y78667D01*
G01X551250Y80250D02*
X553917D01*
X553667Y80833D01*
X553250Y81167D01*
X552667Y81333D01*
X552083Y81250D01*
X551583Y81000D01*
X551250Y80417D01*
X551083Y79917D01*
Y79417D01*
X551250Y78917D01*
X551667Y78417D01*
X552167Y78083D01*
X552750Y78000D01*
X553333Y78167D01*
X553917Y78667D01*
G01X556683Y78000D02*
Y81333D01*
G01Y80500D02*
X557017Y80917D01*
X557517Y81250D01*
X558183Y81333D01*
X558767Y81250D01*
X559267Y80917D01*
X559517Y80333D01*
Y78000D01*
G01X270750Y93667D02*
X271417Y93250D01*
X272167Y93000D01*
X272833D01*
X273500Y93250D01*
X274000Y93667D01*
X274250Y94250D01*
X274083Y94833D01*
X273667Y95333D01*
X272917Y95667D01*
X271917Y95833D01*
X271333Y96167D01*
X271083Y96750D01*
X271250Y97333D01*
X271667Y97750D01*
X272250Y98000D01*
X272833D01*
X273417Y97833D01*
X273917Y97417D01*
G01X278100Y93000D02*
X277600Y93083D01*
X277100Y93417D01*
X276767Y94000D01*
X276600Y94667D01*
X276767Y95333D01*
X277100Y95917D01*
X277600Y96250D01*
X278100Y96333D01*
X278600Y96250D01*
X279100Y95917D01*
X279433Y95333D01*
X279517Y94667D01*
X279433Y94000D01*
X279100Y93417D01*
X278600Y93083D01*
X278100Y93000D01*
G01X283700D02*
Y98000D01*
G01X290800D02*
Y93000D01*
G01Y93750D02*
X290467Y93333D01*
X289967Y93083D01*
X289383Y93000D01*
X288717Y93167D01*
X288217Y93583D01*
X287883Y94083D01*
X287800Y94667D01*
X287883Y95250D01*
X288217Y95750D01*
X288717Y96167D01*
X289383Y96333D01*
X289967Y96250D01*
X290383Y96083D01*
X290800Y95750D01*
G01X293650Y95250D02*
X296317D01*
X296067Y95833D01*
X295650Y96167D01*
X295067Y96333D01*
X294483Y96250D01*
X293983Y96000D01*
X293650Y95417D01*
X293483Y94917D01*
Y94417D01*
X293650Y93917D01*
X294067Y93417D01*
X294567Y93083D01*
X295150Y93000D01*
X295733Y93167D01*
X296317Y93667D01*
G01X299333Y93000D02*
Y96333D01*
G01Y95667D02*
X299750Y96000D01*
X300167Y96250D01*
X300750Y96333D01*
X301167Y96250D01*
X301667Y96000D01*
G01X309200Y93000D02*
Y96333D01*
G01Y95417D02*
X309450Y95833D01*
X309867Y96167D01*
X310450Y96333D01*
X311033Y96167D01*
X311450Y95833D01*
X311700Y95417D01*
Y93000D01*
G01Y95417D02*
X311950Y95833D01*
X312367Y96167D01*
X312950Y96333D01*
X313533Y96167D01*
X313950Y95833D01*
X314200Y95333D01*
Y93000D01*
G01X318800D02*
Y96333D01*
G01Y95750D02*
X318467Y96083D01*
X317967Y96250D01*
X317383Y96333D01*
X316800Y96167D01*
X316300Y95833D01*
X315967Y95333D01*
X315800Y94667D01*
X315967Y94000D01*
X316300Y93500D01*
X316800Y93167D01*
X317383Y93000D01*
X317967Y93083D01*
X318467Y93333D01*
X318800Y93667D01*
G01X321650Y93583D02*
X322067Y93250D01*
X322650Y93000D01*
X323150D01*
X323650Y93167D01*
X323983Y93417D01*
X324150Y93750D01*
X324067Y94250D01*
X323733Y94500D01*
X322233Y95000D01*
X321900Y95583D01*
X322067Y96000D01*
X322400Y96250D01*
X322900Y96333D01*
X323400Y96250D01*
X323900Y96000D01*
G01X327083Y93000D02*
Y98000D01*
G01X329750Y96333D02*
X327083Y94417D01*
G01X328167Y95167D02*
X329917Y93000D01*
G01X339700Y98000D02*
Y93000D01*
G01X338533Y96333D02*
X340867D01*
G01X343883Y93000D02*
Y98000D01*
G01Y95583D02*
X344300Y96000D01*
X344717Y96250D01*
X345383Y96333D01*
X345883Y96250D01*
X346467Y95917D01*
X346717Y95417D01*
Y93000D01*
G01X350900Y96333D02*
Y93000D01*
G01Y97667D02*
X350733Y97750D01*
Y97917D01*
X350900Y98000D01*
X351067Y97917D01*
Y97750D01*
X350900Y97667D01*
G01X357833Y95917D02*
X357250Y96250D01*
X356750Y96333D01*
X356083Y96167D01*
X355583Y95833D01*
X355250Y95250D01*
X355167Y94667D01*
X355250Y94083D01*
X355583Y93583D01*
X356083Y93167D01*
X356750Y93000D01*
X357333Y93167D01*
X357833Y93500D01*
G01X360683Y93000D02*
Y98000D01*
G01X363350Y96333D02*
X360683Y94417D01*
G01X361767Y95167D02*
X363517Y93000D01*
G01X366283D02*
Y96333D01*
G01Y95500D02*
X366617Y95917D01*
X367117Y96250D01*
X367783Y96333D01*
X368367Y96250D01*
X368867Y95917D01*
X369117Y95333D01*
Y93000D01*
G01X372050Y95250D02*
X374717D01*
X374467Y95833D01*
X374050Y96167D01*
X373467Y96333D01*
X372883Y96250D01*
X372383Y96000D01*
X372050Y95417D01*
X371883Y94917D01*
Y94417D01*
X372050Y93917D01*
X372467Y93417D01*
X372967Y93083D01*
X373550Y93000D01*
X374133Y93167D01*
X374717Y93667D01*
G01X377650Y93583D02*
X378067Y93250D01*
X378650Y93000D01*
X379150D01*
X379650Y93167D01*
X379983Y93417D01*
X380150Y93750D01*
X380067Y94250D01*
X379733Y94500D01*
X378233Y95000D01*
X377900Y95583D01*
X378067Y96000D01*
X378400Y96250D01*
X378900Y96333D01*
X379400Y96250D01*
X379900Y96000D01*
G01X383250Y93583D02*
X383667Y93250D01*
X384250Y93000D01*
X384750D01*
X385250Y93167D01*
X385583Y93417D01*
X385750Y93750D01*
X385667Y94250D01*
X385333Y94500D01*
X383833Y95000D01*
X383500Y95583D01*
X383667Y96000D01*
X384000Y96250D01*
X384500Y96333D01*
X385000Y96250D01*
X385500Y96000D01*
G01X394200Y91333D02*
Y96333D01*
G01Y95583D02*
X394617Y96000D01*
X395033Y96250D01*
X395700Y96333D01*
X396283Y96250D01*
X396867Y95833D01*
X397117Y95250D01*
X397200Y94667D01*
X397117Y94083D01*
X396867Y93500D01*
X396367Y93167D01*
X395700Y93000D01*
X395117Y93083D01*
X394533Y93333D01*
X394200Y93667D01*
G01X401300Y93000D02*
Y98000D01*
G01X405483Y96333D02*
Y94000D01*
X405817Y93417D01*
X406317Y93083D01*
X406900Y93000D01*
X407483Y93083D01*
X407983Y93417D01*
X408317Y94000D01*
G01Y93000D02*
Y96333D01*
G01X411250Y93583D02*
X411667Y93250D01*
X412250Y93000D01*
X412750D01*
X413250Y93167D01*
X413583Y93417D01*
X413750Y93750D01*
X413667Y94250D01*
X413333Y94500D01*
X411833Y95000D01*
X411500Y95583D01*
X411667Y96000D01*
X412000Y96250D01*
X412500Y96333D01*
X413000Y96250D01*
X413500Y96000D01*
G01X423700Y93000D02*
Y98000D01*
G01X428050Y95250D02*
X430717D01*
X430467Y95833D01*
X430050Y96167D01*
X429467Y96333D01*
X428883Y96250D01*
X428383Y96000D01*
X428050Y95417D01*
X427883Y94917D01*
Y94417D01*
X428050Y93917D01*
X428467Y93417D01*
X428967Y93083D01*
X429550Y93000D01*
X430133Y93167D01*
X430717Y93667D01*
G01X433733Y91750D02*
X434317Y91417D01*
X434983Y91333D01*
X435567Y91417D01*
X436067Y91833D01*
X436400Y92417D01*
Y96333D01*
G01Y95667D02*
X436067Y96000D01*
X435567Y96250D01*
X434983Y96333D01*
X434317Y96167D01*
X433900Y95833D01*
X433567Y95250D01*
X433400Y94667D01*
X433483Y94167D01*
X433817Y93583D01*
X434317Y93167D01*
X434983Y93000D01*
X435483Y93083D01*
X436067Y93417D01*
X436400Y93750D01*
G01X439250Y95250D02*
X441917D01*
X441667Y95833D01*
X441250Y96167D01*
X440667Y96333D01*
X440083Y96250D01*
X439583Y96000D01*
X439250Y95417D01*
X439083Y94917D01*
Y94417D01*
X439250Y93917D01*
X439667Y93417D01*
X440167Y93083D01*
X440750Y93000D01*
X441333Y93167D01*
X441917Y93667D01*
G01X444683Y93000D02*
Y96333D01*
G01Y95500D02*
X445017Y95917D01*
X445517Y96250D01*
X446183Y96333D01*
X446767Y96250D01*
X447267Y95917D01*
X447517Y95333D01*
Y93000D01*
G01X453200Y98000D02*
Y93000D01*
G01Y93750D02*
X452867Y93333D01*
X452367Y93083D01*
X451783Y93000D01*
X451117Y93167D01*
X450617Y93583D01*
X450283Y94083D01*
X450200Y94667D01*
X450283Y95250D01*
X450617Y95750D01*
X451117Y96167D01*
X451783Y96333D01*
X452367Y96250D01*
X452783Y96083D01*
X453200Y95750D01*
G01X462900Y98000D02*
Y93000D01*
G01X461733Y96333D02*
X464067D01*
G01X467083Y93000D02*
Y98000D01*
G01Y95583D02*
X467500Y96000D01*
X467917Y96250D01*
X468583Y96333D01*
X469083Y96250D01*
X469667Y95917D01*
X469917Y95417D01*
Y93000D01*
G01X474100Y96333D02*
Y93000D01*
G01Y97667D02*
X473933Y97750D01*
Y97917D01*
X474100Y98000D01*
X474267Y97917D01*
Y97750D01*
X474100Y97667D01*
G01X481033Y95917D02*
X480450Y96250D01*
X479950Y96333D01*
X479283Y96167D01*
X478783Y95833D01*
X478450Y95250D01*
X478367Y94667D01*
X478450Y94083D01*
X478783Y93583D01*
X479283Y93167D01*
X479950Y93000D01*
X480533Y93167D01*
X481033Y93500D01*
G01X483883Y93000D02*
Y98000D01*
G01X486550Y96333D02*
X483883Y94417D01*
G01X484967Y95167D02*
X486717Y93000D01*
G01X489483D02*
Y96333D01*
G01Y95500D02*
X489817Y95917D01*
X490317Y96250D01*
X490983Y96333D01*
X491567Y96250D01*
X492067Y95917D01*
X492317Y95333D01*
Y93000D01*
G01X495250Y95250D02*
X497917D01*
X497667Y95833D01*
X497250Y96167D01*
X496667Y96333D01*
X496083Y96250D01*
X495583Y96000D01*
X495250Y95417D01*
X495083Y94917D01*
Y94417D01*
X495250Y93917D01*
X495667Y93417D01*
X496167Y93083D01*
X496750Y93000D01*
X497333Y93167D01*
X497917Y93667D01*
G01X500850Y93583D02*
X501267Y93250D01*
X501850Y93000D01*
X502350D01*
X502850Y93167D01*
X503183Y93417D01*
X503350Y93750D01*
X503267Y94250D01*
X502933Y94500D01*
X501433Y95000D01*
X501100Y95583D01*
X501267Y96000D01*
X501600Y96250D01*
X502100Y96333D01*
X502600Y96250D01*
X503100Y96000D01*
G01X506450Y93583D02*
X506867Y93250D01*
X507450Y93000D01*
X507950D01*
X508450Y93167D01*
X508783Y93417D01*
X508950Y93750D01*
X508867Y94250D01*
X508533Y94500D01*
X507033Y95000D01*
X506700Y95583D01*
X506867Y96000D01*
X507200Y96250D01*
X507700Y96333D01*
X508200Y96250D01*
X508700Y96000D01*
G01X518900Y93000D02*
X518400Y93083D01*
X517900Y93417D01*
X517567Y94000D01*
X517400Y94667D01*
X517567Y95333D01*
X517900Y95917D01*
X518400Y96250D01*
X518900Y96333D01*
X519400Y96250D01*
X519900Y95917D01*
X520233Y95333D01*
X520317Y94667D01*
X520233Y94000D01*
X519900Y93417D01*
X519400Y93083D01*
X518900Y93000D01*
G01X523083D02*
Y96333D01*
G01Y95500D02*
X523417Y95917D01*
X523917Y96250D01*
X524583Y96333D01*
X525167Y96250D01*
X525667Y95917D01*
X525917Y95333D01*
Y93000D01*
G01X535700Y98000D02*
Y93000D01*
G01X534533Y96333D02*
X536867D01*
G01X540133Y93000D02*
Y96333D01*
G01Y95667D02*
X540550Y96000D01*
X540967Y96250D01*
X541550Y96333D01*
X541967Y96250D01*
X542467Y96000D01*
G01X548400Y93000D02*
Y96333D01*
G01Y95750D02*
X548067Y96083D01*
X547567Y96250D01*
X546983Y96333D01*
X546400Y96167D01*
X545900Y95833D01*
X545567Y95333D01*
X545400Y94667D01*
X545567Y94000D01*
X545900Y93500D01*
X546400Y93167D01*
X546983Y93000D01*
X547567Y93083D01*
X548067Y93333D01*
X548400Y93667D01*
G01X553833Y95917D02*
X553250Y96250D01*
X552750Y96333D01*
X552083Y96167D01*
X551583Y95833D01*
X551250Y95250D01*
X551167Y94667D01*
X551250Y94083D01*
X551583Y93583D01*
X552083Y93167D01*
X552750Y93000D01*
X553333Y93167D01*
X553833Y93500D01*
G01X556850Y95250D02*
X559517D01*
X559267Y95833D01*
X558850Y96167D01*
X558267Y96333D01*
X557683Y96250D01*
X557183Y96000D01*
X556850Y95417D01*
X556683Y94917D01*
Y94417D01*
X556850Y93917D01*
X557267Y93417D01*
X557767Y93083D01*
X558350Y93000D01*
X558933Y93167D01*
X559517Y93667D01*
G01X563700Y92833D02*
X563533Y92917D01*
Y93083D01*
X563700Y93167D01*
X563867Y93083D01*
Y92917D01*
X563700Y92833D01*
G01X272500Y108000D02*
Y113000D01*
G01X276850Y110250D02*
X279517D01*
X279267Y110833D01*
X278850Y111167D01*
X278267Y111333D01*
X277683Y111250D01*
X277183Y111000D01*
X276850Y110417D01*
X276683Y109917D01*
Y109417D01*
X276850Y108917D01*
X277267Y108417D01*
X277767Y108083D01*
X278350Y108000D01*
X278933Y108167D01*
X279517Y108667D01*
G01X282533Y106750D02*
X283117Y106417D01*
X283783Y106333D01*
X284367Y106417D01*
X284867Y106833D01*
X285200Y107417D01*
Y111333D01*
G01Y110667D02*
X284867Y111000D01*
X284367Y111250D01*
X283783Y111333D01*
X283117Y111167D01*
X282700Y110833D01*
X282367Y110250D01*
X282200Y109667D01*
X282283Y109167D01*
X282617Y108583D01*
X283117Y108167D01*
X283783Y108000D01*
X284283Y108083D01*
X284867Y108417D01*
X285200Y108750D01*
G01X288050Y110250D02*
X290717D01*
X290467Y110833D01*
X290050Y111167D01*
X289467Y111333D01*
X288883Y111250D01*
X288383Y111000D01*
X288050Y110417D01*
X287883Y109917D01*
Y109417D01*
X288050Y108917D01*
X288467Y108417D01*
X288967Y108083D01*
X289550Y108000D01*
X290133Y108167D01*
X290717Y108667D01*
G01X293483Y108000D02*
Y111333D01*
G01Y110500D02*
X293817Y110917D01*
X294317Y111250D01*
X294983Y111333D01*
X295567Y111250D01*
X296067Y110917D01*
X296317Y110333D01*
Y108000D01*
G01X302000Y113000D02*
Y108000D01*
G01Y108750D02*
X301667Y108333D01*
X301167Y108083D01*
X300583Y108000D01*
X299917Y108167D01*
X299417Y108583D01*
X299083Y109083D01*
X299000Y109667D01*
X299083Y110250D01*
X299417Y110750D01*
X299917Y111167D01*
X300583Y111333D01*
X301167Y111250D01*
X301583Y111083D01*
X302000Y110750D01*
G01X311700Y113000D02*
Y108000D01*
G01X310533Y111333D02*
X312867D01*
G01X315883Y108000D02*
Y113000D01*
G01Y110583D02*
X316300Y111000D01*
X316717Y111250D01*
X317383Y111333D01*
X317883Y111250D01*
X318467Y110917D01*
X318717Y110417D01*
Y108000D01*
G01X322900Y111333D02*
Y108000D01*
G01Y112667D02*
X322733Y112750D01*
Y112917D01*
X322900Y113000D01*
X323067Y112917D01*
Y112750D01*
X322900Y112667D01*
G01X329833Y110917D02*
X329250Y111250D01*
X328750Y111333D01*
X328083Y111167D01*
X327583Y110833D01*
X327250Y110250D01*
X327167Y109667D01*
X327250Y109083D01*
X327583Y108583D01*
X328083Y108167D01*
X328750Y108000D01*
X329333Y108167D01*
X329833Y108500D01*
G01X332683Y108000D02*
Y113000D01*
G01X335350Y111333D02*
X332683Y109417D01*
G01X333767Y110167D02*
X335517Y108000D01*
G01X338283D02*
Y111333D01*
G01Y110500D02*
X338617Y110917D01*
X339117Y111250D01*
X339783Y111333D01*
X340367Y111250D01*
X340867Y110917D01*
X341117Y110333D01*
Y108000D01*
G01X344050Y110250D02*
X346717D01*
X346467Y110833D01*
X346050Y111167D01*
X345467Y111333D01*
X344883Y111250D01*
X344383Y111000D01*
X344050Y110417D01*
X343883Y109917D01*
Y109417D01*
X344050Y108917D01*
X344467Y108417D01*
X344967Y108083D01*
X345550Y108000D01*
X346133Y108167D01*
X346717Y108667D01*
G01X349650Y108583D02*
X350067Y108250D01*
X350650Y108000D01*
X351150D01*
X351650Y108167D01*
X351983Y108417D01*
X352150Y108750D01*
X352067Y109250D01*
X351733Y109500D01*
X350233Y110000D01*
X349900Y110583D01*
X350067Y111000D01*
X350400Y111250D01*
X350900Y111333D01*
X351400Y111250D01*
X351900Y111000D01*
G01X355250Y108583D02*
X355667Y108250D01*
X356250Y108000D01*
X356750D01*
X357250Y108167D01*
X357583Y108417D01*
X357750Y108750D01*
X357667Y109250D01*
X357333Y109500D01*
X355833Y110000D01*
X355500Y110583D01*
X355667Y111000D01*
X356000Y111250D01*
X356500Y111333D01*
X357000Y111250D01*
X357500Y111000D01*
G01X367700Y108000D02*
X367200Y108083D01*
X366700Y108417D01*
X366367Y109000D01*
X366200Y109667D01*
X366367Y110333D01*
X366700Y110917D01*
X367200Y111250D01*
X367700Y111333D01*
X368200Y111250D01*
X368700Y110917D01*
X369033Y110333D01*
X369117Y109667D01*
X369033Y109000D01*
X368700Y108417D01*
X368200Y108083D01*
X367700Y108000D01*
G01X371883D02*
Y111333D01*
G01Y110500D02*
X372217Y110917D01*
X372717Y111250D01*
X373383Y111333D01*
X373967Y111250D01*
X374467Y110917D01*
X374717Y110333D01*
Y108000D01*
G01X385833Y110917D02*
X385250Y111250D01*
X384750Y111333D01*
X384083Y111167D01*
X383583Y110833D01*
X383250Y110250D01*
X383167Y109667D01*
X383250Y109083D01*
X383583Y108583D01*
X384083Y108167D01*
X384750Y108000D01*
X385333Y108167D01*
X385833Y108500D01*
G01X390100Y108000D02*
X389600Y108083D01*
X389100Y108417D01*
X388767Y109000D01*
X388600Y109667D01*
X388767Y110333D01*
X389100Y110917D01*
X389600Y111250D01*
X390100Y111333D01*
X390600Y111250D01*
X391100Y110917D01*
X391433Y110333D01*
X391517Y109667D01*
X391433Y109000D01*
X391100Y108417D01*
X390600Y108083D01*
X390100Y108000D01*
G01X394200Y106333D02*
Y111333D01*
G01Y110583D02*
X394617Y111000D01*
X395033Y111250D01*
X395700Y111333D01*
X396283Y111250D01*
X396867Y110833D01*
X397117Y110250D01*
X397200Y109667D01*
X397117Y109083D01*
X396867Y108500D01*
X396367Y108167D01*
X395700Y108000D01*
X395117Y108083D01*
X394533Y108333D01*
X394200Y108667D01*
G01X399800Y106333D02*
Y111333D01*
G01Y110583D02*
X400217Y111000D01*
X400633Y111250D01*
X401300Y111333D01*
X401883Y111250D01*
X402467Y110833D01*
X402717Y110250D01*
X402800Y109667D01*
X402717Y109083D01*
X402467Y108500D01*
X401967Y108167D01*
X401300Y108000D01*
X400717Y108083D01*
X400133Y108333D01*
X399800Y108667D01*
G01X405650Y110250D02*
X408317D01*
X408067Y110833D01*
X407650Y111167D01*
X407067Y111333D01*
X406483Y111250D01*
X405983Y111000D01*
X405650Y110417D01*
X405483Y109917D01*
Y109417D01*
X405650Y108917D01*
X406067Y108417D01*
X406567Y108083D01*
X407150Y108000D01*
X407733Y108167D01*
X408317Y108667D01*
G01X411333Y108000D02*
Y111333D01*
G01Y110667D02*
X411750Y111000D01*
X412167Y111250D01*
X412750Y111333D01*
X413167Y111250D01*
X413667Y111000D01*
G01X423283Y106333D02*
X422450Y107167D01*
X422033Y108000D01*
Y111333D01*
X422450Y112167D01*
X423283Y113000D01*
G01X427217Y111333D02*
X428217Y108000D01*
X429300Y111333D01*
X430383Y108000D01*
X431383Y111333D01*
G01X433483Y108000D02*
Y113000D01*
G01Y110583D02*
X433900Y111000D01*
X434317Y111250D01*
X434983Y111333D01*
X435483Y111250D01*
X436067Y110917D01*
X436317Y110417D01*
Y108000D01*
G01X440500Y111333D02*
Y108000D01*
G01Y112667D02*
X440333Y112750D01*
Y112917D01*
X440500Y113000D01*
X440667Y112917D01*
Y112750D01*
X440500Y112667D01*
G01X447433Y110917D02*
X446850Y111250D01*
X446350Y111333D01*
X445683Y111167D01*
X445183Y110833D01*
X444850Y110250D01*
X444767Y109667D01*
X444850Y109083D01*
X445183Y108583D01*
X445683Y108167D01*
X446350Y108000D01*
X446933Y108167D01*
X447433Y108500D01*
G01X450283Y108000D02*
Y113000D01*
G01Y110583D02*
X450700Y111000D01*
X451117Y111250D01*
X451783Y111333D01*
X452283Y111250D01*
X452867Y110917D01*
X453117Y110417D01*
Y108000D01*
G01X462900Y111333D02*
Y108000D01*
G01Y112667D02*
X462733Y112750D01*
Y112917D01*
X462900Y113000D01*
X463067Y112917D01*
Y112750D01*
X462900Y112667D01*
G01X467250Y108583D02*
X467667Y108250D01*
X468250Y108000D01*
X468750D01*
X469250Y108167D01*
X469583Y108417D01*
X469750Y108750D01*
X469667Y109250D01*
X469333Y109500D01*
X467833Y110000D01*
X467500Y110583D01*
X467667Y111000D01*
X468000Y111250D01*
X468500Y111333D01*
X469000Y111250D01*
X469500Y111000D01*
G01X478200Y108000D02*
Y113000D01*
G01Y110500D02*
X478617Y111000D01*
X479117Y111250D01*
X479617Y111333D01*
X480367Y111167D01*
X480867Y110833D01*
X481200Y110250D01*
Y109583D01*
X481033Y108917D01*
X480700Y108417D01*
X480117Y108083D01*
X479617Y108000D01*
X479117Y108083D01*
X478617Y108333D01*
X478200Y108750D01*
G01X484050Y110250D02*
X486717D01*
X486467Y110833D01*
X486050Y111167D01*
X485467Y111333D01*
X484883Y111250D01*
X484383Y111000D01*
X484050Y110417D01*
X483883Y109917D01*
Y109417D01*
X484050Y108917D01*
X484467Y108417D01*
X484967Y108083D01*
X485550Y108000D01*
X486133Y108167D01*
X486717Y108667D01*
G01X490900Y113000D02*
Y108000D01*
G01X489733Y111333D02*
X492067D01*
G01X496500Y113000D02*
Y108000D01*
G01X495333Y111333D02*
X497667D01*
G01X500850Y110250D02*
X503517D01*
X503267Y110833D01*
X502850Y111167D01*
X502267Y111333D01*
X501683Y111250D01*
X501183Y111000D01*
X500850Y110417D01*
X500683Y109917D01*
Y109417D01*
X500850Y108917D01*
X501267Y108417D01*
X501767Y108083D01*
X502350Y108000D01*
X502933Y108167D01*
X503517Y108667D01*
G01X506533Y108000D02*
Y111333D01*
G01Y110667D02*
X506950Y111000D01*
X507367Y111250D01*
X507950Y111333D01*
X508367Y111250D01*
X508867Y111000D01*
G01X513717Y106333D02*
X514550Y107167D01*
X514967Y108000D01*
Y111333D01*
X514550Y112167D01*
X513717Y113000D01*
G01X271250Y122083D02*
X271667Y121750D01*
X272250Y121500D01*
X272750D01*
X273250Y121667D01*
X273583Y121917D01*
X273750Y122250D01*
X273667Y122750D01*
X273333Y123000D01*
X271833Y123500D01*
X271500Y124083D01*
X271667Y124500D01*
X272000Y124750D01*
X272500Y124833D01*
X273000Y124750D01*
X273500Y124500D01*
G01X278100Y121500D02*
X277600Y121583D01*
X277100Y121917D01*
X276767Y122500D01*
X276600Y123167D01*
X276767Y123833D01*
X277100Y124417D01*
X277600Y124750D01*
X278100Y124833D01*
X278600Y124750D01*
X279100Y124417D01*
X279433Y123833D01*
X279517Y123167D01*
X279433Y122500D01*
X279100Y121917D01*
X278600Y121583D01*
X278100Y121500D01*
G01X283700D02*
Y126500D01*
G01X290800D02*
Y121500D01*
G01Y122250D02*
X290467Y121833D01*
X289967Y121583D01*
X289383Y121500D01*
X288717Y121667D01*
X288217Y122083D01*
X287883Y122583D01*
X287800Y123167D01*
X287883Y123750D01*
X288217Y124250D01*
X288717Y124667D01*
X289383Y124833D01*
X289967Y124750D01*
X290383Y124583D01*
X290800Y124250D01*
G01X293650Y123750D02*
X296317D01*
X296067Y124333D01*
X295650Y124667D01*
X295067Y124833D01*
X294483Y124750D01*
X293983Y124500D01*
X293650Y123917D01*
X293483Y123417D01*
Y122917D01*
X293650Y122417D01*
X294067Y121917D01*
X294567Y121583D01*
X295150Y121500D01*
X295733Y121667D01*
X296317Y122167D01*
G01X299333Y121500D02*
Y124833D01*
G01Y124167D02*
X299750Y124500D01*
X300167Y124750D01*
X300750Y124833D01*
X301167Y124750D01*
X301667Y124500D01*
G01X309200Y121500D02*
Y124833D01*
G01Y123917D02*
X309450Y124333D01*
X309867Y124667D01*
X310450Y124833D01*
X311033Y124667D01*
X311450Y124333D01*
X311700Y123917D01*
Y121500D01*
G01Y123917D02*
X311950Y124333D01*
X312367Y124667D01*
X312950Y124833D01*
X313533Y124667D01*
X313950Y124333D01*
X314200Y123833D01*
Y121500D01*
G01X318800D02*
Y124833D01*
G01Y124250D02*
X318467Y124583D01*
X317967Y124750D01*
X317383Y124833D01*
X316800Y124667D01*
X316300Y124333D01*
X315967Y123833D01*
X315800Y123167D01*
X315967Y122500D01*
X316300Y122000D01*
X316800Y121667D01*
X317383Y121500D01*
X317967Y121583D01*
X318467Y121833D01*
X318800Y122167D01*
G01X321650Y122083D02*
X322067Y121750D01*
X322650Y121500D01*
X323150D01*
X323650Y121667D01*
X323983Y121917D01*
X324150Y122250D01*
X324067Y122750D01*
X323733Y123000D01*
X322233Y123500D01*
X321900Y124083D01*
X322067Y124500D01*
X322400Y124750D01*
X322900Y124833D01*
X323400Y124750D01*
X323900Y124500D01*
G01X327083Y121500D02*
Y126500D01*
G01X329750Y124833D02*
X327083Y122917D01*
G01X328167Y123667D02*
X329917Y121500D01*
G01X339700Y126500D02*
Y121500D01*
G01X338533Y124833D02*
X340867D01*
G01X343883Y121500D02*
Y126500D01*
G01Y124083D02*
X344300Y124500D01*
X344717Y124750D01*
X345383Y124833D01*
X345883Y124750D01*
X346467Y124417D01*
X346717Y123917D01*
Y121500D01*
G01X350900Y124833D02*
Y121500D01*
G01Y126167D02*
X350733Y126250D01*
Y126417D01*
X350900Y126500D01*
X351067Y126417D01*
Y126250D01*
X350900Y126167D01*
G01X357833Y124417D02*
X357250Y124750D01*
X356750Y124833D01*
X356083Y124667D01*
X355583Y124333D01*
X355250Y123750D01*
X355167Y123167D01*
X355250Y122583D01*
X355583Y122083D01*
X356083Y121667D01*
X356750Y121500D01*
X357333Y121667D01*
X357833Y122000D01*
G01X360683Y121500D02*
Y126500D01*
G01X363350Y124833D02*
X360683Y122917D01*
G01X361767Y123667D02*
X363517Y121500D01*
G01X366283D02*
Y124833D01*
G01Y124000D02*
X366617Y124417D01*
X367117Y124750D01*
X367783Y124833D01*
X368367Y124750D01*
X368867Y124417D01*
X369117Y123833D01*
Y121500D01*
G01X372050Y123750D02*
X374717D01*
X374467Y124333D01*
X374050Y124667D01*
X373467Y124833D01*
X372883Y124750D01*
X372383Y124500D01*
X372050Y123917D01*
X371883Y123417D01*
Y122917D01*
X372050Y122417D01*
X372467Y121917D01*
X372967Y121583D01*
X373550Y121500D01*
X374133Y121667D01*
X374717Y122167D01*
G01X377650Y122083D02*
X378067Y121750D01*
X378650Y121500D01*
X379150D01*
X379650Y121667D01*
X379983Y121917D01*
X380150Y122250D01*
X380067Y122750D01*
X379733Y123000D01*
X378233Y123500D01*
X377900Y124083D01*
X378067Y124500D01*
X378400Y124750D01*
X378900Y124833D01*
X379400Y124750D01*
X379900Y124500D01*
G01X383250Y122083D02*
X383667Y121750D01*
X384250Y121500D01*
X384750D01*
X385250Y121667D01*
X385583Y121917D01*
X385750Y122250D01*
X385667Y122750D01*
X385333Y123000D01*
X383833Y123500D01*
X383500Y124083D01*
X383667Y124500D01*
X384000Y124750D01*
X384500Y124833D01*
X385000Y124750D01*
X385500Y124500D01*
G01X264000Y102000D02*
X694500D01*
G01X264000Y147000D02*
X694500D01*
G01X270667Y228750D02*
X271167Y228333D01*
X271750Y228083D01*
X272500Y228000D01*
X273250Y228167D01*
X273833Y228500D01*
X274250Y229083D01*
X274333Y229750D01*
X274167Y230417D01*
X273750Y230833D01*
X273167Y231167D01*
X272583Y231250D01*
X272000Y231167D01*
X271250Y230833D01*
X271500Y233000D01*
X273750D01*
G01X281200Y228000D02*
Y231333D01*
G01Y230417D02*
X281450Y230833D01*
X281867Y231167D01*
X282450Y231333D01*
X283033Y231167D01*
X283450Y230833D01*
X283700Y230417D01*
Y228000D01*
G01Y230417D02*
X283950Y230833D01*
X284367Y231167D01*
X284950Y231333D01*
X285533Y231167D01*
X285950Y230833D01*
X286200Y230333D01*
Y228000D01*
G01X289300Y231333D02*
Y228000D01*
G01Y232667D02*
X289133Y232750D01*
Y232917D01*
X289300Y233000D01*
X289467Y232917D01*
Y232750D01*
X289300Y232667D01*
G01X294900Y228000D02*
Y233000D01*
G01X307767Y228000D02*
X304433Y229667D01*
X307767Y231333D01*
G01X317300Y233000D02*
Y228000D01*
G01X316133Y231333D02*
X318467D01*
G01X321733Y228000D02*
Y231333D01*
G01Y230667D02*
X322150Y231000D01*
X322567Y231250D01*
X323150Y231333D01*
X323567Y231250D01*
X324067Y231000D01*
G01X330000Y228000D02*
Y231333D01*
G01Y230750D02*
X329667Y231083D01*
X329167Y231250D01*
X328583Y231333D01*
X328000Y231167D01*
X327500Y230833D01*
X327167Y230333D01*
X327000Y229667D01*
X327167Y229000D01*
X327500Y228500D01*
X328000Y228167D01*
X328583Y228000D01*
X329167Y228083D01*
X329667Y228333D01*
X330000Y228667D01*
G01X335433Y230917D02*
X334850Y231250D01*
X334350Y231333D01*
X333683Y231167D01*
X333183Y230833D01*
X332850Y230250D01*
X332767Y229667D01*
X332850Y229083D01*
X333183Y228583D01*
X333683Y228167D01*
X334350Y228000D01*
X334933Y228167D01*
X335433Y228500D01*
G01X338450Y230250D02*
X341117D01*
X340867Y230833D01*
X340450Y231167D01*
X339867Y231333D01*
X339283Y231250D01*
X338783Y231000D01*
X338450Y230417D01*
X338283Y229917D01*
Y229417D01*
X338450Y228917D01*
X338867Y228417D01*
X339367Y228083D01*
X339950Y228000D01*
X340533Y228167D01*
X341117Y228667D01*
G01X348817Y231333D02*
X349817Y228000D01*
X350900Y231333D01*
X351983Y228000D01*
X352983Y231333D01*
G01X356500D02*
Y228000D01*
G01Y232667D02*
X356333Y232750D01*
Y232917D01*
X356500Y233000D01*
X356667Y232917D01*
Y232750D01*
X356500Y232667D01*
G01X363600Y233000D02*
Y228000D01*
G01Y228750D02*
X363267Y228333D01*
X362767Y228083D01*
X362183Y228000D01*
X361517Y228167D01*
X361017Y228583D01*
X360683Y229083D01*
X360600Y229667D01*
X360683Y230250D01*
X361017Y230750D01*
X361517Y231167D01*
X362183Y231333D01*
X362767Y231250D01*
X363183Y231083D01*
X363600Y230750D01*
G01X367700Y233000D02*
Y228000D01*
G01X366533Y231333D02*
X368867D01*
G01X371883Y228000D02*
Y233000D01*
G01Y230583D02*
X372300Y231000D01*
X372717Y231250D01*
X373383Y231333D01*
X373883Y231250D01*
X374467Y230917D01*
X374717Y230417D01*
Y228000D01*
G01X386167D02*
X382833Y229667D01*
X386167Y231333D01*
G01X389017Y228917D02*
X391183D01*
G01Y230417D02*
X389017D01*
G01X401133Y228000D02*
X401300Y229083D01*
X401550Y230000D01*
X401883Y230833D01*
X402300Y231750D01*
X402967Y233000D01*
X399633D01*
G01X410000Y228000D02*
Y231333D01*
G01Y230417D02*
X410250Y230833D01*
X410667Y231167D01*
X411250Y231333D01*
X411833Y231167D01*
X412250Y230833D01*
X412500Y230417D01*
Y228000D01*
G01Y230417D02*
X412750Y230833D01*
X413167Y231167D01*
X413750Y231333D01*
X414333Y231167D01*
X414750Y230833D01*
X415000Y230333D01*
Y228000D01*
G01X418100Y231333D02*
Y228000D01*
G01Y232667D02*
X417933Y232750D01*
Y232917D01*
X418100Y233000D01*
X418267Y232917D01*
Y232750D01*
X418100Y232667D01*
G01X423700Y228000D02*
Y233000D01*
G01X272500Y218000D02*
Y213000D01*
G01X271333Y216333D02*
X273667D01*
G01X276933Y213000D02*
Y216333D01*
G01Y215667D02*
X277350Y216000D01*
X277767Y216250D01*
X278350Y216333D01*
X278767Y216250D01*
X279267Y216000D01*
G01X285200Y213000D02*
Y216333D01*
G01Y215750D02*
X284867Y216083D01*
X284367Y216250D01*
X283783Y216333D01*
X283200Y216167D01*
X282700Y215833D01*
X282367Y215333D01*
X282200Y214667D01*
X282367Y214000D01*
X282700Y213500D01*
X283200Y213167D01*
X283783Y213000D01*
X284367Y213083D01*
X284867Y213333D01*
X285200Y213667D01*
G01X290633Y215917D02*
X290050Y216250D01*
X289550Y216333D01*
X288883Y216167D01*
X288383Y215833D01*
X288050Y215250D01*
X287967Y214667D01*
X288050Y214083D01*
X288383Y213583D01*
X288883Y213167D01*
X289550Y213000D01*
X290133Y213167D01*
X290633Y213500D01*
G01X293650Y215250D02*
X296317D01*
X296067Y215833D01*
X295650Y216167D01*
X295067Y216333D01*
X294483Y216250D01*
X293983Y216000D01*
X293650Y215417D01*
X293483Y214917D01*
Y214417D01*
X293650Y213917D01*
X294067Y213417D01*
X294567Y213083D01*
X295150Y213000D01*
X295733Y213167D01*
X296317Y213667D01*
G01X304017Y216333D02*
X305017Y213000D01*
X306100Y216333D01*
X307183Y213000D01*
X308183Y216333D01*
G01X311700D02*
Y213000D01*
G01Y217667D02*
X311533Y217750D01*
Y217917D01*
X311700Y218000D01*
X311867Y217917D01*
Y217750D01*
X311700Y217667D01*
G01X318800Y218000D02*
Y213000D01*
G01Y213750D02*
X318467Y213333D01*
X317967Y213083D01*
X317383Y213000D01*
X316717Y213167D01*
X316217Y213583D01*
X315883Y214083D01*
X315800Y214667D01*
X315883Y215250D01*
X316217Y215750D01*
X316717Y216167D01*
X317383Y216333D01*
X317967Y216250D01*
X318383Y216083D01*
X318800Y215750D01*
G01X322900Y218000D02*
Y213000D01*
G01X321733Y216333D02*
X324067D01*
G01X327083Y213000D02*
Y218000D01*
G01Y215583D02*
X327500Y216000D01*
X327917Y216250D01*
X328583Y216333D01*
X329083Y216250D01*
X329667Y215917D01*
X329917Y215417D01*
Y213000D01*
G01X338033D02*
X341367Y214667D01*
X338033Y216333D01*
G01X350733Y213000D02*
X350900Y214083D01*
X351150Y215000D01*
X351483Y215833D01*
X351900Y216750D01*
X352567Y218000D01*
X349233D01*
G01X359600Y213000D02*
Y216333D01*
G01Y215417D02*
X359850Y215833D01*
X360267Y216167D01*
X360850Y216333D01*
X361433Y216167D01*
X361850Y215833D01*
X362100Y215417D01*
Y213000D01*
G01Y215417D02*
X362350Y215833D01*
X362767Y216167D01*
X363350Y216333D01*
X363933Y216167D01*
X364350Y215833D01*
X364600Y215333D01*
Y213000D01*
G01X367700Y216333D02*
Y213000D01*
G01Y217667D02*
X367533Y217750D01*
Y217917D01*
X367700Y218000D01*
X367867Y217917D01*
Y217750D01*
X367700Y217667D01*
G01X373300Y213000D02*
Y218000D01*
G01X272500Y198500D02*
Y193500D01*
G01X270583Y198500D02*
X274417D01*
G01X276683Y193500D02*
Y198500D01*
G01Y196083D02*
X277100Y196500D01*
X277517Y196750D01*
X278183Y196833D01*
X278683Y196750D01*
X279267Y196417D01*
X279517Y195917D01*
Y193500D01*
G01X282450Y195750D02*
X285117D01*
X284867Y196333D01*
X284450Y196667D01*
X283867Y196833D01*
X283283Y196750D01*
X282783Y196500D01*
X282450Y195917D01*
X282283Y195417D01*
Y194917D01*
X282450Y194417D01*
X282867Y193917D01*
X283367Y193583D01*
X283950Y193500D01*
X284533Y193667D01*
X285117Y194167D01*
G01X294900Y193500D02*
Y198500D01*
G01X302000Y193500D02*
Y196833D01*
G01Y196250D02*
X301667Y196583D01*
X301167Y196750D01*
X300583Y196833D01*
X300000Y196667D01*
X299500Y196333D01*
X299167Y195833D01*
X299000Y195167D01*
X299167Y194500D01*
X299500Y194000D01*
X300000Y193667D01*
X300583Y193500D01*
X301167Y193583D01*
X301667Y193833D01*
X302000Y194167D01*
G01X304933Y193500D02*
Y196833D01*
G01Y196167D02*
X305350Y196500D01*
X305767Y196750D01*
X306350Y196833D01*
X306767Y196750D01*
X307267Y196500D01*
G01X310533Y192250D02*
X311117Y191917D01*
X311783Y191833D01*
X312367Y191917D01*
X312867Y192333D01*
X313200Y192917D01*
Y196833D01*
G01Y196167D02*
X312867Y196500D01*
X312367Y196750D01*
X311783Y196833D01*
X311117Y196667D01*
X310700Y196333D01*
X310367Y195750D01*
X310200Y195167D01*
X310283Y194667D01*
X310617Y194083D01*
X311117Y193667D01*
X311783Y193500D01*
X312283Y193583D01*
X312867Y193917D01*
X313200Y194250D01*
G01X316050Y195750D02*
X318717D01*
X318467Y196333D01*
X318050Y196667D01*
X317467Y196833D01*
X316883Y196750D01*
X316383Y196500D01*
X316050Y195917D01*
X315883Y195417D01*
Y194917D01*
X316050Y194417D01*
X316467Y193917D01*
X316967Y193583D01*
X317550Y193500D01*
X318133Y193667D01*
X318717Y194167D01*
G01X321650Y194083D02*
X322067Y193750D01*
X322650Y193500D01*
X323150D01*
X323650Y193667D01*
X323983Y193917D01*
X324150Y194250D01*
X324067Y194750D01*
X323733Y195000D01*
X322233Y195500D01*
X321900Y196083D01*
X322067Y196500D01*
X322400Y196750D01*
X322900Y196833D01*
X323400Y196750D01*
X323900Y196500D01*
G01X328500Y198500D02*
Y193500D01*
G01X327333Y196833D02*
X329667D01*
G01X341200Y198500D02*
Y193500D01*
G01Y194250D02*
X340867Y193833D01*
X340367Y193583D01*
X339783Y193500D01*
X339117Y193667D01*
X338617Y194083D01*
X338283Y194583D01*
X338200Y195167D01*
X338283Y195750D01*
X338617Y196250D01*
X339117Y196667D01*
X339783Y196833D01*
X340367Y196750D01*
X340783Y196583D01*
X341200Y196250D01*
G01X345300Y196833D02*
Y193500D01*
G01Y198167D02*
X345133Y198250D01*
Y198417D01*
X345300Y198500D01*
X345467Y198417D01*
Y198250D01*
X345300Y198167D01*
G01X348400Y193500D02*
Y196833D01*
G01Y195917D02*
X348650Y196333D01*
X349067Y196667D01*
X349650Y196833D01*
X350233Y196667D01*
X350650Y196333D01*
X350900Y195917D01*
Y193500D01*
G01Y195917D02*
X351150Y196333D01*
X351567Y196667D01*
X352150Y196833D01*
X352733Y196667D01*
X353150Y196333D01*
X353400Y195833D01*
Y193500D01*
G01X355250Y195750D02*
X357917D01*
X357667Y196333D01*
X357250Y196667D01*
X356667Y196833D01*
X356083Y196750D01*
X355583Y196500D01*
X355250Y195917D01*
X355083Y195417D01*
Y194917D01*
X355250Y194417D01*
X355667Y193917D01*
X356167Y193583D01*
X356750Y193500D01*
X357333Y193667D01*
X357917Y194167D01*
G01X360683Y193500D02*
Y196833D01*
G01Y196000D02*
X361017Y196417D01*
X361517Y196750D01*
X362183Y196833D01*
X362767Y196750D01*
X363267Y196417D01*
X363517Y195833D01*
Y193500D01*
G01X366450Y194083D02*
X366867Y193750D01*
X367450Y193500D01*
X367950D01*
X368450Y193667D01*
X368783Y193917D01*
X368950Y194250D01*
X368867Y194750D01*
X368533Y195000D01*
X367033Y195500D01*
X366700Y196083D01*
X366867Y196500D01*
X367200Y196750D01*
X367700Y196833D01*
X368200Y196750D01*
X368700Y196500D01*
G01X373300Y196833D02*
Y193500D01*
G01Y198167D02*
X373133Y198250D01*
Y198417D01*
X373300Y198500D01*
X373467Y198417D01*
Y198250D01*
X373300Y198167D01*
G01X378900Y193500D02*
X378400Y193583D01*
X377900Y193917D01*
X377567Y194500D01*
X377400Y195167D01*
X377567Y195833D01*
X377900Y196417D01*
X378400Y196750D01*
X378900Y196833D01*
X379400Y196750D01*
X379900Y196417D01*
X380233Y195833D01*
X380317Y195167D01*
X380233Y194500D01*
X379900Y193917D01*
X379400Y193583D01*
X378900Y193500D01*
G01X383083D02*
Y196833D01*
G01Y196000D02*
X383417Y196417D01*
X383917Y196750D01*
X384583Y196833D01*
X385167Y196750D01*
X385667Y196417D01*
X385917Y195833D01*
Y193500D01*
G01X395700D02*
X395200Y193583D01*
X394700Y193917D01*
X394367Y194500D01*
X394200Y195167D01*
X394367Y195833D01*
X394700Y196417D01*
X395200Y196750D01*
X395700Y196833D01*
X396200Y196750D01*
X396700Y196417D01*
X397033Y195833D01*
X397117Y195167D01*
X397033Y194500D01*
X396700Y193917D01*
X396200Y193583D01*
X395700Y193500D01*
G01X400800D02*
Y197750D01*
X400967Y198167D01*
X401300Y198417D01*
X401800Y198500D01*
X402300Y198333D01*
X402550Y197917D01*
G01X401550Y196500D02*
X399883D01*
G01X411000Y191833D02*
Y196833D01*
G01Y196083D02*
X411417Y196500D01*
X411833Y196750D01*
X412500Y196833D01*
X413083Y196750D01*
X413667Y196333D01*
X413917Y195750D01*
X414000Y195167D01*
X413917Y194583D01*
X413667Y194000D01*
X413167Y193667D01*
X412500Y193500D01*
X411917Y193583D01*
X411333Y193833D01*
X411000Y194167D01*
G01X419600Y193500D02*
Y196833D01*
G01Y196250D02*
X419267Y196583D01*
X418767Y196750D01*
X418183Y196833D01*
X417600Y196667D01*
X417100Y196333D01*
X416767Y195833D01*
X416600Y195167D01*
X416767Y194500D01*
X417100Y194000D01*
X417600Y193667D01*
X418183Y193500D01*
X418767Y193583D01*
X419267Y193833D01*
X419600Y194167D01*
G01X425200Y198500D02*
Y193500D01*
G01Y194250D02*
X424867Y193833D01*
X424367Y193583D01*
X423783Y193500D01*
X423117Y193667D01*
X422617Y194083D01*
X422283Y194583D01*
X422200Y195167D01*
X422283Y195750D01*
X422617Y196250D01*
X423117Y196667D01*
X423783Y196833D01*
X424367Y196750D01*
X424783Y196583D01*
X425200Y196250D01*
G01X434900Y193500D02*
X434400Y193583D01*
X433900Y193917D01*
X433567Y194500D01*
X433400Y195167D01*
X433567Y195833D01*
X433900Y196417D01*
X434400Y196750D01*
X434900Y196833D01*
X435400Y196750D01*
X435900Y196417D01*
X436233Y195833D01*
X436317Y195167D01*
X436233Y194500D01*
X435900Y193917D01*
X435400Y193583D01*
X434900Y193500D01*
G01X439333D02*
Y196833D01*
G01Y196167D02*
X439750Y196500D01*
X440167Y196750D01*
X440750Y196833D01*
X441167Y196750D01*
X441667Y196500D01*
G01X453200Y198500D02*
Y193500D01*
G01Y194250D02*
X452867Y193833D01*
X452367Y193583D01*
X451783Y193500D01*
X451117Y193667D01*
X450617Y194083D01*
X450283Y194583D01*
X450200Y195167D01*
X450283Y195750D01*
X450617Y196250D01*
X451117Y196667D01*
X451783Y196833D01*
X452367Y196750D01*
X452783Y196583D01*
X453200Y196250D01*
G01X457300Y196833D02*
Y193500D01*
G01Y198167D02*
X457133Y198250D01*
Y198417D01*
X457300Y198500D01*
X457467Y198417D01*
Y198250D01*
X457300Y198167D01*
G01X464400Y193500D02*
Y196833D01*
G01Y196250D02*
X464067Y196583D01*
X463567Y196750D01*
X462983Y196833D01*
X462400Y196667D01*
X461900Y196333D01*
X461567Y195833D01*
X461400Y195167D01*
X461567Y194500D01*
X461900Y194000D01*
X462400Y193667D01*
X462983Y193500D01*
X463567Y193583D01*
X464067Y193833D01*
X464400Y194167D01*
G01X466000Y193500D02*
Y196833D01*
G01Y195917D02*
X466250Y196333D01*
X466667Y196667D01*
X467250Y196833D01*
X467833Y196667D01*
X468250Y196333D01*
X468500Y195917D01*
Y193500D01*
G01Y195917D02*
X468750Y196333D01*
X469167Y196667D01*
X469750Y196833D01*
X470333Y196667D01*
X470750Y196333D01*
X471000Y195833D01*
Y193500D01*
G01X472850Y195750D02*
X475517D01*
X475267Y196333D01*
X474850Y196667D01*
X474267Y196833D01*
X473683Y196750D01*
X473183Y196500D01*
X472850Y195917D01*
X472683Y195417D01*
Y194917D01*
X472850Y194417D01*
X473267Y193917D01*
X473767Y193583D01*
X474350Y193500D01*
X474933Y193667D01*
X475517Y194167D01*
G01X479700Y198500D02*
Y193500D01*
G01X478533Y196833D02*
X480867D01*
G01X484050Y195750D02*
X486717D01*
X486467Y196333D01*
X486050Y196667D01*
X485467Y196833D01*
X484883Y196750D01*
X484383Y196500D01*
X484050Y195917D01*
X483883Y195417D01*
Y194917D01*
X484050Y194417D01*
X484467Y193917D01*
X484967Y193583D01*
X485550Y193500D01*
X486133Y193667D01*
X486717Y194167D01*
G01X489733Y193500D02*
Y196833D01*
G01Y196167D02*
X490150Y196500D01*
X490567Y196750D01*
X491150Y196833D01*
X491567Y196750D01*
X492067Y196500D01*
G01X500433Y193500D02*
X503767Y195167D01*
X500433Y196833D01*
G01X513300Y193500D02*
Y198500D01*
X512300Y197500D01*
G01Y193500D02*
X514300D01*
G01X519900D02*
Y198500D01*
X516817Y194917D01*
X520983D01*
G01X527600Y193500D02*
Y196833D01*
G01Y195917D02*
X527850Y196333D01*
X528267Y196667D01*
X528850Y196833D01*
X529433Y196667D01*
X529850Y196333D01*
X530100Y195917D01*
Y193500D01*
G01Y195917D02*
X530350Y196333D01*
X530767Y196667D01*
X531350Y196833D01*
X531933Y196667D01*
X532350Y196333D01*
X532600Y195833D01*
Y193500D01*
G01X535700Y196833D02*
Y193500D01*
G01Y198167D02*
X535533Y198250D01*
Y198417D01*
X535700Y198500D01*
X535867Y198417D01*
Y198250D01*
X535700Y198167D01*
G01X541300Y193500D02*
Y198500D01*
G01X272500Y174500D02*
Y169500D01*
G01X270583Y174500D02*
X274417D01*
G01X276683Y169500D02*
Y174500D01*
G01Y172083D02*
X277100Y172500D01*
X277517Y172750D01*
X278183Y172833D01*
X278683Y172750D01*
X279267Y172417D01*
X279517Y171917D01*
Y169500D01*
G01X282450Y171750D02*
X285117D01*
X284867Y172333D01*
X284450Y172667D01*
X283867Y172833D01*
X283283Y172750D01*
X282783Y172500D01*
X282450Y171917D01*
X282283Y171417D01*
Y170917D01*
X282450Y170417D01*
X282867Y169917D01*
X283367Y169583D01*
X283950Y169500D01*
X284533Y169667D01*
X285117Y170167D01*
G01X294900Y169500D02*
Y174500D01*
G01X302000Y169500D02*
Y172833D01*
G01Y172250D02*
X301667Y172583D01*
X301167Y172750D01*
X300583Y172833D01*
X300000Y172667D01*
X299500Y172333D01*
X299167Y171833D01*
X299000Y171167D01*
X299167Y170500D01*
X299500Y170000D01*
X300000Y169667D01*
X300583Y169500D01*
X301167Y169583D01*
X301667Y169833D01*
X302000Y170167D01*
G01X304933Y169500D02*
Y172833D01*
G01Y172167D02*
X305350Y172500D01*
X305767Y172750D01*
X306350Y172833D01*
X306767Y172750D01*
X307267Y172500D01*
G01X310533Y168250D02*
X311117Y167917D01*
X311783Y167833D01*
X312367Y167917D01*
X312867Y168333D01*
X313200Y168917D01*
Y172833D01*
G01Y172167D02*
X312867Y172500D01*
X312367Y172750D01*
X311783Y172833D01*
X311117Y172667D01*
X310700Y172333D01*
X310367Y171750D01*
X310200Y171167D01*
X310283Y170667D01*
X310617Y170083D01*
X311117Y169667D01*
X311783Y169500D01*
X312283Y169583D01*
X312867Y169917D01*
X313200Y170250D01*
G01X316050Y171750D02*
X318717D01*
X318467Y172333D01*
X318050Y172667D01*
X317467Y172833D01*
X316883Y172750D01*
X316383Y172500D01*
X316050Y171917D01*
X315883Y171417D01*
Y170917D01*
X316050Y170417D01*
X316467Y169917D01*
X316967Y169583D01*
X317550Y169500D01*
X318133Y169667D01*
X318717Y170167D01*
G01X321650Y170083D02*
X322067Y169750D01*
X322650Y169500D01*
X323150D01*
X323650Y169667D01*
X323983Y169917D01*
X324150Y170250D01*
X324067Y170750D01*
X323733Y171000D01*
X322233Y171500D01*
X321900Y172083D01*
X322067Y172500D01*
X322400Y172750D01*
X322900Y172833D01*
X323400Y172750D01*
X323900Y172500D01*
G01X328500Y174500D02*
Y169500D01*
G01X327333Y172833D02*
X329667D01*
G01X341200Y174500D02*
Y169500D01*
G01Y170250D02*
X340867Y169833D01*
X340367Y169583D01*
X339783Y169500D01*
X339117Y169667D01*
X338617Y170083D01*
X338283Y170583D01*
X338200Y171167D01*
X338283Y171750D01*
X338617Y172250D01*
X339117Y172667D01*
X339783Y172833D01*
X340367Y172750D01*
X340783Y172583D01*
X341200Y172250D01*
G01X345300Y172833D02*
Y169500D01*
G01Y174167D02*
X345133Y174250D01*
Y174417D01*
X345300Y174500D01*
X345467Y174417D01*
Y174250D01*
X345300Y174167D01*
G01X348400Y169500D02*
Y172833D01*
G01Y171917D02*
X348650Y172333D01*
X349067Y172667D01*
X349650Y172833D01*
X350233Y172667D01*
X350650Y172333D01*
X350900Y171917D01*
Y169500D01*
G01Y171917D02*
X351150Y172333D01*
X351567Y172667D01*
X352150Y172833D01*
X352733Y172667D01*
X353150Y172333D01*
X353400Y171833D01*
Y169500D01*
G01X355250Y171750D02*
X357917D01*
X357667Y172333D01*
X357250Y172667D01*
X356667Y172833D01*
X356083Y172750D01*
X355583Y172500D01*
X355250Y171917D01*
X355083Y171417D01*
Y170917D01*
X355250Y170417D01*
X355667Y169917D01*
X356167Y169583D01*
X356750Y169500D01*
X357333Y169667D01*
X357917Y170167D01*
G01X360683Y169500D02*
Y172833D01*
G01Y172000D02*
X361017Y172417D01*
X361517Y172750D01*
X362183Y172833D01*
X362767Y172750D01*
X363267Y172417D01*
X363517Y171833D01*
Y169500D01*
G01X366450Y170083D02*
X366867Y169750D01*
X367450Y169500D01*
X367950D01*
X368450Y169667D01*
X368783Y169917D01*
X368950Y170250D01*
X368867Y170750D01*
X368533Y171000D01*
X367033Y171500D01*
X366700Y172083D01*
X366867Y172500D01*
X367200Y172750D01*
X367700Y172833D01*
X368200Y172750D01*
X368700Y172500D01*
G01X373300Y172833D02*
Y169500D01*
G01Y174167D02*
X373133Y174250D01*
Y174417D01*
X373300Y174500D01*
X373467Y174417D01*
Y174250D01*
X373300Y174167D01*
G01X378900Y169500D02*
X378400Y169583D01*
X377900Y169917D01*
X377567Y170500D01*
X377400Y171167D01*
X377567Y171833D01*
X377900Y172417D01*
X378400Y172750D01*
X378900Y172833D01*
X379400Y172750D01*
X379900Y172417D01*
X380233Y171833D01*
X380317Y171167D01*
X380233Y170500D01*
X379900Y169917D01*
X379400Y169583D01*
X378900Y169500D01*
G01X383083D02*
Y172833D01*
G01Y172000D02*
X383417Y172417D01*
X383917Y172750D01*
X384583Y172833D01*
X385167Y172750D01*
X385667Y172417D01*
X385917Y171833D01*
Y169500D01*
G01X395700D02*
X395200Y169583D01*
X394700Y169917D01*
X394367Y170500D01*
X394200Y171167D01*
X394367Y171833D01*
X394700Y172417D01*
X395200Y172750D01*
X395700Y172833D01*
X396200Y172750D01*
X396700Y172417D01*
X397033Y171833D01*
X397117Y171167D01*
X397033Y170500D01*
X396700Y169917D01*
X396200Y169583D01*
X395700Y169500D01*
G01X400800D02*
Y173750D01*
X400967Y174167D01*
X401300Y174417D01*
X401800Y174500D01*
X402300Y174333D01*
X402550Y173917D01*
G01X401550Y172500D02*
X399883D01*
G01X411000Y167833D02*
Y172833D01*
G01Y172083D02*
X411417Y172500D01*
X411833Y172750D01*
X412500Y172833D01*
X413083Y172750D01*
X413667Y172333D01*
X413917Y171750D01*
X414000Y171167D01*
X413917Y170583D01*
X413667Y170000D01*
X413167Y169667D01*
X412500Y169500D01*
X411917Y169583D01*
X411333Y169833D01*
X411000Y170167D01*
G01X419600Y169500D02*
Y172833D01*
G01Y172250D02*
X419267Y172583D01*
X418767Y172750D01*
X418183Y172833D01*
X417600Y172667D01*
X417100Y172333D01*
X416767Y171833D01*
X416600Y171167D01*
X416767Y170500D01*
X417100Y170000D01*
X417600Y169667D01*
X418183Y169500D01*
X418767Y169583D01*
X419267Y169833D01*
X419600Y170167D01*
G01X425200Y174500D02*
Y169500D01*
G01Y170250D02*
X424867Y169833D01*
X424367Y169583D01*
X423783Y169500D01*
X423117Y169667D01*
X422617Y170083D01*
X422283Y170583D01*
X422200Y171167D01*
X422283Y171750D01*
X422617Y172250D01*
X423117Y172667D01*
X423783Y172833D01*
X424367Y172750D01*
X424783Y172583D01*
X425200Y172250D01*
G01X434900Y169500D02*
X434400Y169583D01*
X433900Y169917D01*
X433567Y170500D01*
X433400Y171167D01*
X433567Y171833D01*
X433900Y172417D01*
X434400Y172750D01*
X434900Y172833D01*
X435400Y172750D01*
X435900Y172417D01*
X436233Y171833D01*
X436317Y171167D01*
X436233Y170500D01*
X435900Y169917D01*
X435400Y169583D01*
X434900Y169500D01*
G01X439333D02*
Y172833D01*
G01Y172167D02*
X439750Y172500D01*
X440167Y172750D01*
X440750Y172833D01*
X441167Y172750D01*
X441667Y172500D01*
G01X453200Y174500D02*
Y169500D01*
G01Y170250D02*
X452867Y169833D01*
X452367Y169583D01*
X451783Y169500D01*
X451117Y169667D01*
X450617Y170083D01*
X450283Y170583D01*
X450200Y171167D01*
X450283Y171750D01*
X450617Y172250D01*
X451117Y172667D01*
X451783Y172833D01*
X452367Y172750D01*
X452783Y172583D01*
X453200Y172250D01*
G01X457300Y172833D02*
Y169500D01*
G01Y174167D02*
X457133Y174250D01*
Y174417D01*
X457300Y174500D01*
X457467Y174417D01*
Y174250D01*
X457300Y174167D01*
G01X464400Y169500D02*
Y172833D01*
G01Y172250D02*
X464067Y172583D01*
X463567Y172750D01*
X462983Y172833D01*
X462400Y172667D01*
X461900Y172333D01*
X461567Y171833D01*
X461400Y171167D01*
X461567Y170500D01*
X461900Y170000D01*
X462400Y169667D01*
X462983Y169500D01*
X463567Y169583D01*
X464067Y169833D01*
X464400Y170167D01*
G01X466000Y169500D02*
Y172833D01*
G01Y171917D02*
X466250Y172333D01*
X466667Y172667D01*
X467250Y172833D01*
X467833Y172667D01*
X468250Y172333D01*
X468500Y171917D01*
Y169500D01*
G01Y171917D02*
X468750Y172333D01*
X469167Y172667D01*
X469750Y172833D01*
X470333Y172667D01*
X470750Y172333D01*
X471000Y171833D01*
Y169500D01*
G01X472850Y171750D02*
X475517D01*
X475267Y172333D01*
X474850Y172667D01*
X474267Y172833D01*
X473683Y172750D01*
X473183Y172500D01*
X472850Y171917D01*
X472683Y171417D01*
Y170917D01*
X472850Y170417D01*
X473267Y169917D01*
X473767Y169583D01*
X474350Y169500D01*
X474933Y169667D01*
X475517Y170167D01*
G01X479700Y174500D02*
Y169500D01*
G01X478533Y172833D02*
X480867D01*
G01X484050Y171750D02*
X486717D01*
X486467Y172333D01*
X486050Y172667D01*
X485467Y172833D01*
X484883Y172750D01*
X484383Y172500D01*
X484050Y171917D01*
X483883Y171417D01*
Y170917D01*
X484050Y170417D01*
X484467Y169917D01*
X484967Y169583D01*
X485550Y169500D01*
X486133Y169667D01*
X486717Y170167D01*
G01X489733Y169500D02*
Y172833D01*
G01Y172167D02*
X490150Y172500D01*
X490567Y172750D01*
X491150Y172833D01*
X491567Y172750D01*
X492067Y172500D01*
G01X503767Y169500D02*
X500433Y171167D01*
X503767Y172833D01*
G01X506617Y170417D02*
X508783D01*
G01Y171917D02*
X506617D01*
G01X518900Y169500D02*
Y174500D01*
X517900Y173500D01*
G01Y169500D02*
X519900D01*
G01X525500D02*
Y174500D01*
X522417Y170917D01*
X526583D01*
G01X533200Y169500D02*
Y172833D01*
G01Y171917D02*
X533450Y172333D01*
X533867Y172667D01*
X534450Y172833D01*
X535033Y172667D01*
X535450Y172333D01*
X535700Y171917D01*
Y169500D01*
G01Y171917D02*
X535950Y172333D01*
X536367Y172667D01*
X536950Y172833D01*
X537533Y172667D01*
X537950Y172333D01*
X538200Y171833D01*
Y169500D01*
G01X541300Y172833D02*
Y169500D01*
G01Y174167D02*
X541133Y174250D01*
Y174417D01*
X541300Y174500D01*
X541467Y174417D01*
Y174250D01*
X541300Y174167D01*
G01X546900Y169500D02*
Y174500D01*
G01X272500Y156500D02*
Y151500D01*
G01X270583Y156500D02*
X274417D01*
G01X276683Y151500D02*
Y156500D01*
G01Y154083D02*
X277100Y154500D01*
X277517Y154750D01*
X278183Y154833D01*
X278683Y154750D01*
X279267Y154417D01*
X279517Y153917D01*
Y151500D01*
G01X282450Y153750D02*
X285117D01*
X284867Y154333D01*
X284450Y154667D01*
X283867Y154833D01*
X283283Y154750D01*
X282783Y154500D01*
X282450Y153917D01*
X282283Y153417D01*
Y152917D01*
X282450Y152417D01*
X282867Y151917D01*
X283367Y151583D01*
X283950Y151500D01*
X284533Y151667D01*
X285117Y152167D01*
G01X294900Y151500D02*
Y156500D01*
G01X302000Y151500D02*
Y154833D01*
G01Y154250D02*
X301667Y154583D01*
X301167Y154750D01*
X300583Y154833D01*
X300000Y154667D01*
X299500Y154333D01*
X299167Y153833D01*
X299000Y153167D01*
X299167Y152500D01*
X299500Y152000D01*
X300000Y151667D01*
X300583Y151500D01*
X301167Y151583D01*
X301667Y151833D01*
X302000Y152167D01*
G01X304933Y151500D02*
Y154833D01*
G01Y154167D02*
X305350Y154500D01*
X305767Y154750D01*
X306350Y154833D01*
X306767Y154750D01*
X307267Y154500D01*
G01X310533Y150250D02*
X311117Y149917D01*
X311783Y149833D01*
X312367Y149917D01*
X312867Y150333D01*
X313200Y150917D01*
Y154833D01*
G01Y154167D02*
X312867Y154500D01*
X312367Y154750D01*
X311783Y154833D01*
X311117Y154667D01*
X310700Y154333D01*
X310367Y153750D01*
X310200Y153167D01*
X310283Y152667D01*
X310617Y152083D01*
X311117Y151667D01*
X311783Y151500D01*
X312283Y151583D01*
X312867Y151917D01*
X313200Y152250D01*
G01X316050Y153750D02*
X318717D01*
X318467Y154333D01*
X318050Y154667D01*
X317467Y154833D01*
X316883Y154750D01*
X316383Y154500D01*
X316050Y153917D01*
X315883Y153417D01*
Y152917D01*
X316050Y152417D01*
X316467Y151917D01*
X316967Y151583D01*
X317550Y151500D01*
X318133Y151667D01*
X318717Y152167D01*
G01X321650Y152083D02*
X322067Y151750D01*
X322650Y151500D01*
X323150D01*
X323650Y151667D01*
X323983Y151917D01*
X324150Y152250D01*
X324067Y152750D01*
X323733Y153000D01*
X322233Y153500D01*
X321900Y154083D01*
X322067Y154500D01*
X322400Y154750D01*
X322900Y154833D01*
X323400Y154750D01*
X323900Y154500D01*
G01X328500Y156500D02*
Y151500D01*
G01X327333Y154833D02*
X329667D01*
G01X341200Y156500D02*
Y151500D01*
G01Y152250D02*
X340867Y151833D01*
X340367Y151583D01*
X339783Y151500D01*
X339117Y151667D01*
X338617Y152083D01*
X338283Y152583D01*
X338200Y153167D01*
X338283Y153750D01*
X338617Y154250D01*
X339117Y154667D01*
X339783Y154833D01*
X340367Y154750D01*
X340783Y154583D01*
X341200Y154250D01*
G01X345300Y154833D02*
Y151500D01*
G01Y156167D02*
X345133Y156250D01*
Y156417D01*
X345300Y156500D01*
X345467Y156417D01*
Y156250D01*
X345300Y156167D01*
G01X348400Y151500D02*
Y154833D01*
G01Y153917D02*
X348650Y154333D01*
X349067Y154667D01*
X349650Y154833D01*
X350233Y154667D01*
X350650Y154333D01*
X350900Y153917D01*
Y151500D01*
G01Y153917D02*
X351150Y154333D01*
X351567Y154667D01*
X352150Y154833D01*
X352733Y154667D01*
X353150Y154333D01*
X353400Y153833D01*
Y151500D01*
G01X355250Y153750D02*
X357917D01*
X357667Y154333D01*
X357250Y154667D01*
X356667Y154833D01*
X356083Y154750D01*
X355583Y154500D01*
X355250Y153917D01*
X355083Y153417D01*
Y152917D01*
X355250Y152417D01*
X355667Y151917D01*
X356167Y151583D01*
X356750Y151500D01*
X357333Y151667D01*
X357917Y152167D01*
G01X360683Y151500D02*
Y154833D01*
G01Y154000D02*
X361017Y154417D01*
X361517Y154750D01*
X362183Y154833D01*
X362767Y154750D01*
X363267Y154417D01*
X363517Y153833D01*
Y151500D01*
G01X366450Y152083D02*
X366867Y151750D01*
X367450Y151500D01*
X367950D01*
X368450Y151667D01*
X368783Y151917D01*
X368950Y152250D01*
X368867Y152750D01*
X368533Y153000D01*
X367033Y153500D01*
X366700Y154083D01*
X366867Y154500D01*
X367200Y154750D01*
X367700Y154833D01*
X368200Y154750D01*
X368700Y154500D01*
G01X373300Y154833D02*
Y151500D01*
G01Y156167D02*
X373133Y156250D01*
Y156417D01*
X373300Y156500D01*
X373467Y156417D01*
Y156250D01*
X373300Y156167D01*
G01X378900Y151500D02*
X378400Y151583D01*
X377900Y151917D01*
X377567Y152500D01*
X377400Y153167D01*
X377567Y153833D01*
X377900Y154417D01*
X378400Y154750D01*
X378900Y154833D01*
X379400Y154750D01*
X379900Y154417D01*
X380233Y153833D01*
X380317Y153167D01*
X380233Y152500D01*
X379900Y151917D01*
X379400Y151583D01*
X378900Y151500D01*
G01X383083D02*
Y154833D01*
G01Y154000D02*
X383417Y154417D01*
X383917Y154750D01*
X384583Y154833D01*
X385167Y154750D01*
X385667Y154417D01*
X385917Y153833D01*
Y151500D01*
G01X395700D02*
X395200Y151583D01*
X394700Y151917D01*
X394367Y152500D01*
X394200Y153167D01*
X394367Y153833D01*
X394700Y154417D01*
X395200Y154750D01*
X395700Y154833D01*
X396200Y154750D01*
X396700Y154417D01*
X397033Y153833D01*
X397117Y153167D01*
X397033Y152500D01*
X396700Y151917D01*
X396200Y151583D01*
X395700Y151500D01*
G01X400800D02*
Y155750D01*
X400967Y156167D01*
X401300Y156417D01*
X401800Y156500D01*
X402300Y156333D01*
X402550Y155917D01*
G01X401550Y154500D02*
X399883D01*
G01X411000Y149833D02*
Y154833D01*
G01Y154083D02*
X411417Y154500D01*
X411833Y154750D01*
X412500Y154833D01*
X413083Y154750D01*
X413667Y154333D01*
X413917Y153750D01*
X414000Y153167D01*
X413917Y152583D01*
X413667Y152000D01*
X413167Y151667D01*
X412500Y151500D01*
X411917Y151583D01*
X411333Y151833D01*
X411000Y152167D01*
G01X419600Y151500D02*
Y154833D01*
G01Y154250D02*
X419267Y154583D01*
X418767Y154750D01*
X418183Y154833D01*
X417600Y154667D01*
X417100Y154333D01*
X416767Y153833D01*
X416600Y153167D01*
X416767Y152500D01*
X417100Y152000D01*
X417600Y151667D01*
X418183Y151500D01*
X418767Y151583D01*
X419267Y151833D01*
X419600Y152167D01*
G01X425200Y156500D02*
Y151500D01*
G01Y152250D02*
X424867Y151833D01*
X424367Y151583D01*
X423783Y151500D01*
X423117Y151667D01*
X422617Y152083D01*
X422283Y152583D01*
X422200Y153167D01*
X422283Y153750D01*
X422617Y154250D01*
X423117Y154667D01*
X423783Y154833D01*
X424367Y154750D01*
X424783Y154583D01*
X425200Y154250D01*
G01X434900Y151500D02*
X434400Y151583D01*
X433900Y151917D01*
X433567Y152500D01*
X433400Y153167D01*
X433567Y153833D01*
X433900Y154417D01*
X434400Y154750D01*
X434900Y154833D01*
X435400Y154750D01*
X435900Y154417D01*
X436233Y153833D01*
X436317Y153167D01*
X436233Y152500D01*
X435900Y151917D01*
X435400Y151583D01*
X434900Y151500D01*
G01X439333D02*
Y154833D01*
G01Y154167D02*
X439750Y154500D01*
X440167Y154750D01*
X440750Y154833D01*
X441167Y154750D01*
X441667Y154500D01*
G01X453200Y156500D02*
Y151500D01*
G01Y152250D02*
X452867Y151833D01*
X452367Y151583D01*
X451783Y151500D01*
X451117Y151667D01*
X450617Y152083D01*
X450283Y152583D01*
X450200Y153167D01*
X450283Y153750D01*
X450617Y154250D01*
X451117Y154667D01*
X451783Y154833D01*
X452367Y154750D01*
X452783Y154583D01*
X453200Y154250D01*
G01X457300Y154833D02*
Y151500D01*
G01Y156167D02*
X457133Y156250D01*
Y156417D01*
X457300Y156500D01*
X457467Y156417D01*
Y156250D01*
X457300Y156167D01*
G01X464400Y151500D02*
Y154833D01*
G01Y154250D02*
X464067Y154583D01*
X463567Y154750D01*
X462983Y154833D01*
X462400Y154667D01*
X461900Y154333D01*
X461567Y153833D01*
X461400Y153167D01*
X461567Y152500D01*
X461900Y152000D01*
X462400Y151667D01*
X462983Y151500D01*
X463567Y151583D01*
X464067Y151833D01*
X464400Y152167D01*
G01X466000Y151500D02*
Y154833D01*
G01Y153917D02*
X466250Y154333D01*
X466667Y154667D01*
X467250Y154833D01*
X467833Y154667D01*
X468250Y154333D01*
X468500Y153917D01*
Y151500D01*
G01Y153917D02*
X468750Y154333D01*
X469167Y154667D01*
X469750Y154833D01*
X470333Y154667D01*
X470750Y154333D01*
X471000Y153833D01*
Y151500D01*
G01X472850Y153750D02*
X475517D01*
X475267Y154333D01*
X474850Y154667D01*
X474267Y154833D01*
X473683Y154750D01*
X473183Y154500D01*
X472850Y153917D01*
X472683Y153417D01*
Y152917D01*
X472850Y152417D01*
X473267Y151917D01*
X473767Y151583D01*
X474350Y151500D01*
X474933Y151667D01*
X475517Y152167D01*
G01X479700Y156500D02*
Y151500D01*
G01X478533Y154833D02*
X480867D01*
G01X484050Y153750D02*
X486717D01*
X486467Y154333D01*
X486050Y154667D01*
X485467Y154833D01*
X484883Y154750D01*
X484383Y154500D01*
X484050Y153917D01*
X483883Y153417D01*
Y152917D01*
X484050Y152417D01*
X484467Y151917D01*
X484967Y151583D01*
X485550Y151500D01*
X486133Y151667D01*
X486717Y152167D01*
G01X489733Y151500D02*
Y154833D01*
G01Y154167D02*
X490150Y154500D01*
X490567Y154750D01*
X491150Y154833D01*
X491567Y154750D01*
X492067Y154500D01*
G01X500433Y151500D02*
X503767Y153167D01*
X500433Y154833D01*
G01X507700Y151500D02*
Y156500D01*
X506700Y155500D01*
G01Y151500D02*
X508700D01*
G01X514300D02*
Y156500D01*
X511217Y152917D01*
X515383D01*
G01X522000Y151500D02*
Y154833D01*
G01Y153917D02*
X522250Y154333D01*
X522667Y154667D01*
X523250Y154833D01*
X523833Y154667D01*
X524250Y154333D01*
X524500Y153917D01*
Y151500D01*
G01Y153917D02*
X524750Y154333D01*
X525167Y154667D01*
X525750Y154833D01*
X526333Y154667D01*
X526750Y154333D01*
X527000Y153833D01*
Y151500D01*
G01X530100Y154833D02*
Y151500D01*
G01Y156167D02*
X529933Y156250D01*
Y156417D01*
X530100Y156500D01*
X530267Y156417D01*
Y156250D01*
X530100Y156167D01*
G01X535700Y151500D02*
Y156500D01*
G01X264000Y183000D02*
X694500D01*
G01X264000Y222000D02*
X694500D01*
G01X271250Y290083D02*
X271667Y289750D01*
X272250Y289500D01*
X272750D01*
X273250Y289667D01*
X273583Y289917D01*
X273750Y290250D01*
X273667Y290750D01*
X273333Y291000D01*
X271833Y291500D01*
X271500Y292083D01*
X271667Y292500D01*
X272000Y292750D01*
X272500Y292833D01*
X273000Y292750D01*
X273500Y292500D01*
G01X276600Y287833D02*
Y292833D01*
G01Y292083D02*
X277017Y292500D01*
X277433Y292750D01*
X278100Y292833D01*
X278683Y292750D01*
X279267Y292333D01*
X279517Y291750D01*
X279600Y291167D01*
X279517Y290583D01*
X279267Y290000D01*
X278767Y289667D01*
X278100Y289500D01*
X277517Y289583D01*
X276933Y289833D01*
X276600Y290167D01*
G01X282450Y291750D02*
X285117D01*
X284867Y292333D01*
X284450Y292667D01*
X283867Y292833D01*
X283283Y292750D01*
X282783Y292500D01*
X282450Y291917D01*
X282283Y291417D01*
Y290917D01*
X282450Y290417D01*
X282867Y289917D01*
X283367Y289583D01*
X283950Y289500D01*
X284533Y289667D01*
X285117Y290167D01*
G01X290633Y292417D02*
X290050Y292750D01*
X289550Y292833D01*
X288883Y292667D01*
X288383Y292333D01*
X288050Y291750D01*
X287967Y291167D01*
X288050Y290583D01*
X288383Y290083D01*
X288883Y289667D01*
X289550Y289500D01*
X290133Y289667D01*
X290633Y290000D01*
G01X294900Y292833D02*
Y289500D01*
G01Y294167D02*
X294733Y294250D01*
Y294417D01*
X294900Y294500D01*
X295067Y294417D01*
Y294250D01*
X294900Y294167D01*
G01X300000Y289500D02*
Y293750D01*
X300167Y294167D01*
X300500Y294417D01*
X301000Y294500D01*
X301500Y294333D01*
X301750Y293917D01*
G01X300750Y292500D02*
X299083D01*
G01X306100Y292833D02*
Y289500D01*
G01Y294167D02*
X305933Y294250D01*
Y294417D01*
X306100Y294500D01*
X306267Y294417D01*
Y294250D01*
X306100Y294167D01*
G01X313033Y292417D02*
X312450Y292750D01*
X311950Y292833D01*
X311283Y292667D01*
X310783Y292333D01*
X310450Y291750D01*
X310367Y291167D01*
X310450Y290583D01*
X310783Y290083D01*
X311283Y289667D01*
X311950Y289500D01*
X312533Y289667D01*
X313033Y290000D01*
G01X318800Y289500D02*
Y292833D01*
G01Y292250D02*
X318467Y292583D01*
X317967Y292750D01*
X317383Y292833D01*
X316800Y292667D01*
X316300Y292333D01*
X315967Y291833D01*
X315800Y291167D01*
X315967Y290500D01*
X316300Y290000D01*
X316800Y289667D01*
X317383Y289500D01*
X317967Y289583D01*
X318467Y289833D01*
X318800Y290167D01*
G01X322900Y294500D02*
Y289500D01*
G01X321733Y292833D02*
X324067D01*
G01X328500D02*
Y289500D01*
G01Y294167D02*
X328333Y294250D01*
Y294417D01*
X328500Y294500D01*
X328667Y294417D01*
Y294250D01*
X328500Y294167D01*
G01X334100Y289500D02*
X333600Y289583D01*
X333100Y289917D01*
X332767Y290500D01*
X332600Y291167D01*
X332767Y291833D01*
X333100Y292417D01*
X333600Y292750D01*
X334100Y292833D01*
X334600Y292750D01*
X335100Y292417D01*
X335433Y291833D01*
X335517Y291167D01*
X335433Y290500D01*
X335100Y289917D01*
X334600Y289583D01*
X334100Y289500D01*
G01X338283D02*
Y292833D01*
G01Y292000D02*
X338617Y292417D01*
X339117Y292750D01*
X339783Y292833D01*
X340367Y292750D01*
X340867Y292417D01*
X341117Y291833D01*
Y289500D01*
G01X345300Y289333D02*
X345133Y289417D01*
Y289583D01*
X345300Y289667D01*
X345467Y289583D01*
Y289417D01*
X345300Y289333D01*
G01X272500Y248000D02*
Y243000D01*
G01X271333Y246333D02*
X273667D01*
G01X276933Y243000D02*
Y246333D01*
G01Y245667D02*
X277350Y246000D01*
X277767Y246250D01*
X278350Y246333D01*
X278767Y246250D01*
X279267Y246000D01*
G01X285200Y243000D02*
Y246333D01*
G01Y245750D02*
X284867Y246083D01*
X284367Y246250D01*
X283783Y246333D01*
X283200Y246167D01*
X282700Y245833D01*
X282367Y245333D01*
X282200Y244667D01*
X282367Y244000D01*
X282700Y243500D01*
X283200Y243167D01*
X283783Y243000D01*
X284367Y243083D01*
X284867Y243333D01*
X285200Y243667D01*
G01X290633Y245917D02*
X290050Y246250D01*
X289550Y246333D01*
X288883Y246167D01*
X288383Y245833D01*
X288050Y245250D01*
X287967Y244667D01*
X288050Y244083D01*
X288383Y243583D01*
X288883Y243167D01*
X289550Y243000D01*
X290133Y243167D01*
X290633Y243500D01*
G01X293650Y245250D02*
X296317D01*
X296067Y245833D01*
X295650Y246167D01*
X295067Y246333D01*
X294483Y246250D01*
X293983Y246000D01*
X293650Y245417D01*
X293483Y244917D01*
Y244417D01*
X293650Y243917D01*
X294067Y243417D01*
X294567Y243083D01*
X295150Y243000D01*
X295733Y243167D01*
X296317Y243667D01*
G01X304017Y246333D02*
X305017Y243000D01*
X306100Y246333D01*
X307183Y243000D01*
X308183Y246333D01*
G01X311700D02*
Y243000D01*
G01Y247667D02*
X311533Y247750D01*
Y247917D01*
X311700Y248000D01*
X311867Y247917D01*
Y247750D01*
X311700Y247667D01*
G01X318800Y248000D02*
Y243000D01*
G01Y243750D02*
X318467Y243333D01*
X317967Y243083D01*
X317383Y243000D01*
X316717Y243167D01*
X316217Y243583D01*
X315883Y244083D01*
X315800Y244667D01*
X315883Y245250D01*
X316217Y245750D01*
X316717Y246167D01*
X317383Y246333D01*
X317967Y246250D01*
X318383Y246083D01*
X318800Y245750D01*
G01X322900Y248000D02*
Y243000D01*
G01X321733Y246333D02*
X324067D01*
G01X327083Y243000D02*
Y248000D01*
G01Y245583D02*
X327500Y246000D01*
X327917Y246250D01*
X328583Y246333D01*
X329083Y246250D01*
X329667Y245917D01*
X329917Y245417D01*
Y243000D01*
G01X341367D02*
X338033Y244667D01*
X341367Y246333D01*
G01X344217Y243917D02*
X346383D01*
G01Y245417D02*
X344217D01*
G01X354667Y243750D02*
X355167Y243333D01*
X355750Y243083D01*
X356500Y243000D01*
X357250Y243167D01*
X357833Y243500D01*
X358250Y244083D01*
X358333Y244750D01*
X358167Y245417D01*
X357750Y245833D01*
X357167Y246167D01*
X356583Y246250D01*
X356000Y246167D01*
X355250Y245833D01*
X355500Y248000D01*
X357750D01*
G01X365200Y243000D02*
Y246333D01*
G01Y245417D02*
X365450Y245833D01*
X365867Y246167D01*
X366450Y246333D01*
X367033Y246167D01*
X367450Y245833D01*
X367700Y245417D01*
Y243000D01*
G01Y245417D02*
X367950Y245833D01*
X368367Y246167D01*
X368950Y246333D01*
X369533Y246167D01*
X369950Y245833D01*
X370200Y245333D01*
Y243000D01*
G01X373300Y246333D02*
Y243000D01*
G01Y247667D02*
X373133Y247750D01*
Y247917D01*
X373300Y248000D01*
X373467Y247917D01*
Y247750D01*
X373300Y247667D01*
G01X378900Y243000D02*
Y248000D01*
G01X270833Y256500D02*
Y261500D01*
X272917D01*
X273583Y261250D01*
X274000Y260917D01*
X274167Y260250D01*
X274000Y259583D01*
X273500Y259167D01*
X272917Y258917D01*
X270833D01*
G01X272917D02*
X274167Y256500D01*
G01X276850Y258750D02*
X279517D01*
X279267Y259333D01*
X278850Y259667D01*
X278267Y259833D01*
X277683Y259750D01*
X277183Y259500D01*
X276850Y258917D01*
X276683Y258417D01*
Y257917D01*
X276850Y257417D01*
X277267Y256917D01*
X277767Y256583D01*
X278350Y256500D01*
X278933Y256667D01*
X279517Y257167D01*
G01X283700Y256500D02*
Y261500D01*
G01X290800Y256500D02*
Y259833D01*
G01Y259250D02*
X290467Y259583D01*
X289967Y259750D01*
X289383Y259833D01*
X288800Y259667D01*
X288300Y259333D01*
X287967Y258833D01*
X287800Y258167D01*
X287967Y257500D01*
X288300Y257000D01*
X288800Y256667D01*
X289383Y256500D01*
X289967Y256583D01*
X290467Y256833D01*
X290800Y257167D01*
G01X294900Y261500D02*
Y256500D01*
G01X293733Y259833D02*
X296067D01*
G01X300500D02*
Y256500D01*
G01Y261167D02*
X300333Y261250D01*
Y261417D01*
X300500Y261500D01*
X300667Y261417D01*
Y261250D01*
X300500Y261167D01*
G01X304600Y259833D02*
X306100Y256500D01*
X307600Y259833D01*
G01X310450Y258750D02*
X313117D01*
X312867Y259333D01*
X312450Y259667D01*
X311867Y259833D01*
X311283Y259750D01*
X310783Y259500D01*
X310450Y258917D01*
X310283Y258417D01*
Y257917D01*
X310450Y257417D01*
X310867Y256917D01*
X311367Y256583D01*
X311950Y256500D01*
X312533Y256667D01*
X313117Y257167D01*
G01X321400Y254833D02*
Y259833D01*
G01Y259083D02*
X321817Y259500D01*
X322233Y259750D01*
X322900Y259833D01*
X323483Y259750D01*
X324067Y259333D01*
X324317Y258750D01*
X324400Y258167D01*
X324317Y257583D01*
X324067Y257000D01*
X323567Y256667D01*
X322900Y256500D01*
X322317Y256583D01*
X321733Y256833D01*
X321400Y257167D01*
G01X328500Y256500D02*
X328000Y256583D01*
X327500Y256917D01*
X327167Y257500D01*
X327000Y258167D01*
X327167Y258833D01*
X327500Y259417D01*
X328000Y259750D01*
X328500Y259833D01*
X329000Y259750D01*
X329500Y259417D01*
X329833Y258833D01*
X329917Y258167D01*
X329833Y257500D01*
X329500Y256917D01*
X329000Y256583D01*
X328500Y256500D01*
G01X332850Y257083D02*
X333267Y256750D01*
X333850Y256500D01*
X334350D01*
X334850Y256667D01*
X335183Y256917D01*
X335350Y257250D01*
X335267Y257750D01*
X334933Y258000D01*
X333433Y258500D01*
X333100Y259083D01*
X333267Y259500D01*
X333600Y259750D01*
X334100Y259833D01*
X334600Y259750D01*
X335100Y259500D01*
G01X339700Y259833D02*
Y256500D01*
G01Y261167D02*
X339533Y261250D01*
Y261417D01*
X339700Y261500D01*
X339867Y261417D01*
Y261250D01*
X339700Y261167D01*
G01X345300Y261500D02*
Y256500D01*
G01X344133Y259833D02*
X346467D01*
G01X350900D02*
Y256500D01*
G01Y261167D02*
X350733Y261250D01*
Y261417D01*
X350900Y261500D01*
X351067Y261417D01*
Y261250D01*
X350900Y261167D01*
G01X356500Y256500D02*
X356000Y256583D01*
X355500Y256917D01*
X355167Y257500D01*
X355000Y258167D01*
X355167Y258833D01*
X355500Y259417D01*
X356000Y259750D01*
X356500Y259833D01*
X357000Y259750D01*
X357500Y259417D01*
X357833Y258833D01*
X357917Y258167D01*
X357833Y257500D01*
X357500Y256917D01*
X357000Y256583D01*
X356500Y256500D01*
G01X360683D02*
Y259833D01*
G01Y259000D02*
X361017Y259417D01*
X361517Y259750D01*
X362183Y259833D01*
X362767Y259750D01*
X363267Y259417D01*
X363517Y258833D01*
Y256500D01*
G01X371800D02*
Y261500D01*
G01Y259000D02*
X372217Y259500D01*
X372717Y259750D01*
X373217Y259833D01*
X373967Y259667D01*
X374467Y259333D01*
X374800Y258750D01*
Y258083D01*
X374633Y257417D01*
X374300Y256917D01*
X373717Y256583D01*
X373217Y256500D01*
X372717Y256583D01*
X372217Y256833D01*
X371800Y257250D01*
G01X377650Y258750D02*
X380317D01*
X380067Y259333D01*
X379650Y259667D01*
X379067Y259833D01*
X378483Y259750D01*
X377983Y259500D01*
X377650Y258917D01*
X377483Y258417D01*
Y257917D01*
X377650Y257417D01*
X378067Y256917D01*
X378567Y256583D01*
X379150Y256500D01*
X379733Y256667D01*
X380317Y257167D01*
G01X384500Y261500D02*
Y256500D01*
G01X383333Y259833D02*
X385667D01*
G01X388017D02*
X389017Y256500D01*
X390100Y259833D01*
X391183Y256500D01*
X392183Y259833D01*
G01X394450Y258750D02*
X397117D01*
X396867Y259333D01*
X396450Y259667D01*
X395867Y259833D01*
X395283Y259750D01*
X394783Y259500D01*
X394450Y258917D01*
X394283Y258417D01*
Y257917D01*
X394450Y257417D01*
X394867Y256917D01*
X395367Y256583D01*
X395950Y256500D01*
X396533Y256667D01*
X397117Y257167D01*
G01X400050Y258750D02*
X402717D01*
X402467Y259333D01*
X402050Y259667D01*
X401467Y259833D01*
X400883Y259750D01*
X400383Y259500D01*
X400050Y258917D01*
X399883Y258417D01*
Y257917D01*
X400050Y257417D01*
X400467Y256917D01*
X400967Y256583D01*
X401550Y256500D01*
X402133Y256667D01*
X402717Y257167D01*
G01X405483Y256500D02*
Y259833D01*
G01Y259000D02*
X405817Y259417D01*
X406317Y259750D01*
X406983Y259833D01*
X407567Y259750D01*
X408067Y259417D01*
X408317Y258833D01*
Y256500D01*
G01X419600D02*
Y259833D01*
G01Y259250D02*
X419267Y259583D01*
X418767Y259750D01*
X418183Y259833D01*
X417600Y259667D01*
X417100Y259333D01*
X416767Y258833D01*
X416600Y258167D01*
X416767Y257500D01*
X417100Y257000D01*
X417600Y256667D01*
X418183Y256500D01*
X418767Y256583D01*
X419267Y256833D01*
X419600Y257167D01*
G01X422283Y256500D02*
Y259833D01*
G01Y259000D02*
X422617Y259417D01*
X423117Y259750D01*
X423783Y259833D01*
X424367Y259750D01*
X424867Y259417D01*
X425117Y258833D01*
Y256500D01*
G01X427550Y255000D02*
X428050Y254833D01*
X428717Y255000D01*
X429133Y255333D01*
X429467Y255750D01*
X429967Y257083D01*
X431050Y259833D01*
G01X428383D02*
X429967Y257083D01*
G01X439000Y254833D02*
Y259833D01*
G01Y259083D02*
X439417Y259500D01*
X439833Y259750D01*
X440500Y259833D01*
X441083Y259750D01*
X441667Y259333D01*
X441917Y258750D01*
X442000Y258167D01*
X441917Y257583D01*
X441667Y257000D01*
X441167Y256667D01*
X440500Y256500D01*
X439917Y256583D01*
X439333Y256833D01*
X439000Y257167D01*
G01X447600Y256500D02*
Y259833D01*
G01Y259250D02*
X447267Y259583D01*
X446767Y259750D01*
X446183Y259833D01*
X445600Y259667D01*
X445100Y259333D01*
X444767Y258833D01*
X444600Y258167D01*
X444767Y257500D01*
X445100Y257000D01*
X445600Y256667D01*
X446183Y256500D01*
X446767Y256583D01*
X447267Y256833D01*
X447600Y257167D01*
G01X453200Y261500D02*
Y256500D01*
G01Y257250D02*
X452867Y256833D01*
X452367Y256583D01*
X451783Y256500D01*
X451117Y256667D01*
X450617Y257083D01*
X450283Y257583D01*
X450200Y258167D01*
X450283Y258750D01*
X450617Y259250D01*
X451117Y259667D01*
X451783Y259833D01*
X452367Y259750D01*
X452783Y259583D01*
X453200Y259250D01*
G01X462900Y261500D02*
Y256500D01*
G01X461733Y259833D02*
X464067D01*
G01X468500Y256500D02*
X468000Y256583D01*
X467500Y256917D01*
X467167Y257500D01*
X467000Y258167D01*
X467167Y258833D01*
X467500Y259417D01*
X468000Y259750D01*
X468500Y259833D01*
X469000Y259750D01*
X469500Y259417D01*
X469833Y258833D01*
X469917Y258167D01*
X469833Y257500D01*
X469500Y256917D01*
X469000Y256583D01*
X468500Y256500D01*
G01X478200Y254833D02*
Y259833D01*
G01Y259083D02*
X478617Y259500D01*
X479033Y259750D01*
X479700Y259833D01*
X480283Y259750D01*
X480867Y259333D01*
X481117Y258750D01*
X481200Y258167D01*
X481117Y257583D01*
X480867Y257000D01*
X480367Y256667D01*
X479700Y256500D01*
X479117Y256583D01*
X478533Y256833D01*
X478200Y257167D01*
G01X486800Y256500D02*
Y259833D01*
G01Y259250D02*
X486467Y259583D01*
X485967Y259750D01*
X485383Y259833D01*
X484800Y259667D01*
X484300Y259333D01*
X483967Y258833D01*
X483800Y258167D01*
X483967Y257500D01*
X484300Y257000D01*
X484800Y256667D01*
X485383Y256500D01*
X485967Y256583D01*
X486467Y256833D01*
X486800Y257167D01*
G01X492400Y261500D02*
Y256500D01*
G01Y257250D02*
X492067Y256833D01*
X491567Y256583D01*
X490983Y256500D01*
X490317Y256667D01*
X489817Y257083D01*
X489483Y257583D01*
X489400Y258167D01*
X489483Y258750D01*
X489817Y259250D01*
X490317Y259667D01*
X490983Y259833D01*
X491567Y259750D01*
X491983Y259583D01*
X492400Y259250D01*
G01X270750Y271500D02*
Y276500D01*
G01X274250D02*
Y271500D01*
G01Y274000D02*
X270750D01*
G01X276267Y271500D02*
Y276500D01*
X277933D01*
X278600Y276250D01*
X279100Y275917D01*
X279517Y275417D01*
X279850Y274833D01*
X279933Y274000D01*
X279850Y273167D01*
X279517Y272583D01*
X279100Y272083D01*
X278600Y271750D01*
X277933Y271500D01*
X276267D01*
G01X282700Y276500D02*
X284700D01*
G01X283700D02*
Y271500D01*
G01X282700D02*
X284700D01*
G01X293233D02*
Y276500D01*
X295233D01*
X295900Y276250D01*
X296400Y275667D01*
X296567Y275000D01*
X296400Y274333D01*
X295983Y273833D01*
X295233Y273583D01*
X293233D01*
G01X302333Y276083D02*
X301833Y276333D01*
X301250Y276500D01*
X300583D01*
X299833Y276250D01*
X299250Y275833D01*
X298833Y275333D01*
X298500Y274500D01*
X298417Y273750D01*
X298583Y273000D01*
X298833Y272500D01*
X299333Y272000D01*
X299917Y271667D01*
X300500Y271500D01*
X301083D01*
X301667Y271667D01*
X302167Y271917D01*
X302583Y272250D01*
G01X306767Y274167D02*
X307100Y274417D01*
X307350Y274833D01*
X307517Y275417D01*
X307350Y275917D01*
X307017Y276250D01*
X306433Y276500D01*
X304183D01*
Y271500D01*
X306933D01*
X307517Y271833D01*
X307850Y272333D01*
X308017Y272917D01*
X307850Y273500D01*
X307350Y274000D01*
X306767Y274167D01*
X304183D01*
G01X311700Y271333D02*
X311533Y271417D01*
Y271583D01*
X311700Y271667D01*
X311867Y271583D01*
Y271417D01*
X311700Y271333D01*
G01X270750Y299167D02*
X271417Y298750D01*
X272167Y298500D01*
X272833D01*
X273500Y298750D01*
X274000Y299167D01*
X274250Y299750D01*
X274083Y300333D01*
X273667Y300833D01*
X272917Y301167D01*
X271917Y301333D01*
X271333Y301667D01*
X271083Y302250D01*
X271250Y302833D01*
X271667Y303250D01*
X272250Y303500D01*
X272833D01*
X273417Y303333D01*
X273917Y302917D01*
G01X276850Y300750D02*
X279517D01*
X279267Y301333D01*
X278850Y301667D01*
X278267Y301833D01*
X277683Y301750D01*
X277183Y301500D01*
X276850Y300917D01*
X276683Y300417D01*
Y299917D01*
X276850Y299417D01*
X277267Y298917D01*
X277767Y298583D01*
X278350Y298500D01*
X278933Y298667D01*
X279517Y299167D01*
G01X282533Y298500D02*
Y301833D01*
G01Y301167D02*
X282950Y301500D01*
X283367Y301750D01*
X283950Y301833D01*
X284367Y301750D01*
X284867Y301500D01*
G01X287800Y301833D02*
X289300Y298500D01*
X290800Y301833D01*
G01X293650Y300750D02*
X296317D01*
X296067Y301333D01*
X295650Y301667D01*
X295067Y301833D01*
X294483Y301750D01*
X293983Y301500D01*
X293650Y300917D01*
X293483Y300417D01*
Y299917D01*
X293650Y299417D01*
X294067Y298917D01*
X294567Y298583D01*
X295150Y298500D01*
X295733Y298667D01*
X296317Y299167D01*
G01X299333Y298500D02*
Y301833D01*
G01Y301167D02*
X299750Y301500D01*
X300167Y301750D01*
X300750Y301833D01*
X301167Y301750D01*
X301667Y301500D01*
G01X310033Y298500D02*
Y303500D01*
X312033D01*
X312700Y303250D01*
X313200Y302667D01*
X313367Y302000D01*
X313200Y301333D01*
X312783Y300833D01*
X312033Y300583D01*
X310033D01*
G01X319133Y303083D02*
X318633Y303333D01*
X318050Y303500D01*
X317383D01*
X316633Y303250D01*
X316050Y302833D01*
X315633Y302333D01*
X315300Y301500D01*
X315217Y300750D01*
X315383Y300000D01*
X315633Y299500D01*
X316133Y299000D01*
X316717Y298667D01*
X317300Y298500D01*
X317883D01*
X318467Y298667D01*
X318967Y298917D01*
X319383Y299250D01*
G01X323567Y301167D02*
X323900Y301417D01*
X324150Y301833D01*
X324317Y302417D01*
X324150Y302917D01*
X323817Y303250D01*
X323233Y303500D01*
X320983D01*
Y298500D01*
X323733D01*
X324317Y298833D01*
X324650Y299333D01*
X324817Y299917D01*
X324650Y300500D01*
X324150Y301000D01*
X323567Y301167D01*
X320983D01*
G01X328500Y298333D02*
X328333Y298417D01*
Y298583D01*
X328500Y298667D01*
X328667Y298583D01*
Y298417D01*
X328500Y298333D01*
G01Y300583D02*
X328333Y300667D01*
Y300833D01*
X328500Y300917D01*
X328667Y300833D01*
Y300667D01*
X328500Y300583D01*
G01X332517Y298500D02*
Y303500D01*
X335683D01*
G01X334517Y301083D02*
X332517D01*
G01X339700Y298500D02*
X339200Y298583D01*
X338700Y298917D01*
X338367Y299500D01*
X338200Y300167D01*
X338367Y300833D01*
X338700Y301417D01*
X339200Y301750D01*
X339700Y301833D01*
X340200Y301750D01*
X340700Y301417D01*
X341033Y300833D01*
X341117Y300167D01*
X341033Y299500D01*
X340700Y298917D01*
X340200Y298583D01*
X339700Y298500D01*
G01X345300D02*
Y303500D01*
G01X350900Y298500D02*
Y303500D01*
G01X356500Y298500D02*
X356000Y298583D01*
X355500Y298917D01*
X355167Y299500D01*
X355000Y300167D01*
X355167Y300833D01*
X355500Y301417D01*
X356000Y301750D01*
X356500Y301833D01*
X357000Y301750D01*
X357500Y301417D01*
X357833Y300833D01*
X357917Y300167D01*
X357833Y299500D01*
X357500Y298917D01*
X357000Y298583D01*
X356500Y298500D01*
G01X360017Y301833D02*
X361017Y298500D01*
X362100Y301833D01*
X363183Y298500D01*
X364183Y301833D01*
G01X372133Y298500D02*
Y301833D01*
G01Y301167D02*
X372550Y301500D01*
X372967Y301750D01*
X373550Y301833D01*
X373967Y301750D01*
X374467Y301500D01*
G01X378900Y301833D02*
Y298500D01*
G01Y303167D02*
X378733Y303250D01*
Y303417D01*
X378900Y303500D01*
X379067Y303417D01*
Y303250D01*
X378900Y303167D01*
G01X383333Y297250D02*
X383917Y296917D01*
X384583Y296833D01*
X385167Y296917D01*
X385667Y297333D01*
X386000Y297917D01*
Y301833D01*
G01Y301167D02*
X385667Y301500D01*
X385167Y301750D01*
X384583Y301833D01*
X383917Y301667D01*
X383500Y301333D01*
X383167Y300750D01*
X383000Y300167D01*
X383083Y299667D01*
X383417Y299083D01*
X383917Y298667D01*
X384583Y298500D01*
X385083Y298583D01*
X385667Y298917D01*
X386000Y299250D01*
G01X388683Y298500D02*
Y303500D01*
G01Y301083D02*
X389100Y301500D01*
X389517Y301750D01*
X390183Y301833D01*
X390683Y301750D01*
X391267Y301417D01*
X391517Y300917D01*
Y298500D01*
G01X395700Y303500D02*
Y298500D01*
G01X394533Y301833D02*
X396867D01*
G01X405650Y299083D02*
X406067Y298750D01*
X406650Y298500D01*
X407150D01*
X407650Y298667D01*
X407983Y298917D01*
X408150Y299250D01*
X408067Y299750D01*
X407733Y300000D01*
X406233Y300500D01*
X405900Y301083D01*
X406067Y301500D01*
X406400Y301750D01*
X406900Y301833D01*
X407400Y301750D01*
X407900Y301500D01*
G01X412500Y301833D02*
Y298500D01*
G01Y303167D02*
X412333Y303250D01*
Y303417D01*
X412500Y303500D01*
X412667Y303417D01*
Y303250D01*
X412500Y303167D01*
G01X419600Y303500D02*
Y298500D01*
G01Y299250D02*
X419267Y298833D01*
X418767Y298583D01*
X418183Y298500D01*
X417517Y298667D01*
X417017Y299083D01*
X416683Y299583D01*
X416600Y300167D01*
X416683Y300750D01*
X417017Y301250D01*
X417517Y301667D01*
X418183Y301833D01*
X418767Y301750D01*
X419183Y301583D01*
X419600Y301250D01*
G01X422450Y300750D02*
X425117D01*
X424867Y301333D01*
X424450Y301667D01*
X423867Y301833D01*
X423283Y301750D01*
X422783Y301500D01*
X422450Y300917D01*
X422283Y300417D01*
Y299917D01*
X422450Y299417D01*
X422867Y298917D01*
X423367Y298583D01*
X423950Y298500D01*
X424533Y298667D01*
X425117Y299167D01*
G01X433650Y299083D02*
X434067Y298750D01*
X434650Y298500D01*
X435150D01*
X435650Y298667D01*
X435983Y298917D01*
X436150Y299250D01*
X436067Y299750D01*
X435733Y300000D01*
X434233Y300500D01*
X433900Y301083D01*
X434067Y301500D01*
X434400Y301750D01*
X434900Y301833D01*
X435400Y301750D01*
X435900Y301500D01*
G01X439000Y296833D02*
Y301833D01*
G01Y301083D02*
X439417Y301500D01*
X439833Y301750D01*
X440500Y301833D01*
X441083Y301750D01*
X441667Y301333D01*
X441917Y300750D01*
X442000Y300167D01*
X441917Y299583D01*
X441667Y299000D01*
X441167Y298667D01*
X440500Y298500D01*
X439917Y298583D01*
X439333Y298833D01*
X439000Y299167D01*
G01X444850Y300750D02*
X447517D01*
X447267Y301333D01*
X446850Y301667D01*
X446267Y301833D01*
X445683Y301750D01*
X445183Y301500D01*
X444850Y300917D01*
X444683Y300417D01*
Y299917D01*
X444850Y299417D01*
X445267Y298917D01*
X445767Y298583D01*
X446350Y298500D01*
X446933Y298667D01*
X447517Y299167D01*
G01X453033Y301417D02*
X452450Y301750D01*
X451950Y301833D01*
X451283Y301667D01*
X450783Y301333D01*
X450450Y300750D01*
X450367Y300167D01*
X450450Y299583D01*
X450783Y299083D01*
X451283Y298667D01*
X451950Y298500D01*
X452533Y298667D01*
X453033Y299000D01*
G01X462733Y297583D02*
X463067Y298667D01*
G01X468500Y301833D02*
Y298500D01*
G01Y303167D02*
X468333Y303250D01*
Y303417D01*
X468500Y303500D01*
X468667Y303417D01*
Y303250D01*
X468500Y303167D01*
G01X473600Y298500D02*
Y302750D01*
X473767Y303167D01*
X474100Y303417D01*
X474600Y303500D01*
X475100Y303333D01*
X475350Y302917D01*
G01X474350Y301500D02*
X472683D01*
G01X484050Y299083D02*
X484467Y298750D01*
X485050Y298500D01*
X485550D01*
X486050Y298667D01*
X486383Y298917D01*
X486550Y299250D01*
X486467Y299750D01*
X486133Y300000D01*
X484633Y300500D01*
X484300Y301083D01*
X484467Y301500D01*
X484800Y301750D01*
X485300Y301833D01*
X485800Y301750D01*
X486300Y301500D01*
G01X490900Y303500D02*
Y298500D01*
G01X489733Y301833D02*
X492067D01*
G01X498000Y298500D02*
Y301833D01*
G01Y301250D02*
X497667Y301583D01*
X497167Y301750D01*
X496583Y301833D01*
X496000Y301667D01*
X495500Y301333D01*
X495167Y300833D01*
X495000Y300167D01*
X495167Y299500D01*
X495500Y299000D01*
X496000Y298667D01*
X496583Y298500D01*
X497167Y298583D01*
X497667Y298833D01*
X498000Y299167D01*
G01X503433Y301417D02*
X502850Y301750D01*
X502350Y301833D01*
X501683Y301667D01*
X501183Y301333D01*
X500850Y300750D01*
X500767Y300167D01*
X500850Y299583D01*
X501183Y299083D01*
X501683Y298667D01*
X502350Y298500D01*
X502933Y298667D01*
X503433Y299000D01*
G01X506283Y298500D02*
Y303500D01*
G01X508950Y301833D02*
X506283Y299917D01*
G01X507367Y300667D02*
X509117Y298500D01*
G01X517483Y301833D02*
Y299500D01*
X517817Y298917D01*
X518317Y298583D01*
X518900Y298500D01*
X519483Y298583D01*
X519983Y298917D01*
X520317Y299500D01*
G01Y298500D02*
Y301833D01*
G01X523000Y296833D02*
Y301833D01*
G01Y301083D02*
X523417Y301500D01*
X523833Y301750D01*
X524500Y301833D01*
X525083Y301750D01*
X525667Y301333D01*
X525917Y300750D01*
X526000Y300167D01*
X525917Y299583D01*
X525667Y299000D01*
X525167Y298667D01*
X524500Y298500D01*
X523917Y298583D01*
X523333Y298833D01*
X523000Y299167D01*
G01X533617Y301833D02*
X534617Y298500D01*
X535700Y301833D01*
X536783Y298500D01*
X537783Y301833D01*
G01X541300D02*
Y298500D01*
G01Y303167D02*
X541133Y303250D01*
Y303417D01*
X541300Y303500D01*
X541467Y303417D01*
Y303250D01*
X541300Y303167D01*
G01X546900Y303500D02*
Y298500D01*
G01X545733Y301833D02*
X548067D01*
G01X551083Y298500D02*
Y303500D01*
G01Y301083D02*
X551500Y301500D01*
X551917Y301750D01*
X552583Y301833D01*
X553083Y301750D01*
X553667Y301417D01*
X553917Y300917D01*
Y298500D01*
G01X558100D02*
X557600Y298583D01*
X557100Y298917D01*
X556767Y299500D01*
X556600Y300167D01*
X556767Y300833D01*
X557100Y301417D01*
X557600Y301750D01*
X558100Y301833D01*
X558600Y301750D01*
X559100Y301417D01*
X559433Y300833D01*
X559517Y300167D01*
X559433Y299500D01*
X559100Y298917D01*
X558600Y298583D01*
X558100Y298500D01*
G01X562283Y301833D02*
Y299500D01*
X562617Y298917D01*
X563117Y298583D01*
X563700Y298500D01*
X564283Y298583D01*
X564783Y298917D01*
X565117Y299500D01*
G01Y298500D02*
Y301833D01*
G01X569300Y303500D02*
Y298500D01*
G01X568133Y301833D02*
X570467D01*
G01X272500Y318500D02*
Y313500D01*
G01X270583Y318500D02*
X274417D01*
G01X276933Y313500D02*
Y316833D01*
G01Y316167D02*
X277350Y316500D01*
X277767Y316750D01*
X278350Y316833D01*
X278767Y316750D01*
X279267Y316500D01*
G01X285200Y313500D02*
Y316833D01*
G01Y316250D02*
X284867Y316583D01*
X284367Y316750D01*
X283783Y316833D01*
X283200Y316667D01*
X282700Y316333D01*
X282367Y315833D01*
X282200Y315167D01*
X282367Y314500D01*
X282700Y314000D01*
X283200Y313667D01*
X283783Y313500D01*
X284367Y313583D01*
X284867Y313833D01*
X285200Y314167D01*
G01X290800Y318500D02*
Y313500D01*
G01Y314250D02*
X290467Y313833D01*
X289967Y313583D01*
X289383Y313500D01*
X288717Y313667D01*
X288217Y314083D01*
X287883Y314583D01*
X287800Y315167D01*
X287883Y315750D01*
X288217Y316250D01*
X288717Y316667D01*
X289383Y316833D01*
X289967Y316750D01*
X290383Y316583D01*
X290800Y316250D01*
G01X294900Y316833D02*
Y313500D01*
G01Y318167D02*
X294733Y318250D01*
Y318417D01*
X294900Y318500D01*
X295067Y318417D01*
Y318250D01*
X294900Y318167D01*
G01X300500Y318500D02*
Y313500D01*
G01X299333Y316833D02*
X301667D01*
G01X306100D02*
Y313500D01*
G01Y318167D02*
X305933Y318250D01*
Y318417D01*
X306100Y318500D01*
X306267Y318417D01*
Y318250D01*
X306100Y318167D01*
G01X311700Y313500D02*
X311200Y313583D01*
X310700Y313917D01*
X310367Y314500D01*
X310200Y315167D01*
X310367Y315833D01*
X310700Y316417D01*
X311200Y316750D01*
X311700Y316833D01*
X312200Y316750D01*
X312700Y316417D01*
X313033Y315833D01*
X313117Y315167D01*
X313033Y314500D01*
X312700Y313917D01*
X312200Y313583D01*
X311700Y313500D01*
G01X315883D02*
Y316833D01*
G01Y316000D02*
X316217Y316417D01*
X316717Y316750D01*
X317383Y316833D01*
X317967Y316750D01*
X318467Y316417D01*
X318717Y315833D01*
Y313500D01*
G01X324400D02*
Y316833D01*
G01Y316250D02*
X324067Y316583D01*
X323567Y316750D01*
X322983Y316833D01*
X322400Y316667D01*
X321900Y316333D01*
X321567Y315833D01*
X321400Y315167D01*
X321567Y314500D01*
X321900Y314000D01*
X322400Y313667D01*
X322983Y313500D01*
X323567Y313583D01*
X324067Y313833D01*
X324400Y314167D01*
G01X328500Y313500D02*
Y318500D01*
G01X338033Y313500D02*
Y318500D01*
X340033D01*
X340700Y318250D01*
X341200Y317667D01*
X341367Y317000D01*
X341200Y316333D01*
X340783Y315833D01*
X340033Y315583D01*
X338033D01*
G01X347133Y318083D02*
X346633Y318333D01*
X346050Y318500D01*
X345383D01*
X344633Y318250D01*
X344050Y317833D01*
X343633Y317333D01*
X343300Y316500D01*
X343217Y315750D01*
X343383Y315000D01*
X343633Y314500D01*
X344133Y314000D01*
X344717Y313667D01*
X345300Y313500D01*
X345883D01*
X346467Y313667D01*
X346967Y313917D01*
X347383Y314250D01*
G01X351567Y316167D02*
X351900Y316417D01*
X352150Y316833D01*
X352317Y317417D01*
X352150Y317917D01*
X351817Y318250D01*
X351233Y318500D01*
X348983D01*
Y313500D01*
X351733D01*
X352317Y313833D01*
X352650Y314333D01*
X352817Y314917D01*
X352650Y315500D01*
X352150Y316000D01*
X351567Y316167D01*
X348983D01*
G01X356500Y313333D02*
X356333Y313417D01*
Y313583D01*
X356500Y313667D01*
X356667Y313583D01*
Y313417D01*
X356500Y313333D01*
G01X264000Y237000D02*
X694500D01*
G01X264000Y282000D02*
X694500D01*
G01X264000Y309000D02*
X694500D01*
G01X270000Y368500D02*
Y363500D01*
G01X268833Y366833D02*
X271167D01*
G01X275600Y363500D02*
X275100Y363583D01*
X274600Y363917D01*
X274267Y364500D01*
X274100Y365167D01*
X274267Y365833D01*
X274600Y366417D01*
X275100Y366750D01*
X275600Y366833D01*
X276100Y366750D01*
X276600Y366417D01*
X276933Y365833D01*
X277017Y365167D01*
X276933Y364500D01*
X276600Y363917D01*
X276100Y363583D01*
X275600Y363500D01*
G01X281200D02*
Y368500D01*
G01X285550Y365750D02*
X288217D01*
X287967Y366333D01*
X287550Y366667D01*
X286967Y366833D01*
X286383Y366750D01*
X285883Y366500D01*
X285550Y365917D01*
X285383Y365417D01*
Y364917D01*
X285550Y364417D01*
X285967Y363917D01*
X286467Y363583D01*
X287050Y363500D01*
X287633Y363667D01*
X288217Y364167D01*
G01X291233Y363500D02*
Y366833D01*
G01Y366167D02*
X291650Y366500D01*
X292067Y366750D01*
X292650Y366833D01*
X293067Y366750D01*
X293567Y366500D01*
G01X299500Y363500D02*
Y366833D01*
G01Y366250D02*
X299167Y366583D01*
X298667Y366750D01*
X298083Y366833D01*
X297500Y366667D01*
X297000Y366333D01*
X296667Y365833D01*
X296500Y365167D01*
X296667Y364500D01*
X297000Y364000D01*
X297500Y363667D01*
X298083Y363500D01*
X298667Y363583D01*
X299167Y363833D01*
X299500Y364167D01*
G01X302183Y363500D02*
Y366833D01*
G01Y366000D02*
X302517Y366417D01*
X303017Y366750D01*
X303683Y366833D01*
X304267Y366750D01*
X304767Y366417D01*
X305017Y365833D01*
Y363500D01*
G01X310533Y366417D02*
X309950Y366750D01*
X309450Y366833D01*
X308783Y366667D01*
X308283Y366333D01*
X307950Y365750D01*
X307867Y365167D01*
X307950Y364583D01*
X308283Y364083D01*
X308783Y363667D01*
X309450Y363500D01*
X310033Y363667D01*
X310533Y364000D01*
G01X313550Y365750D02*
X316217D01*
X315967Y366333D01*
X315550Y366667D01*
X314967Y366833D01*
X314383Y366750D01*
X313883Y366500D01*
X313550Y365917D01*
X313383Y365417D01*
Y364917D01*
X313550Y364417D01*
X313967Y363917D01*
X314467Y363583D01*
X315050Y363500D01*
X315633Y363667D01*
X316217Y364167D01*
G01X326000Y368500D02*
Y363500D01*
G01X324833Y366833D02*
X327167D01*
G01X333100Y363500D02*
Y366833D01*
G01Y366250D02*
X332767Y366583D01*
X332267Y366750D01*
X331683Y366833D01*
X331100Y366667D01*
X330600Y366333D01*
X330267Y365833D01*
X330100Y365167D01*
X330267Y364500D01*
X330600Y364000D01*
X331100Y363667D01*
X331683Y363500D01*
X332267Y363583D01*
X332767Y363833D01*
X333100Y364167D01*
G01X335700Y363500D02*
Y368500D01*
G01Y366000D02*
X336117Y366500D01*
X336617Y366750D01*
X337117Y366833D01*
X337867Y366667D01*
X338367Y366333D01*
X338700Y365750D01*
Y365083D01*
X338533Y364417D01*
X338200Y363917D01*
X337617Y363583D01*
X337117Y363500D01*
X336617Y363583D01*
X336117Y363833D01*
X335700Y364250D01*
G01X342800Y363500D02*
Y368500D01*
G01X347150Y365750D02*
X349817D01*
X349567Y366333D01*
X349150Y366667D01*
X348567Y366833D01*
X347983Y366750D01*
X347483Y366500D01*
X347150Y365917D01*
X346983Y365417D01*
Y364917D01*
X347150Y364417D01*
X347567Y363917D01*
X348067Y363583D01*
X348650Y363500D01*
X349233Y363667D01*
X349817Y364167D01*
G01X354000Y363333D02*
X353833Y363417D01*
Y363583D01*
X354000Y363667D01*
X354167Y363583D01*
Y363417D01*
X354000Y363333D01*
G01X268667Y374250D02*
X269250Y373917D01*
X269750Y373833D01*
X270417Y374000D01*
X270917Y374417D01*
X271167Y375167D01*
Y378833D01*
G01Y380167D02*
X271000Y380250D01*
Y380417D01*
X271167Y380500D01*
X271333Y380417D01*
Y380250D01*
X271167Y380167D01*
G01X274183Y378833D02*
Y376500D01*
X274517Y375917D01*
X275017Y375583D01*
X275600Y375500D01*
X276183Y375583D01*
X276683Y375917D01*
X277017Y376500D01*
G01Y375500D02*
Y378833D01*
G01X279783Y375500D02*
Y378833D01*
G01Y378000D02*
X280117Y378417D01*
X280617Y378750D01*
X281283Y378833D01*
X281867Y378750D01*
X282367Y378417D01*
X282617Y377833D01*
Y375500D01*
G01X288133Y378417D02*
X287550Y378750D01*
X287050Y378833D01*
X286383Y378667D01*
X285883Y378333D01*
X285550Y377750D01*
X285467Y377167D01*
X285550Y376583D01*
X285883Y376083D01*
X286383Y375667D01*
X287050Y375500D01*
X287633Y375667D01*
X288133Y376000D01*
G01X292400Y380500D02*
Y375500D01*
G01X291233Y378833D02*
X293567D01*
G01X298000D02*
Y375500D01*
G01Y380167D02*
X297833Y380250D01*
Y380417D01*
X298000Y380500D01*
X298167Y380417D01*
Y380250D01*
X298000Y380167D01*
G01X303600Y375500D02*
X303100Y375583D01*
X302600Y375917D01*
X302267Y376500D01*
X302100Y377167D01*
X302267Y377833D01*
X302600Y378417D01*
X303100Y378750D01*
X303600Y378833D01*
X304100Y378750D01*
X304600Y378417D01*
X304933Y377833D01*
X305017Y377167D01*
X304933Y376500D01*
X304600Y375917D01*
X304100Y375583D01*
X303600Y375500D01*
G01X307783D02*
Y378833D01*
G01Y378000D02*
X308117Y378417D01*
X308617Y378750D01*
X309283Y378833D01*
X309867Y378750D01*
X310367Y378417D01*
X310617Y377833D01*
Y375500D01*
G01X318900D02*
Y380500D01*
G01Y378000D02*
X319317Y378500D01*
X319817Y378750D01*
X320317Y378833D01*
X321067Y378667D01*
X321567Y378333D01*
X321900Y377750D01*
Y377083D01*
X321733Y376417D01*
X321400Y375917D01*
X320817Y375583D01*
X320317Y375500D01*
X319817Y375583D01*
X319317Y375833D01*
X318900Y376250D01*
G01X324750Y377750D02*
X327417D01*
X327167Y378333D01*
X326750Y378667D01*
X326167Y378833D01*
X325583Y378750D01*
X325083Y378500D01*
X324750Y377917D01*
X324583Y377417D01*
Y376917D01*
X324750Y376417D01*
X325167Y375917D01*
X325667Y375583D01*
X326250Y375500D01*
X326833Y375667D01*
X327417Y376167D01*
G01X331600Y375500D02*
Y380500D01*
G01X337200Y375500D02*
X336700Y375583D01*
X336200Y375917D01*
X335867Y376500D01*
X335700Y377167D01*
X335867Y377833D01*
X336200Y378417D01*
X336700Y378750D01*
X337200Y378833D01*
X337700Y378750D01*
X338200Y378417D01*
X338533Y377833D01*
X338617Y377167D01*
X338533Y376500D01*
X338200Y375917D01*
X337700Y375583D01*
X337200Y375500D01*
G01X340717Y378833D02*
X341717Y375500D01*
X342800Y378833D01*
X343883Y375500D01*
X344883Y378833D01*
G01X354000Y380500D02*
Y375500D01*
G01X352833Y378833D02*
X355167D01*
G01X358183Y375500D02*
Y380500D01*
G01Y378083D02*
X358600Y378500D01*
X359017Y378750D01*
X359683Y378833D01*
X360183Y378750D01*
X360767Y378417D01*
X361017Y377917D01*
Y375500D01*
G01X363950Y377750D02*
X366617D01*
X366367Y378333D01*
X365950Y378667D01*
X365367Y378833D01*
X364783Y378750D01*
X364283Y378500D01*
X363950Y377917D01*
X363783Y377417D01*
Y376917D01*
X363950Y376417D01*
X364367Y375917D01*
X364867Y375583D01*
X365450Y375500D01*
X366033Y375667D01*
X366617Y376167D01*
G01X373900Y375500D02*
Y378833D01*
G01Y377917D02*
X374150Y378333D01*
X374567Y378667D01*
X375150Y378833D01*
X375733Y378667D01*
X376150Y378333D01*
X376400Y377917D01*
Y375500D01*
G01Y377917D02*
X376650Y378333D01*
X377067Y378667D01*
X377650Y378833D01*
X378233Y378667D01*
X378650Y378333D01*
X378900Y377833D01*
Y375500D01*
G01X382000Y378833D02*
Y375500D01*
G01Y380167D02*
X381833Y380250D01*
Y380417D01*
X382000Y380500D01*
X382167Y380417D01*
Y380250D01*
X382000Y380167D01*
G01X386183Y375500D02*
Y378833D01*
G01Y378000D02*
X386517Y378417D01*
X387017Y378750D01*
X387683Y378833D01*
X388267Y378750D01*
X388767Y378417D01*
X389017Y377833D01*
Y375500D01*
G01X400133Y378417D02*
X399550Y378750D01*
X399050Y378833D01*
X398383Y378667D01*
X397883Y378333D01*
X397550Y377750D01*
X397467Y377167D01*
X397550Y376583D01*
X397883Y376083D01*
X398383Y375667D01*
X399050Y375500D01*
X399633Y375667D01*
X400133Y376000D01*
G01X404400Y375500D02*
X403900Y375583D01*
X403400Y375917D01*
X403067Y376500D01*
X402900Y377167D01*
X403067Y377833D01*
X403400Y378417D01*
X403900Y378750D01*
X404400Y378833D01*
X404900Y378750D01*
X405400Y378417D01*
X405733Y377833D01*
X405817Y377167D01*
X405733Y376500D01*
X405400Y375917D01*
X404900Y375583D01*
X404400Y375500D01*
G01X408583D02*
Y378833D01*
G01Y378000D02*
X408917Y378417D01*
X409417Y378750D01*
X410083Y378833D01*
X410667Y378750D01*
X411167Y378417D01*
X411417Y377833D01*
Y375500D01*
G01X417100Y380500D02*
Y375500D01*
G01Y376250D02*
X416767Y375833D01*
X416267Y375583D01*
X415683Y375500D01*
X415017Y375667D01*
X414517Y376083D01*
X414183Y376583D01*
X414100Y377167D01*
X414183Y377750D01*
X414517Y378250D01*
X415017Y378667D01*
X415683Y378833D01*
X416267Y378750D01*
X416683Y378583D01*
X417100Y378250D01*
G01X419783Y378833D02*
Y376500D01*
X420117Y375917D01*
X420617Y375583D01*
X421200Y375500D01*
X421783Y375583D01*
X422283Y375917D01*
X422617Y376500D01*
G01Y375500D02*
Y378833D01*
G01X428133Y378417D02*
X427550Y378750D01*
X427050Y378833D01*
X426383Y378667D01*
X425883Y378333D01*
X425550Y377750D01*
X425467Y377167D01*
X425550Y376583D01*
X425883Y376083D01*
X426383Y375667D01*
X427050Y375500D01*
X427633Y375667D01*
X428133Y376000D01*
G01X432400Y380500D02*
Y375500D01*
G01X431233Y378833D02*
X433567D01*
G01X438000Y375500D02*
X437500Y375583D01*
X437000Y375917D01*
X436667Y376500D01*
X436500Y377167D01*
X436667Y377833D01*
X437000Y378417D01*
X437500Y378750D01*
X438000Y378833D01*
X438500Y378750D01*
X439000Y378417D01*
X439333Y377833D01*
X439417Y377167D01*
X439333Y376500D01*
X439000Y375917D01*
X438500Y375583D01*
X438000Y375500D01*
G01X442433D02*
Y378833D01*
G01Y378167D02*
X442850Y378500D01*
X443267Y378750D01*
X443850Y378833D01*
X444267Y378750D01*
X444767Y378500D01*
G01X452717Y378833D02*
X453717Y375500D01*
X454800Y378833D01*
X455883Y375500D01*
X456883Y378833D01*
G01X460400D02*
Y375500D01*
G01Y380167D02*
X460233Y380250D01*
Y380417D01*
X460400Y380500D01*
X460567Y380417D01*
Y380250D01*
X460400Y380167D01*
G01X467500Y380500D02*
Y375500D01*
G01Y376250D02*
X467167Y375833D01*
X466667Y375583D01*
X466083Y375500D01*
X465417Y375667D01*
X464917Y376083D01*
X464583Y376583D01*
X464500Y377167D01*
X464583Y377750D01*
X464917Y378250D01*
X465417Y378667D01*
X466083Y378833D01*
X466667Y378750D01*
X467083Y378583D01*
X467500Y378250D01*
G01X471600Y380500D02*
Y375500D01*
G01X470433Y378833D02*
X472767D01*
G01X475783Y375500D02*
Y380500D01*
G01Y378083D02*
X476200Y378500D01*
X476617Y378750D01*
X477283Y378833D01*
X477783Y378750D01*
X478367Y378417D01*
X478617Y377917D01*
Y375500D01*
G01X487150Y376083D02*
X487567Y375750D01*
X488150Y375500D01*
X488650D01*
X489150Y375667D01*
X489483Y375917D01*
X489650Y376250D01*
X489567Y376750D01*
X489233Y377000D01*
X487733Y377500D01*
X487400Y378083D01*
X487567Y378500D01*
X487900Y378750D01*
X488400Y378833D01*
X488900Y378750D01*
X489400Y378500D01*
G01X492500Y373833D02*
Y378833D01*
G01Y378083D02*
X492917Y378500D01*
X493333Y378750D01*
X494000Y378833D01*
X494583Y378750D01*
X495167Y378333D01*
X495417Y377750D01*
X495500Y377167D01*
X495417Y376583D01*
X495167Y376000D01*
X494667Y375667D01*
X494000Y375500D01*
X493417Y375583D01*
X492833Y375833D01*
X492500Y376167D01*
G01X498350Y377750D02*
X501017D01*
X500767Y378333D01*
X500350Y378667D01*
X499767Y378833D01*
X499183Y378750D01*
X498683Y378500D01*
X498350Y377917D01*
X498183Y377417D01*
Y376917D01*
X498350Y376417D01*
X498767Y375917D01*
X499267Y375583D01*
X499850Y375500D01*
X500433Y375667D01*
X501017Y376167D01*
G01X506533Y378417D02*
X505950Y378750D01*
X505450Y378833D01*
X504783Y378667D01*
X504283Y378333D01*
X503950Y377750D01*
X503867Y377167D01*
X503950Y376583D01*
X504283Y376083D01*
X504783Y375667D01*
X505450Y375500D01*
X506033Y375667D01*
X506533Y376000D01*
G01X510800Y378833D02*
Y375500D01*
G01Y380167D02*
X510633Y380250D01*
Y380417D01*
X510800Y380500D01*
X510967Y380417D01*
Y380250D01*
X510800Y380167D01*
G01X515900Y375500D02*
Y379750D01*
X516067Y380167D01*
X516400Y380417D01*
X516900Y380500D01*
X517400Y380333D01*
X517650Y379917D01*
G01X516650Y378500D02*
X514983D01*
G01X522000Y378833D02*
Y375500D01*
G01Y380167D02*
X521833Y380250D01*
Y380417D01*
X522000Y380500D01*
X522167Y380417D01*
Y380250D01*
X522000Y380167D01*
G01X526350Y377750D02*
X529017D01*
X528767Y378333D01*
X528350Y378667D01*
X527767Y378833D01*
X527183Y378750D01*
X526683Y378500D01*
X526350Y377917D01*
X526183Y377417D01*
Y376917D01*
X526350Y376417D01*
X526767Y375917D01*
X527267Y375583D01*
X527850Y375500D01*
X528433Y375667D01*
X529017Y376167D01*
G01X534700Y380500D02*
Y375500D01*
G01Y376250D02*
X534367Y375833D01*
X533867Y375583D01*
X533283Y375500D01*
X532617Y375667D01*
X532117Y376083D01*
X531783Y376583D01*
X531700Y377167D01*
X531783Y377750D01*
X532117Y378250D01*
X532617Y378667D01*
X533283Y378833D01*
X533867Y378750D01*
X534283Y378583D01*
X534700Y378250D01*
G01X544400Y375500D02*
X543900Y375583D01*
X543400Y375917D01*
X543067Y376500D01*
X542900Y377167D01*
X543067Y377833D01*
X543400Y378417D01*
X543900Y378750D01*
X544400Y378833D01*
X544900Y378750D01*
X545400Y378417D01*
X545733Y377833D01*
X545817Y377167D01*
X545733Y376500D01*
X545400Y375917D01*
X544900Y375583D01*
X544400Y375500D01*
G01X548583D02*
Y378833D01*
G01Y378000D02*
X548917Y378417D01*
X549417Y378750D01*
X550083Y378833D01*
X550667Y378750D01*
X551167Y378417D01*
X551417Y377833D01*
Y375500D01*
G01X561200Y380500D02*
Y375500D01*
G01X560033Y378833D02*
X562367D01*
G01X565383Y375500D02*
Y380500D01*
G01Y378083D02*
X565800Y378500D01*
X566217Y378750D01*
X566883Y378833D01*
X567383Y378750D01*
X567967Y378417D01*
X568217Y377917D01*
Y375500D01*
G01X571150Y377750D02*
X573817D01*
X573567Y378333D01*
X573150Y378667D01*
X572567Y378833D01*
X571983Y378750D01*
X571483Y378500D01*
X571150Y377917D01*
X570983Y377417D01*
Y376917D01*
X571150Y376417D01*
X571567Y375917D01*
X572067Y375583D01*
X572650Y375500D01*
X573233Y375667D01*
X573817Y376167D01*
G01X268250Y386000D02*
Y391000D01*
G01X271750D02*
Y386000D01*
G01Y388500D02*
X268250D01*
G01X275600Y386000D02*
X275100Y386083D01*
X274600Y386417D01*
X274267Y387000D01*
X274100Y387667D01*
X274267Y388333D01*
X274600Y388917D01*
X275100Y389250D01*
X275600Y389333D01*
X276100Y389250D01*
X276600Y388917D01*
X276933Y388333D01*
X277017Y387667D01*
X276933Y387000D01*
X276600Y386417D01*
X276100Y386083D01*
X275600Y386000D01*
G01X279117Y389333D02*
X280117Y386000D01*
X281200Y389333D01*
X282283Y386000D01*
X283283Y389333D01*
G01X285550Y388250D02*
X288217D01*
X287967Y388833D01*
X287550Y389167D01*
X286967Y389333D01*
X286383Y389250D01*
X285883Y389000D01*
X285550Y388417D01*
X285383Y387917D01*
Y387417D01*
X285550Y386917D01*
X285967Y386417D01*
X286467Y386083D01*
X287050Y386000D01*
X287633Y386167D01*
X288217Y386667D01*
G01X290900Y389333D02*
X292400Y386000D01*
X293900Y389333D01*
G01X296750Y388250D02*
X299417D01*
X299167Y388833D01*
X298750Y389167D01*
X298167Y389333D01*
X297583Y389250D01*
X297083Y389000D01*
X296750Y388417D01*
X296583Y387917D01*
Y387417D01*
X296750Y386917D01*
X297167Y386417D01*
X297667Y386083D01*
X298250Y386000D01*
X298833Y386167D01*
X299417Y386667D01*
G01X302433Y386000D02*
Y389333D01*
G01Y388667D02*
X302850Y389000D01*
X303267Y389250D01*
X303850Y389333D01*
X304267Y389250D01*
X304767Y389000D01*
G01X309033Y385083D02*
X309367Y386167D01*
G01X314800Y391000D02*
Y386000D01*
G01X313633Y389333D02*
X315967D01*
G01X318983Y386000D02*
Y391000D01*
G01Y388583D02*
X319400Y389000D01*
X319817Y389250D01*
X320483Y389333D01*
X320983Y389250D01*
X321567Y388917D01*
X321817Y388417D01*
Y386000D01*
G01X324750Y388250D02*
X327417D01*
X327167Y388833D01*
X326750Y389167D01*
X326167Y389333D01*
X325583Y389250D01*
X325083Y389000D01*
X324750Y388417D01*
X324583Y387917D01*
Y387417D01*
X324750Y386917D01*
X325167Y386417D01*
X325667Y386083D01*
X326250Y386000D01*
X326833Y386167D01*
X327417Y386667D01*
G01X337200Y391000D02*
Y386000D01*
G01X336033Y389333D02*
X338367D01*
G01X344300Y386000D02*
Y389333D01*
G01Y388750D02*
X343967Y389083D01*
X343467Y389250D01*
X342883Y389333D01*
X342300Y389167D01*
X341800Y388833D01*
X341467Y388333D01*
X341300Y387667D01*
X341467Y387000D01*
X341800Y386500D01*
X342300Y386167D01*
X342883Y386000D01*
X343467Y386083D01*
X343967Y386333D01*
X344300Y386667D01*
G01X346983Y386000D02*
Y389333D01*
G01Y388500D02*
X347317Y388917D01*
X347817Y389250D01*
X348483Y389333D01*
X349067Y389250D01*
X349567Y388917D01*
X349817Y388333D01*
Y386000D01*
G01X352833Y384750D02*
X353417Y384417D01*
X354083Y384333D01*
X354667Y384417D01*
X355167Y384833D01*
X355500Y385417D01*
Y389333D01*
G01Y388667D02*
X355167Y389000D01*
X354667Y389250D01*
X354083Y389333D01*
X353417Y389167D01*
X353000Y388833D01*
X352667Y388250D01*
X352500Y387667D01*
X352583Y387167D01*
X352917Y386583D01*
X353417Y386167D01*
X354083Y386000D01*
X354583Y386083D01*
X355167Y386417D01*
X355500Y386750D01*
G01X358350Y388250D02*
X361017D01*
X360767Y388833D01*
X360350Y389167D01*
X359767Y389333D01*
X359183Y389250D01*
X358683Y389000D01*
X358350Y388417D01*
X358183Y387917D01*
Y387417D01*
X358350Y386917D01*
X358767Y386417D01*
X359267Y386083D01*
X359850Y386000D01*
X360433Y386167D01*
X361017Y386667D01*
G01X363783Y386000D02*
Y389333D01*
G01Y388500D02*
X364117Y388917D01*
X364617Y389250D01*
X365283Y389333D01*
X365867Y389250D01*
X366367Y388917D01*
X366617Y388333D01*
Y386000D01*
G01X372133Y388917D02*
X371550Y389250D01*
X371050Y389333D01*
X370383Y389167D01*
X369883Y388833D01*
X369550Y388250D01*
X369467Y387667D01*
X369550Y387083D01*
X369883Y386583D01*
X370383Y386167D01*
X371050Y386000D01*
X371633Y386167D01*
X372133Y386500D01*
G01X374650Y384500D02*
X375150Y384333D01*
X375817Y384500D01*
X376233Y384833D01*
X376567Y385250D01*
X377067Y386583D01*
X378150Y389333D01*
G01X375483D02*
X377067Y386583D01*
G01X386350D02*
X386767Y386250D01*
X387350Y386000D01*
X387850D01*
X388350Y386167D01*
X388683Y386417D01*
X388850Y386750D01*
X388767Y387250D01*
X388433Y387500D01*
X386933Y388000D01*
X386600Y388583D01*
X386767Y389000D01*
X387100Y389250D01*
X387600Y389333D01*
X388100Y389250D01*
X388600Y389000D01*
G01X391783Y386000D02*
Y391000D01*
G01Y388583D02*
X392200Y389000D01*
X392617Y389250D01*
X393283Y389333D01*
X393783Y389250D01*
X394367Y388917D01*
X394617Y388417D01*
Y386000D01*
G01X398800D02*
X398300Y386083D01*
X397800Y386417D01*
X397467Y387000D01*
X397300Y387667D01*
X397467Y388333D01*
X397800Y388917D01*
X398300Y389250D01*
X398800Y389333D01*
X399300Y389250D01*
X399800Y388917D01*
X400133Y388333D01*
X400217Y387667D01*
X400133Y387000D01*
X399800Y386417D01*
X399300Y386083D01*
X398800Y386000D01*
G01X402983Y389333D02*
Y387000D01*
X403317Y386417D01*
X403817Y386083D01*
X404400Y386000D01*
X404983Y386083D01*
X405483Y386417D01*
X405817Y387000D01*
G01Y386000D02*
Y389333D01*
G01X410000Y386000D02*
Y391000D01*
G01X417100D02*
Y386000D01*
G01Y386750D02*
X416767Y386333D01*
X416267Y386083D01*
X415683Y386000D01*
X415017Y386167D01*
X414517Y386583D01*
X414183Y387083D01*
X414100Y387667D01*
X414183Y388250D01*
X414517Y388750D01*
X415017Y389167D01*
X415683Y389333D01*
X416267Y389250D01*
X416683Y389083D01*
X417100Y388750D01*
G01X425383Y386000D02*
Y389333D01*
G01Y388500D02*
X425717Y388917D01*
X426217Y389250D01*
X426883Y389333D01*
X427467Y389250D01*
X427967Y388917D01*
X428217Y388333D01*
Y386000D01*
G01X432400D02*
X431900Y386083D01*
X431400Y386417D01*
X431067Y387000D01*
X430900Y387667D01*
X431067Y388333D01*
X431400Y388917D01*
X431900Y389250D01*
X432400Y389333D01*
X432900Y389250D01*
X433400Y388917D01*
X433733Y388333D01*
X433817Y387667D01*
X433733Y387000D01*
X433400Y386417D01*
X432900Y386083D01*
X432400Y386000D01*
G01X438000Y391000D02*
Y386000D01*
G01X436833Y389333D02*
X439167D01*
G01X448033Y386000D02*
Y389333D01*
G01Y388667D02*
X448450Y389000D01*
X448867Y389250D01*
X449450Y389333D01*
X449867Y389250D01*
X450367Y389000D01*
G01X453550Y388250D02*
X456217D01*
X455967Y388833D01*
X455550Y389167D01*
X454967Y389333D01*
X454383Y389250D01*
X453883Y389000D01*
X453550Y388417D01*
X453383Y387917D01*
Y387417D01*
X453550Y386917D01*
X453967Y386417D01*
X454467Y386083D01*
X455050Y386000D01*
X455633Y386167D01*
X456217Y386667D01*
G01X461900Y391000D02*
Y386000D01*
G01Y386750D02*
X461567Y386333D01*
X461067Y386083D01*
X460483Y386000D01*
X459817Y386167D01*
X459317Y386583D01*
X458983Y387083D01*
X458900Y387667D01*
X458983Y388250D01*
X459317Y388750D01*
X459817Y389167D01*
X460483Y389333D01*
X461067Y389250D01*
X461483Y389083D01*
X461900Y388750D01*
G01X464583Y389333D02*
Y387000D01*
X464917Y386417D01*
X465417Y386083D01*
X466000Y386000D01*
X466583Y386083D01*
X467083Y386417D01*
X467417Y387000D01*
G01Y386000D02*
Y389333D01*
G01X472933Y388917D02*
X472350Y389250D01*
X471850Y389333D01*
X471183Y389167D01*
X470683Y388833D01*
X470350Y388250D01*
X470267Y387667D01*
X470350Y387083D01*
X470683Y386583D01*
X471183Y386167D01*
X471850Y386000D01*
X472433Y386167D01*
X472933Y386500D01*
G01X475950Y388250D02*
X478617D01*
X478367Y388833D01*
X477950Y389167D01*
X477367Y389333D01*
X476783Y389250D01*
X476283Y389000D01*
X475950Y388417D01*
X475783Y387917D01*
Y387417D01*
X475950Y386917D01*
X476367Y386417D01*
X476867Y386083D01*
X477450Y386000D01*
X478033Y386167D01*
X478617Y386667D01*
G01X488400Y391000D02*
Y386000D01*
G01X487233Y389333D02*
X489567D01*
G01X492583Y386000D02*
Y391000D01*
G01Y388583D02*
X493000Y389000D01*
X493417Y389250D01*
X494083Y389333D01*
X494583Y389250D01*
X495167Y388917D01*
X495417Y388417D01*
Y386000D01*
G01X501100D02*
Y389333D01*
G01Y388750D02*
X500767Y389083D01*
X500267Y389250D01*
X499683Y389333D01*
X499100Y389167D01*
X498600Y388833D01*
X498267Y388333D01*
X498100Y387667D01*
X498267Y387000D01*
X498600Y386500D01*
X499100Y386167D01*
X499683Y386000D01*
X500267Y386083D01*
X500767Y386333D01*
X501100Y386667D01*
G01X510800Y386000D02*
Y391000D01*
G01X517900Y386000D02*
Y389333D01*
G01Y388750D02*
X517567Y389083D01*
X517067Y389250D01*
X516483Y389333D01*
X515900Y389167D01*
X515400Y388833D01*
X515067Y388333D01*
X514900Y387667D01*
X515067Y387000D01*
X515400Y386500D01*
X515900Y386167D01*
X516483Y386000D01*
X517067Y386083D01*
X517567Y386333D01*
X517900Y386667D01*
G01X520583Y386000D02*
Y389333D01*
G01Y388500D02*
X520917Y388917D01*
X521417Y389250D01*
X522083Y389333D01*
X522667Y389250D01*
X523167Y388917D01*
X523417Y388333D01*
Y386000D01*
G01X529100Y391000D02*
Y386000D01*
G01Y386750D02*
X528767Y386333D01*
X528267Y386083D01*
X527683Y386000D01*
X527017Y386167D01*
X526517Y386583D01*
X526183Y387083D01*
X526100Y387667D01*
X526183Y388250D01*
X526517Y388750D01*
X527017Y389167D01*
X527683Y389333D01*
X528267Y389250D01*
X528683Y389083D01*
X529100Y388750D01*
G01X531700Y385833D02*
X534700Y391000D01*
G01X540133Y388917D02*
X539550Y389250D01*
X539050Y389333D01*
X538383Y389167D01*
X537883Y388833D01*
X537550Y388250D01*
X537467Y387667D01*
X537550Y387083D01*
X537883Y386583D01*
X538383Y386167D01*
X539050Y386000D01*
X539633Y386167D01*
X540133Y386500D01*
G01X544400Y386000D02*
X543900Y386083D01*
X543400Y386417D01*
X543067Y387000D01*
X542900Y387667D01*
X543067Y388333D01*
X543400Y388917D01*
X543900Y389250D01*
X544400Y389333D01*
X544900Y389250D01*
X545400Y388917D01*
X545733Y388333D01*
X545817Y387667D01*
X545733Y387000D01*
X545400Y386417D01*
X544900Y386083D01*
X544400Y386000D01*
G01X548583D02*
Y389333D01*
G01Y388500D02*
X548917Y388917D01*
X549417Y389250D01*
X550083Y389333D01*
X550667Y389250D01*
X551167Y388917D01*
X551417Y388333D01*
Y386000D01*
G01X557100Y391000D02*
Y386000D01*
G01Y386750D02*
X556767Y386333D01*
X556267Y386083D01*
X555683Y386000D01*
X555017Y386167D01*
X554517Y386583D01*
X554183Y387083D01*
X554100Y387667D01*
X554183Y388250D01*
X554517Y388750D01*
X555017Y389167D01*
X555683Y389333D01*
X556267Y389250D01*
X556683Y389083D01*
X557100Y388750D01*
G01X559783Y389333D02*
Y387000D01*
X560117Y386417D01*
X560617Y386083D01*
X561200Y386000D01*
X561783Y386083D01*
X562283Y386417D01*
X562617Y387000D01*
G01Y386000D02*
Y389333D01*
G01X568133Y388917D02*
X567550Y389250D01*
X567050Y389333D01*
X566383Y389167D01*
X565883Y388833D01*
X565550Y388250D01*
X565467Y387667D01*
X565550Y387083D01*
X565883Y386583D01*
X566383Y386167D01*
X567050Y386000D01*
X567633Y386167D01*
X568133Y386500D01*
G01X572400Y391000D02*
Y386000D01*
G01X571233Y389333D02*
X573567D01*
G01X578000Y386000D02*
X577500Y386083D01*
X577000Y386417D01*
X576667Y387000D01*
X576500Y387667D01*
X576667Y388333D01*
X577000Y388917D01*
X577500Y389250D01*
X578000Y389333D01*
X578500Y389250D01*
X579000Y388917D01*
X579333Y388333D01*
X579417Y387667D01*
X579333Y387000D01*
X579000Y386417D01*
X578500Y386083D01*
X578000Y386000D01*
G01X582433D02*
Y389333D01*
G01Y388667D02*
X582850Y389000D01*
X583267Y389250D01*
X583850Y389333D01*
X584267Y389250D01*
X584767Y389000D01*
G01X271500Y396500D02*
Y399833D01*
G01Y399250D02*
X271167Y399583D01*
X270667Y399750D01*
X270083Y399833D01*
X269500Y399667D01*
X269000Y399333D01*
X268667Y398833D01*
X268500Y398167D01*
X268667Y397500D01*
X269000Y397000D01*
X269500Y396667D01*
X270083Y396500D01*
X270667Y396583D01*
X271167Y396833D01*
X271500Y397167D01*
G01X276933Y399417D02*
X276350Y399750D01*
X275850Y399833D01*
X275183Y399667D01*
X274683Y399333D01*
X274350Y398750D01*
X274267Y398167D01*
X274350Y397583D01*
X274683Y397083D01*
X275183Y396667D01*
X275850Y396500D01*
X276433Y396667D01*
X276933Y397000D01*
G01X282533Y399417D02*
X281950Y399750D01*
X281450Y399833D01*
X280783Y399667D01*
X280283Y399333D01*
X279950Y398750D01*
X279867Y398167D01*
X279950Y397583D01*
X280283Y397083D01*
X280783Y396667D01*
X281450Y396500D01*
X282033Y396667D01*
X282533Y397000D01*
G01X285550Y398750D02*
X288217D01*
X287967Y399333D01*
X287550Y399667D01*
X286967Y399833D01*
X286383Y399750D01*
X285883Y399500D01*
X285550Y398917D01*
X285383Y398417D01*
Y397917D01*
X285550Y397417D01*
X285967Y396917D01*
X286467Y396583D01*
X287050Y396500D01*
X287633Y396667D01*
X288217Y397167D01*
G01X290900Y394833D02*
Y399833D01*
G01Y399083D02*
X291317Y399500D01*
X291733Y399750D01*
X292400Y399833D01*
X292983Y399750D01*
X293567Y399333D01*
X293817Y398750D01*
X293900Y398167D01*
X293817Y397583D01*
X293567Y397000D01*
X293067Y396667D01*
X292400Y396500D01*
X291817Y396583D01*
X291233Y396833D01*
X290900Y397167D01*
G01X298000Y401500D02*
Y396500D01*
G01X296833Y399833D02*
X299167D01*
G01X305100Y396500D02*
Y399833D01*
G01Y399250D02*
X304767Y399583D01*
X304267Y399750D01*
X303683Y399833D01*
X303100Y399667D01*
X302600Y399333D01*
X302267Y398833D01*
X302100Y398167D01*
X302267Y397500D01*
X302600Y397000D01*
X303100Y396667D01*
X303683Y396500D01*
X304267Y396583D01*
X304767Y396833D01*
X305100Y397167D01*
G01X307700Y396500D02*
Y401500D01*
G01Y399000D02*
X308117Y399500D01*
X308617Y399750D01*
X309117Y399833D01*
X309867Y399667D01*
X310367Y399333D01*
X310700Y398750D01*
Y398083D01*
X310533Y397417D01*
X310200Y396917D01*
X309617Y396583D01*
X309117Y396500D01*
X308617Y396583D01*
X308117Y396833D01*
X307700Y397250D01*
G01X314800Y396500D02*
Y401500D01*
G01X319150Y398750D02*
X321817D01*
X321567Y399333D01*
X321150Y399667D01*
X320567Y399833D01*
X319983Y399750D01*
X319483Y399500D01*
X319150Y398917D01*
X318983Y398417D01*
Y397917D01*
X319150Y397417D01*
X319567Y396917D01*
X320067Y396583D01*
X320650Y396500D01*
X321233Y396667D01*
X321817Y397167D01*
G01X326000Y396333D02*
X325833Y396417D01*
Y396583D01*
X326000Y396667D01*
X326167Y396583D01*
Y396417D01*
X326000Y396333D01*
G01X270000Y412000D02*
Y407000D01*
G01X268083Y412000D02*
X271917D01*
G01X274183Y407000D02*
Y412000D01*
G01Y409583D02*
X274600Y410000D01*
X275017Y410250D01*
X275683Y410333D01*
X276183Y410250D01*
X276767Y409917D01*
X277017Y409417D01*
Y407000D01*
G01X279950Y409250D02*
X282617D01*
X282367Y409833D01*
X281950Y410167D01*
X281367Y410333D01*
X280783Y410250D01*
X280283Y410000D01*
X279950Y409417D01*
X279783Y408917D01*
Y408417D01*
X279950Y407917D01*
X280367Y407417D01*
X280867Y407083D01*
X281450Y407000D01*
X282033Y407167D01*
X282617Y407667D01*
G01X290900Y407000D02*
Y412000D01*
G01Y409500D02*
X291317Y410000D01*
X291817Y410250D01*
X292317Y410333D01*
X293067Y410167D01*
X293567Y409833D01*
X293900Y409250D01*
Y408583D01*
X293733Y407917D01*
X293400Y407417D01*
X292817Y407083D01*
X292317Y407000D01*
X291817Y407083D01*
X291317Y407333D01*
X290900Y407750D01*
G01X296833Y407000D02*
Y410333D01*
G01Y409667D02*
X297250Y410000D01*
X297667Y410250D01*
X298250Y410333D01*
X298667Y410250D01*
X299167Y410000D01*
G01X302350Y409250D02*
X305017D01*
X304767Y409833D01*
X304350Y410167D01*
X303767Y410333D01*
X303183Y410250D01*
X302683Y410000D01*
X302350Y409417D01*
X302183Y408917D01*
Y408417D01*
X302350Y407917D01*
X302767Y407417D01*
X303267Y407083D01*
X303850Y407000D01*
X304433Y407167D01*
X305017Y407667D01*
G01X310700Y407000D02*
Y410333D01*
G01Y409750D02*
X310367Y410083D01*
X309867Y410250D01*
X309283Y410333D01*
X308700Y410167D01*
X308200Y409833D01*
X307867Y409333D01*
X307700Y408667D01*
X307867Y408000D01*
X308200Y407500D01*
X308700Y407167D01*
X309283Y407000D01*
X309867Y407083D01*
X310367Y407333D01*
X310700Y407667D01*
G01X313383Y407000D02*
Y412000D01*
G01X316050Y410333D02*
X313383Y408417D01*
G01X314467Y409167D02*
X316217Y407000D01*
G01X320400D02*
X319900Y407083D01*
X319400Y407417D01*
X319067Y408000D01*
X318900Y408667D01*
X319067Y409333D01*
X319400Y409917D01*
X319900Y410250D01*
X320400Y410333D01*
X320900Y410250D01*
X321400Y409917D01*
X321733Y409333D01*
X321817Y408667D01*
X321733Y408000D01*
X321400Y407417D01*
X320900Y407083D01*
X320400Y407000D01*
G01X324583Y410333D02*
Y408000D01*
X324917Y407417D01*
X325417Y407083D01*
X326000Y407000D01*
X326583Y407083D01*
X327083Y407417D01*
X327417Y408000D01*
G01Y407000D02*
Y410333D01*
G01X331600Y412000D02*
Y407000D01*
G01X330433Y410333D02*
X332767D01*
G01X342800D02*
Y407000D01*
G01Y411667D02*
X342633Y411750D01*
Y411917D01*
X342800Y412000D01*
X342967Y411917D01*
Y411750D01*
X342800Y411667D01*
G01X347150Y407583D02*
X347567Y407250D01*
X348150Y407000D01*
X348650D01*
X349150Y407167D01*
X349483Y407417D01*
X349650Y407750D01*
X349567Y408250D01*
X349233Y408500D01*
X347733Y409000D01*
X347400Y409583D01*
X347567Y410000D01*
X347900Y410250D01*
X348400Y410333D01*
X348900Y410250D01*
X349400Y410000D01*
G01X358183Y407000D02*
Y410333D01*
G01Y409500D02*
X358517Y409917D01*
X359017Y410250D01*
X359683Y410333D01*
X360267Y410250D01*
X360767Y409917D01*
X361017Y409333D01*
Y407000D01*
G01X365200D02*
X364700Y407083D01*
X364200Y407417D01*
X363867Y408000D01*
X363700Y408667D01*
X363867Y409333D01*
X364200Y409917D01*
X364700Y410250D01*
X365200Y410333D01*
X365700Y410250D01*
X366200Y409917D01*
X366533Y409333D01*
X366617Y408667D01*
X366533Y408000D01*
X366200Y407417D01*
X365700Y407083D01*
X365200Y407000D01*
G01X370800Y412000D02*
Y407000D01*
G01X369633Y410333D02*
X371967D01*
G01X383500Y407000D02*
Y410333D01*
G01Y409750D02*
X383167Y410083D01*
X382667Y410250D01*
X382083Y410333D01*
X381500Y410167D01*
X381000Y409833D01*
X380667Y409333D01*
X380500Y408667D01*
X380667Y408000D01*
X381000Y407500D01*
X381500Y407167D01*
X382083Y407000D01*
X382667Y407083D01*
X383167Y407333D01*
X383500Y407667D01*
G01X387600Y407000D02*
Y412000D01*
G01X393200Y407000D02*
Y412000D01*
G01X398800Y407000D02*
X398300Y407083D01*
X397800Y407417D01*
X397467Y408000D01*
X397300Y408667D01*
X397467Y409333D01*
X397800Y409917D01*
X398300Y410250D01*
X398800Y410333D01*
X399300Y410250D01*
X399800Y409917D01*
X400133Y409333D01*
X400217Y408667D01*
X400133Y408000D01*
X399800Y407417D01*
X399300Y407083D01*
X398800Y407000D01*
G01X402317Y410333D02*
X403317Y407000D01*
X404400Y410333D01*
X405483Y407000D01*
X406483Y410333D01*
G01X408750Y409250D02*
X411417D01*
X411167Y409833D01*
X410750Y410167D01*
X410167Y410333D01*
X409583Y410250D01*
X409083Y410000D01*
X408750Y409417D01*
X408583Y408917D01*
Y408417D01*
X408750Y407917D01*
X409167Y407417D01*
X409667Y407083D01*
X410250Y407000D01*
X410833Y407167D01*
X411417Y407667D01*
G01X417100Y412000D02*
Y407000D01*
G01Y407750D02*
X416767Y407333D01*
X416267Y407083D01*
X415683Y407000D01*
X415017Y407167D01*
X414517Y407583D01*
X414183Y408083D01*
X414100Y408667D01*
X414183Y409250D01*
X414517Y409750D01*
X415017Y410167D01*
X415683Y410333D01*
X416267Y410250D01*
X416683Y410083D01*
X417100Y409750D01*
G01X421033Y406083D02*
X421367Y407167D01*
G01X436500Y407000D02*
Y412000D01*
G01Y409500D02*
X436917Y410000D01*
X437417Y410250D01*
X437917Y410333D01*
X438667Y410167D01*
X439167Y409833D01*
X439500Y409250D01*
Y408583D01*
X439333Y407917D01*
X439000Y407417D01*
X438417Y407083D01*
X437917Y407000D01*
X437417Y407083D01*
X436917Y407333D01*
X436500Y407750D01*
G01X442183Y410333D02*
Y408000D01*
X442517Y407417D01*
X443017Y407083D01*
X443600Y407000D01*
X444183Y407083D01*
X444683Y407417D01*
X445017Y408000D01*
G01Y407000D02*
Y410333D01*
G01X449200Y412000D02*
Y407000D01*
G01X448033Y410333D02*
X450367D01*
G01X461900Y407000D02*
Y410333D01*
G01Y409750D02*
X461567Y410083D01*
X461067Y410250D01*
X460483Y410333D01*
X459900Y410167D01*
X459400Y409833D01*
X459067Y409333D01*
X458900Y408667D01*
X459067Y408000D01*
X459400Y407500D01*
X459900Y407167D01*
X460483Y407000D01*
X461067Y407083D01*
X461567Y407333D01*
X461900Y407667D01*
G01X464583Y407000D02*
Y410333D01*
G01Y409500D02*
X464917Y409917D01*
X465417Y410250D01*
X466083Y410333D01*
X466667Y410250D01*
X467167Y409917D01*
X467417Y409333D01*
Y407000D01*
G01X470183D02*
Y410333D01*
G01Y409500D02*
X470517Y409917D01*
X471017Y410250D01*
X471683Y410333D01*
X472267Y410250D01*
X472767Y409917D01*
X473017Y409333D01*
Y407000D01*
G01X475783Y410333D02*
Y408000D01*
X476117Y407417D01*
X476617Y407083D01*
X477200Y407000D01*
X477783Y407083D01*
X478283Y407417D01*
X478617Y408000D01*
G01Y407000D02*
Y410333D01*
G01X484300Y407000D02*
Y410333D01*
G01Y409750D02*
X483967Y410083D01*
X483467Y410250D01*
X482883Y410333D01*
X482300Y410167D01*
X481800Y409833D01*
X481467Y409333D01*
X481300Y408667D01*
X481467Y408000D01*
X481800Y407500D01*
X482300Y407167D01*
X482883Y407000D01*
X483467Y407083D01*
X483967Y407333D01*
X484300Y407667D01*
G01X488400Y407000D02*
Y412000D01*
G01X498433Y407000D02*
Y410333D01*
G01Y409667D02*
X498850Y410000D01*
X499267Y410250D01*
X499850Y410333D01*
X500267Y410250D01*
X500767Y410000D01*
G01X505200Y410333D02*
Y407000D01*
G01Y411667D02*
X505033Y411750D01*
Y411917D01*
X505200Y412000D01*
X505367Y411917D01*
Y411750D01*
X505200Y411667D01*
G01X509383Y407000D02*
Y410333D01*
G01Y409500D02*
X509717Y409917D01*
X510217Y410250D01*
X510883Y410333D01*
X511467Y410250D01*
X511967Y409917D01*
X512217Y409333D01*
Y407000D01*
G01X515233Y405750D02*
X515817Y405417D01*
X516483Y405333D01*
X517067Y405417D01*
X517567Y405833D01*
X517900Y406417D01*
Y410333D01*
G01Y409667D02*
X517567Y410000D01*
X517067Y410250D01*
X516483Y410333D01*
X515817Y410167D01*
X515400Y409833D01*
X515067Y409250D01*
X514900Y408667D01*
X514983Y408167D01*
X515317Y407583D01*
X515817Y407167D01*
X516483Y407000D01*
X516983Y407083D01*
X517567Y407417D01*
X517900Y407750D01*
G01X527600Y412000D02*
Y407000D01*
G01X526433Y410333D02*
X528767D01*
G01X534700Y407000D02*
Y410333D01*
G01Y409750D02*
X534367Y410083D01*
X533867Y410250D01*
X533283Y410333D01*
X532700Y410167D01*
X532200Y409833D01*
X531867Y409333D01*
X531700Y408667D01*
X531867Y408000D01*
X532200Y407500D01*
X532700Y407167D01*
X533283Y407000D01*
X533867Y407083D01*
X534367Y407333D01*
X534700Y407667D01*
G01X537383Y407000D02*
Y410333D01*
G01Y409500D02*
X537717Y409917D01*
X538217Y410250D01*
X538883Y410333D01*
X539467Y410250D01*
X539967Y409917D01*
X540217Y409333D01*
Y407000D01*
G01X543233Y405750D02*
X543817Y405417D01*
X544483Y405333D01*
X545067Y405417D01*
X545567Y405833D01*
X545900Y406417D01*
Y410333D01*
G01Y409667D02*
X545567Y410000D01*
X545067Y410250D01*
X544483Y410333D01*
X543817Y410167D01*
X543400Y409833D01*
X543067Y409250D01*
X542900Y408667D01*
X542983Y408167D01*
X543317Y407583D01*
X543817Y407167D01*
X544483Y407000D01*
X544983Y407083D01*
X545567Y407417D01*
X545900Y407750D01*
G01X548750Y409250D02*
X551417D01*
X551167Y409833D01*
X550750Y410167D01*
X550167Y410333D01*
X549583Y410250D01*
X549083Y410000D01*
X548750Y409417D01*
X548583Y408917D01*
Y408417D01*
X548750Y407917D01*
X549167Y407417D01*
X549667Y407083D01*
X550250Y407000D01*
X550833Y407167D01*
X551417Y407667D01*
G01X554183Y407000D02*
Y410333D01*
G01Y409500D02*
X554517Y409917D01*
X555017Y410250D01*
X555683Y410333D01*
X556267Y410250D01*
X556767Y409917D01*
X557017Y409333D01*
Y407000D01*
G01X562533Y409917D02*
X561950Y410250D01*
X561450Y410333D01*
X560783Y410167D01*
X560283Y409833D01*
X559950Y409250D01*
X559867Y408667D01*
X559950Y408083D01*
X560283Y407583D01*
X560783Y407167D01*
X561450Y407000D01*
X562033Y407167D01*
X562533Y407500D01*
G01X565050Y405500D02*
X565550Y405333D01*
X566217Y405500D01*
X566633Y405833D01*
X566967Y406250D01*
X567467Y407583D01*
X568550Y410333D01*
G01X565883D02*
X567467Y407583D01*
G01X578000Y410333D02*
Y407000D01*
G01Y411667D02*
X577833Y411750D01*
Y411917D01*
X578000Y412000D01*
X578167Y411917D01*
Y411750D01*
X578000Y411667D01*
G01X582350Y407583D02*
X582767Y407250D01*
X583350Y407000D01*
X583850D01*
X584350Y407167D01*
X584683Y407417D01*
X584850Y407750D01*
X584767Y408250D01*
X584433Y408500D01*
X582933Y409000D01*
X582600Y409583D01*
X582767Y410000D01*
X583100Y410250D01*
X583600Y410333D01*
X584100Y410250D01*
X584600Y410000D01*
G01X273000Y434000D02*
Y429000D01*
G01Y429750D02*
X272667Y429333D01*
X272167Y429083D01*
X271583Y429000D01*
X270917Y429167D01*
X270417Y429583D01*
X270083Y430083D01*
X270000Y430667D01*
X270083Y431250D01*
X270417Y431750D01*
X270917Y432167D01*
X271583Y432333D01*
X272167Y432250D01*
X272583Y432083D01*
X273000Y431750D01*
G01X275850Y431250D02*
X278517D01*
X278267Y431833D01*
X277850Y432167D01*
X277267Y432333D01*
X276683Y432250D01*
X276183Y432000D01*
X275850Y431417D01*
X275683Y430917D01*
Y430417D01*
X275850Y429917D01*
X276267Y429417D01*
X276767Y429083D01*
X277350Y429000D01*
X277933Y429167D01*
X278517Y429667D01*
G01X281200Y427333D02*
Y432333D01*
G01Y431583D02*
X281617Y432000D01*
X282033Y432250D01*
X282700Y432333D01*
X283283Y432250D01*
X283867Y431833D01*
X284117Y431250D01*
X284200Y430667D01*
X284117Y430083D01*
X283867Y429500D01*
X283367Y429167D01*
X282700Y429000D01*
X282117Y429083D01*
X281533Y429333D01*
X281200Y429667D01*
G01X288300Y434000D02*
Y429000D01*
G01X287133Y432333D02*
X289467D01*
G01X292483Y429000D02*
Y434000D01*
G01Y431583D02*
X292900Y432000D01*
X293317Y432250D01*
X293983Y432333D01*
X294483Y432250D01*
X295067Y431917D01*
X295317Y431417D01*
Y429000D01*
G01X305100Y434000D02*
Y429000D01*
G01X303933Y432333D02*
X306267D01*
G01X310700Y429000D02*
X310200Y429083D01*
X309700Y429417D01*
X309367Y430000D01*
X309200Y430667D01*
X309367Y431333D01*
X309700Y431917D01*
X310200Y432250D01*
X310700Y432333D01*
X311200Y432250D01*
X311700Y431917D01*
X312033Y431333D01*
X312117Y430667D01*
X312033Y430000D01*
X311700Y429417D01*
X311200Y429083D01*
X310700Y429000D01*
G01X316300D02*
Y434000D01*
G01X320650Y431250D02*
X323317D01*
X323067Y431833D01*
X322650Y432167D01*
X322067Y432333D01*
X321483Y432250D01*
X320983Y432000D01*
X320650Y431417D01*
X320483Y430917D01*
Y430417D01*
X320650Y429917D01*
X321067Y429417D01*
X321567Y429083D01*
X322150Y429000D01*
X322733Y429167D01*
X323317Y429667D01*
G01X326333Y429000D02*
Y432333D01*
G01Y431667D02*
X326750Y432000D01*
X327167Y432250D01*
X327750Y432333D01*
X328167Y432250D01*
X328667Y432000D01*
G01X334600Y429000D02*
Y432333D01*
G01Y431750D02*
X334267Y432083D01*
X333767Y432250D01*
X333183Y432333D01*
X332600Y432167D01*
X332100Y431833D01*
X331767Y431333D01*
X331600Y430667D01*
X331767Y430000D01*
X332100Y429500D01*
X332600Y429167D01*
X333183Y429000D01*
X333767Y429083D01*
X334267Y429333D01*
X334600Y429667D01*
G01X337283Y429000D02*
Y432333D01*
G01Y431500D02*
X337617Y431917D01*
X338117Y432250D01*
X338783Y432333D01*
X339367Y432250D01*
X339867Y431917D01*
X340117Y431333D01*
Y429000D01*
G01X345633Y431917D02*
X345050Y432250D01*
X344550Y432333D01*
X343883Y432167D01*
X343383Y431833D01*
X343050Y431250D01*
X342967Y430667D01*
X343050Y430083D01*
X343383Y429583D01*
X343883Y429167D01*
X344550Y429000D01*
X345133Y429167D01*
X345633Y429500D01*
G01X348650Y431250D02*
X351317D01*
X351067Y431833D01*
X350650Y432167D01*
X350067Y432333D01*
X349483Y432250D01*
X348983Y432000D01*
X348650Y431417D01*
X348483Y430917D01*
Y430417D01*
X348650Y429917D01*
X349067Y429417D01*
X349567Y429083D01*
X350150Y429000D01*
X350733Y429167D01*
X351317Y429667D01*
G01X270750Y450000D02*
Y455000D01*
G01X274250D02*
Y450000D01*
G01Y452500D02*
X270750D01*
G01X278100Y450000D02*
X277600Y450083D01*
X277100Y450417D01*
X276767Y451000D01*
X276600Y451667D01*
X276767Y452333D01*
X277100Y452917D01*
X277600Y453250D01*
X278100Y453333D01*
X278600Y453250D01*
X279100Y452917D01*
X279433Y452333D01*
X279517Y451667D01*
X279433Y451000D01*
X279100Y450417D01*
X278600Y450083D01*
X278100Y450000D01*
G01X283700D02*
Y455000D01*
G01X288050Y452250D02*
X290717D01*
X290467Y452833D01*
X290050Y453167D01*
X289467Y453333D01*
X288883Y453250D01*
X288383Y453000D01*
X288050Y452417D01*
X287883Y451917D01*
Y451417D01*
X288050Y450917D01*
X288467Y450417D01*
X288967Y450083D01*
X289550Y450000D01*
X290133Y450167D01*
X290717Y450667D01*
G01X298000Y455000D02*
X299167Y450000D01*
X300500Y455000D01*
X301833Y450000D01*
X303000Y455000D01*
G01X307600Y450000D02*
Y453333D01*
G01Y452750D02*
X307267Y453083D01*
X306767Y453250D01*
X306183Y453333D01*
X305600Y453167D01*
X305100Y452833D01*
X304767Y452333D01*
X304600Y451667D01*
X304767Y451000D01*
X305100Y450500D01*
X305600Y450167D01*
X306183Y450000D01*
X306767Y450083D01*
X307267Y450333D01*
X307600Y450667D01*
G01X311700Y450000D02*
Y455000D01*
G01X317300Y450000D02*
Y455000D01*
G01X326833Y450000D02*
Y455000D01*
X328917D01*
X329583Y454750D01*
X330000Y454417D01*
X330167Y453750D01*
X330000Y453083D01*
X329500Y452667D01*
X328917Y452417D01*
X326833D01*
G01X328917D02*
X330167Y450000D01*
G01X334100D02*
X333600Y450083D01*
X333100Y450417D01*
X332767Y451000D01*
X332600Y451667D01*
X332767Y452333D01*
X333100Y452917D01*
X333600Y453250D01*
X334100Y453333D01*
X334600Y453250D01*
X335100Y452917D01*
X335433Y452333D01*
X335517Y451667D01*
X335433Y451000D01*
X335100Y450417D01*
X334600Y450083D01*
X334100Y450000D01*
G01X338283Y453333D02*
Y451000D01*
X338617Y450417D01*
X339117Y450083D01*
X339700Y450000D01*
X340283Y450083D01*
X340783Y450417D01*
X341117Y451000D01*
G01Y450000D02*
Y453333D01*
G01X344133Y448750D02*
X344717Y448417D01*
X345383Y448333D01*
X345967Y448417D01*
X346467Y448833D01*
X346800Y449417D01*
Y453333D01*
G01Y452667D02*
X346467Y453000D01*
X345967Y453250D01*
X345383Y453333D01*
X344717Y453167D01*
X344300Y452833D01*
X343967Y452250D01*
X343800Y451667D01*
X343883Y451167D01*
X344217Y450583D01*
X344717Y450167D01*
X345383Y450000D01*
X345883Y450083D01*
X346467Y450417D01*
X346800Y450750D01*
G01X349483Y450000D02*
Y455000D01*
G01Y452583D02*
X349900Y453000D01*
X350317Y453250D01*
X350983Y453333D01*
X351483Y453250D01*
X352067Y452917D01*
X352317Y452417D01*
Y450000D01*
G01X355083D02*
Y453333D01*
G01Y452500D02*
X355417Y452917D01*
X355917Y453250D01*
X356583Y453333D01*
X357167Y453250D01*
X357667Y452917D01*
X357917Y452333D01*
Y450000D01*
G01X360850Y452250D02*
X363517D01*
X363267Y452833D01*
X362850Y453167D01*
X362267Y453333D01*
X361683Y453250D01*
X361183Y453000D01*
X360850Y452417D01*
X360683Y451917D01*
Y451417D01*
X360850Y450917D01*
X361267Y450417D01*
X361767Y450083D01*
X362350Y450000D01*
X362933Y450167D01*
X363517Y450667D01*
G01X366450Y450583D02*
X366867Y450250D01*
X367450Y450000D01*
X367950D01*
X368450Y450167D01*
X368783Y450417D01*
X368950Y450750D01*
X368867Y451250D01*
X368533Y451500D01*
X367033Y452000D01*
X366700Y452583D01*
X366867Y453000D01*
X367200Y453250D01*
X367700Y453333D01*
X368200Y453250D01*
X368700Y453000D01*
G01X372050Y450583D02*
X372467Y450250D01*
X373050Y450000D01*
X373550D01*
X374050Y450167D01*
X374383Y450417D01*
X374550Y450750D01*
X374467Y451250D01*
X374133Y451500D01*
X372633Y452000D01*
X372300Y452583D01*
X372467Y453000D01*
X372800Y453250D01*
X373300Y453333D01*
X373800Y453250D01*
X374300Y453000D01*
G01X272500Y466500D02*
X271833Y466583D01*
X271250Y466917D01*
X270750Y467417D01*
X270417Y468000D01*
X270250Y468667D01*
Y469333D01*
X270417Y470000D01*
X270750Y470583D01*
X271250Y471083D01*
X271833Y471417D01*
X272500Y471500D01*
X273167Y471417D01*
X273750Y471083D01*
X274250Y470583D01*
X274583Y470000D01*
X274750Y469333D01*
Y468667D01*
X274583Y468000D01*
X274250Y467417D01*
X273750Y466917D01*
X273167Y466583D01*
X272500Y466500D01*
G01X278100Y471500D02*
Y466500D01*
G01X276933Y469833D02*
X279267D01*
G01X282283Y466500D02*
Y471500D01*
G01Y469083D02*
X282700Y469500D01*
X283117Y469750D01*
X283783Y469833D01*
X284283Y469750D01*
X284867Y469417D01*
X285117Y468917D01*
Y466500D01*
G01X288050Y468750D02*
X290717D01*
X290467Y469333D01*
X290050Y469667D01*
X289467Y469833D01*
X288883Y469750D01*
X288383Y469500D01*
X288050Y468917D01*
X287883Y468417D01*
Y467917D01*
X288050Y467417D01*
X288467Y466917D01*
X288967Y466583D01*
X289550Y466500D01*
X290133Y466667D01*
X290717Y467167D01*
G01X293733Y466500D02*
Y469833D01*
G01Y469167D02*
X294150Y469500D01*
X294567Y469750D01*
X295150Y469833D01*
X295567Y469750D01*
X296067Y469500D01*
G01X299250Y467083D02*
X299667Y466750D01*
X300250Y466500D01*
X300750D01*
X301250Y466667D01*
X301583Y466917D01*
X301750Y467250D01*
X301667Y467750D01*
X301333Y468000D01*
X299833Y468500D01*
X299500Y469083D01*
X299667Y469500D01*
X300000Y469750D01*
X300500Y469833D01*
X301000Y469750D01*
X301500Y469500D01*
G01X311283Y464833D02*
X310450Y465667D01*
X310033Y466500D01*
Y469833D01*
X310450Y470667D01*
X311283Y471500D01*
G01X317300Y466500D02*
Y471500D01*
G01X322900Y469833D02*
Y466500D01*
G01Y471167D02*
X322733Y471250D01*
Y471417D01*
X322900Y471500D01*
X323067Y471417D01*
Y471250D01*
X322900Y471167D01*
G01X327083Y466500D02*
Y471500D01*
G01X329750Y469833D02*
X327083Y467917D01*
G01X328167Y468667D02*
X329917Y466500D01*
G01X332850Y468750D02*
X335517D01*
X335267Y469333D01*
X334850Y469667D01*
X334267Y469833D01*
X333683Y469750D01*
X333183Y469500D01*
X332850Y468917D01*
X332683Y468417D01*
Y467917D01*
X332850Y467417D01*
X333267Y466917D01*
X333767Y466583D01*
X334350Y466500D01*
X334933Y466667D01*
X335517Y467167D01*
G01X344050Y468750D02*
X346717D01*
X346467Y469333D01*
X346050Y469667D01*
X345467Y469833D01*
X344883Y469750D01*
X344383Y469500D01*
X344050Y468917D01*
X343883Y468417D01*
Y467917D01*
X344050Y467417D01*
X344467Y466917D01*
X344967Y466583D01*
X345550Y466500D01*
X346133Y466667D01*
X346717Y467167D01*
G01X350900Y466500D02*
Y471500D01*
G01X356500Y466500D02*
Y471500D01*
G01X362100Y469833D02*
Y466500D01*
G01Y471167D02*
X361933Y471250D01*
Y471417D01*
X362100Y471500D01*
X362267Y471417D01*
Y471250D01*
X362100Y471167D01*
G01X366200Y464833D02*
Y469833D01*
G01Y469083D02*
X366617Y469500D01*
X367033Y469750D01*
X367700Y469833D01*
X368283Y469750D01*
X368867Y469333D01*
X369117Y468750D01*
X369200Y468167D01*
X369117Y467583D01*
X368867Y467000D01*
X368367Y466667D01*
X367700Y466500D01*
X367117Y466583D01*
X366533Y466833D01*
X366200Y467167D01*
G01X372050Y467083D02*
X372467Y466750D01*
X373050Y466500D01*
X373550D01*
X374050Y466667D01*
X374383Y466917D01*
X374550Y467250D01*
X374467Y467750D01*
X374133Y468000D01*
X372633Y468500D01*
X372300Y469083D01*
X372467Y469500D01*
X372800Y469750D01*
X373300Y469833D01*
X373800Y469750D01*
X374300Y469500D01*
G01X377650Y468750D02*
X380317D01*
X380067Y469333D01*
X379650Y469667D01*
X379067Y469833D01*
X378483Y469750D01*
X377983Y469500D01*
X377650Y468917D01*
X377483Y468417D01*
Y467917D01*
X377650Y467417D01*
X378067Y466917D01*
X378567Y466583D01*
X379150Y466500D01*
X379733Y466667D01*
X380317Y467167D01*
G01X391600Y466500D02*
Y469833D01*
G01Y469250D02*
X391267Y469583D01*
X390767Y469750D01*
X390183Y469833D01*
X389600Y469667D01*
X389100Y469333D01*
X388767Y468833D01*
X388600Y468167D01*
X388767Y467500D01*
X389100Y467000D01*
X389600Y466667D01*
X390183Y466500D01*
X390767Y466583D01*
X391267Y466833D01*
X391600Y467167D01*
G01X394283Y466500D02*
Y469833D01*
G01Y469000D02*
X394617Y469417D01*
X395117Y469750D01*
X395783Y469833D01*
X396367Y469750D01*
X396867Y469417D01*
X397117Y468833D01*
Y466500D01*
G01X402800Y471500D02*
Y466500D01*
G01Y467250D02*
X402467Y466833D01*
X401967Y466583D01*
X401383Y466500D01*
X400717Y466667D01*
X400217Y467083D01*
X399883Y467583D01*
X399800Y468167D01*
X399883Y468750D01*
X400217Y469250D01*
X400717Y469667D01*
X401383Y469833D01*
X401967Y469750D01*
X402383Y469583D01*
X402800Y469250D01*
G01X412500Y466500D02*
X412000Y466583D01*
X411500Y466917D01*
X411167Y467500D01*
X411000Y468167D01*
X411167Y468833D01*
X411500Y469417D01*
X412000Y469750D01*
X412500Y469833D01*
X413000Y469750D01*
X413500Y469417D01*
X413833Y468833D01*
X413917Y468167D01*
X413833Y467500D01*
X413500Y466917D01*
X413000Y466583D01*
X412500Y466500D01*
G01X418100Y471500D02*
Y466500D01*
G01X416933Y469833D02*
X419267D01*
G01X422283Y466500D02*
Y471500D01*
G01Y469083D02*
X422700Y469500D01*
X423117Y469750D01*
X423783Y469833D01*
X424283Y469750D01*
X424867Y469417D01*
X425117Y468917D01*
Y466500D01*
G01X428050Y468750D02*
X430717D01*
X430467Y469333D01*
X430050Y469667D01*
X429467Y469833D01*
X428883Y469750D01*
X428383Y469500D01*
X428050Y468917D01*
X427883Y468417D01*
Y467917D01*
X428050Y467417D01*
X428467Y466917D01*
X428967Y466583D01*
X429550Y466500D01*
X430133Y466667D01*
X430717Y467167D01*
G01X433733Y466500D02*
Y469833D01*
G01Y469167D02*
X434150Y469500D01*
X434567Y469750D01*
X435150Y469833D01*
X435567Y469750D01*
X436067Y469500D01*
G01X439250Y467083D02*
X439667Y466750D01*
X440250Y466500D01*
X440750D01*
X441250Y466667D01*
X441583Y466917D01*
X441750Y467250D01*
X441667Y467750D01*
X441333Y468000D01*
X439833Y468500D01*
X439500Y469083D01*
X439667Y469500D01*
X440000Y469750D01*
X440500Y469833D01*
X441000Y469750D01*
X441500Y469500D01*
G01X446517Y464833D02*
X447350Y465667D01*
X447767Y466500D01*
Y469833D01*
X447350Y470667D01*
X446517Y471500D01*
G01X270833Y481500D02*
Y486500D01*
X272833D01*
X273500Y486250D01*
X274000Y485667D01*
X274167Y485000D01*
X274000Y484333D01*
X273583Y483833D01*
X272833Y483583D01*
X270833D01*
G01X278100Y486500D02*
Y481500D01*
G01X276183Y486500D02*
X280017D01*
G01X281950Y481500D02*
Y486500D01*
G01X285450D02*
Y481500D01*
G01Y484000D02*
X281950D01*
G01X287800Y481333D02*
X290800Y486500D01*
G01X292983Y481500D02*
Y486500D01*
X296817Y481500D01*
Y486500D01*
G01X298833Y481500D02*
Y486500D01*
X300833D01*
X301500Y486250D01*
X302000Y485667D01*
X302167Y485000D01*
X302000Y484333D01*
X301583Y483833D01*
X300833Y483583D01*
X298833D01*
G01X306100Y486500D02*
Y481500D01*
G01X304183Y486500D02*
X308017D01*
G01X309950Y481500D02*
Y486500D01*
G01X313450D02*
Y481500D01*
G01Y484000D02*
X309950D01*
G01X321233Y481500D02*
X324567Y483167D01*
X321233Y484833D01*
G01X327417Y482417D02*
X329583D01*
G01Y483917D02*
X327417D01*
G01X332267Y482250D02*
X332767Y481833D01*
X333350Y481583D01*
X334100Y481500D01*
X334850Y481667D01*
X335433Y482000D01*
X335850Y482583D01*
X335933Y483250D01*
X335767Y483917D01*
X335350Y484333D01*
X334767Y484667D01*
X334183Y484750D01*
X333600Y484667D01*
X332850Y484333D01*
X333100Y486500D01*
X335350D01*
G01X342800Y481500D02*
Y484833D01*
G01Y483917D02*
X343050Y484333D01*
X343467Y484667D01*
X344050Y484833D01*
X344633Y484667D01*
X345050Y484333D01*
X345300Y483917D01*
Y481500D01*
G01Y483917D02*
X345550Y484333D01*
X345967Y484667D01*
X346550Y484833D01*
X347133Y484667D01*
X347550Y484333D01*
X347800Y483833D01*
Y481500D01*
G01X348400D02*
Y484833D01*
G01Y483917D02*
X348650Y484333D01*
X349067Y484667D01*
X349650Y484833D01*
X350233Y484667D01*
X350650Y484333D01*
X350900Y483917D01*
Y481500D01*
G01Y483917D02*
X351150Y484333D01*
X351567Y484667D01*
X352150Y484833D01*
X352733Y484667D01*
X353150Y484333D01*
X353400Y483833D01*
Y481500D01*
G01X262500Y475500D02*
X694500D01*
G01X262500Y445500D02*
Y679000D01*
G01X270583Y510000D02*
Y515000D01*
X274417Y510000D01*
Y515000D01*
G01X276433Y510000D02*
Y515000D01*
X278433D01*
X279100Y514750D01*
X279600Y514167D01*
X279767Y513500D01*
X279600Y512833D01*
X279183Y512333D01*
X278433Y512083D01*
X276433D01*
G01X283700Y515000D02*
Y510000D01*
G01X281783Y515000D02*
X285617D01*
G01X287550Y510000D02*
Y515000D01*
G01X291050D02*
Y510000D01*
G01Y512500D02*
X287550D01*
G01X298750Y510667D02*
X299417Y510250D01*
X300167Y510000D01*
X300833D01*
X301500Y510250D01*
X302000Y510667D01*
X302250Y511250D01*
X302083Y511833D01*
X301667Y512333D01*
X300917Y512667D01*
X299917Y512833D01*
X299333Y513167D01*
X299083Y513750D01*
X299250Y514333D01*
X299667Y514750D01*
X300250Y515000D01*
X300833D01*
X301417Y514833D01*
X301917Y514417D01*
G01X306100Y513333D02*
Y510000D01*
G01Y514667D02*
X305933Y514750D01*
Y514917D01*
X306100Y515000D01*
X306267Y514917D01*
Y514750D01*
X306100Y514667D01*
G01X310450Y513333D02*
X312950D01*
X310450Y510000D01*
X312950D01*
G01X316050Y512250D02*
X318717D01*
X318467Y512833D01*
X318050Y513167D01*
X317467Y513333D01*
X316883Y513250D01*
X316383Y513000D01*
X316050Y512417D01*
X315883Y511917D01*
Y511417D01*
X316050Y510917D01*
X316467Y510417D01*
X316967Y510083D01*
X317550Y510000D01*
X318133Y510167D01*
X318717Y510667D01*
G01X326667Y511000D02*
X327167Y510417D01*
X327833Y510083D01*
X328583Y510000D01*
X329250Y510083D01*
X329917Y510500D01*
X330333Y511000D01*
X330417Y511500D01*
X330250Y512083D01*
X329667Y512500D01*
X329083Y512667D01*
X328333D01*
G01X329083D02*
X329583Y512917D01*
X330000Y513333D01*
X330167Y513833D01*
X330000Y514333D01*
X329583Y514750D01*
X328833Y515000D01*
X328083Y514917D01*
X327333Y514583D01*
G01X334100Y509833D02*
X333933Y509917D01*
Y510083D01*
X334100Y510167D01*
X334267Y510083D01*
Y509917D01*
X334100Y509833D01*
G01X337867Y510750D02*
X338367Y510333D01*
X338950Y510083D01*
X339700Y510000D01*
X340450Y510167D01*
X341033Y510500D01*
X341450Y511083D01*
X341533Y511750D01*
X341367Y512417D01*
X340950Y512833D01*
X340367Y513167D01*
X339783Y513250D01*
X339200Y513167D01*
X338450Y512833D01*
X338700Y515000D01*
X340950D01*
G01X343467Y510750D02*
X343967Y510333D01*
X344550Y510083D01*
X345300Y510000D01*
X346050Y510167D01*
X346633Y510500D01*
X347050Y511083D01*
X347133Y511750D01*
X346967Y512417D01*
X346550Y512833D01*
X345967Y513167D01*
X345383Y513250D01*
X344800Y513167D01*
X344050Y512833D01*
X344300Y515000D01*
X346550D01*
G01X348400Y510000D02*
Y513333D01*
G01Y512417D02*
X348650Y512833D01*
X349067Y513167D01*
X349650Y513333D01*
X350233Y513167D01*
X350650Y512833D01*
X350900Y512417D01*
Y510000D01*
G01Y512417D02*
X351150Y512833D01*
X351567Y513167D01*
X352150Y513333D01*
X352733Y513167D01*
X353150Y512833D01*
X353400Y512333D01*
Y510000D01*
G01X354000D02*
Y513333D01*
G01Y512417D02*
X354250Y512833D01*
X354667Y513167D01*
X355250Y513333D01*
X355833Y513167D01*
X356250Y512833D01*
X356500Y512417D01*
Y510000D01*
G01Y512417D02*
X356750Y512833D01*
X357167Y513167D01*
X357750Y513333D01*
X358333Y513167D01*
X358750Y512833D01*
X359000Y512333D01*
Y510000D01*
G01X270583Y495000D02*
Y500000D01*
X274417Y495000D01*
Y500000D01*
G01X276433Y495000D02*
Y500000D01*
X278433D01*
X279100Y499750D01*
X279600Y499167D01*
X279767Y498500D01*
X279600Y497833D01*
X279183Y497333D01*
X278433Y497083D01*
X276433D01*
G01X283700Y500000D02*
Y495000D01*
G01X281783Y500000D02*
X285617D01*
G01X287550Y495000D02*
Y500000D01*
G01X291050D02*
Y495000D01*
G01Y497500D02*
X287550D01*
G01X298750Y495667D02*
X299417Y495250D01*
X300167Y495000D01*
X300833D01*
X301500Y495250D01*
X302000Y495667D01*
X302250Y496250D01*
X302083Y496833D01*
X301667Y497333D01*
X300917Y497667D01*
X299917Y497833D01*
X299333Y498167D01*
X299083Y498750D01*
X299250Y499333D01*
X299667Y499750D01*
X300250Y500000D01*
X300833D01*
X301417Y499833D01*
X301917Y499417D01*
G01X306100Y498333D02*
Y495000D01*
G01Y499667D02*
X305933Y499750D01*
Y499917D01*
X306100Y500000D01*
X306267Y499917D01*
Y499750D01*
X306100Y499667D01*
G01X310450Y498333D02*
X312950D01*
X310450Y495000D01*
X312950D01*
G01X316050Y497250D02*
X318717D01*
X318467Y497833D01*
X318050Y498167D01*
X317467Y498333D01*
X316883Y498250D01*
X316383Y498000D01*
X316050Y497417D01*
X315883Y496917D01*
Y496417D01*
X316050Y495917D01*
X316467Y495417D01*
X316967Y495083D01*
X317550Y495000D01*
X318133Y495167D01*
X318717Y495667D01*
G01X326917Y499167D02*
X327417Y499667D01*
X328000Y499917D01*
X328667Y500000D01*
X329500Y499833D01*
X330083Y499417D01*
X330250Y498917D01*
X330167Y498417D01*
X329833Y498000D01*
X328167Y497167D01*
X327417Y496583D01*
X326917Y495750D01*
X326750Y495000D01*
X330250D01*
G01X334100Y494833D02*
X333933Y494917D01*
Y495083D01*
X334100Y495167D01*
X334267Y495083D01*
Y494917D01*
X334100Y494833D01*
G01X339700Y495000D02*
Y500000D01*
X338700Y499000D01*
G01Y495000D02*
X340700D01*
G01X345300D02*
X345883Y495083D01*
X346550Y495333D01*
X346967Y495750D01*
X347133Y496333D01*
X346967Y496917D01*
X346467Y497417D01*
X345717Y497667D01*
X344883D01*
X344383Y497833D01*
X343967Y498250D01*
X343800Y498833D01*
X344050Y499417D01*
X344633Y499833D01*
X345300Y500000D01*
X345967Y499833D01*
X346550Y499417D01*
X346800Y498833D01*
X346633Y498250D01*
X346217Y497833D01*
X345717Y497667D01*
X344883D01*
X344133Y497417D01*
X343633Y496917D01*
X343467Y496333D01*
X343633Y495750D01*
X344050Y495333D01*
X344717Y495083D01*
X345300Y495000D01*
G01X348400D02*
Y498333D01*
G01Y497417D02*
X348650Y497833D01*
X349067Y498167D01*
X349650Y498333D01*
X350233Y498167D01*
X350650Y497833D01*
X350900Y497417D01*
Y495000D01*
G01Y497417D02*
X351150Y497833D01*
X351567Y498167D01*
X352150Y498333D01*
X352733Y498167D01*
X353150Y497833D01*
X353400Y497333D01*
Y495000D01*
G01X354000D02*
Y498333D01*
G01Y497417D02*
X354250Y497833D01*
X354667Y498167D01*
X355250Y498333D01*
X355833Y498167D01*
X356250Y497833D01*
X356500Y497417D01*
Y495000D01*
G01Y497417D02*
X356750Y497833D01*
X357167Y498167D01*
X357750Y498333D01*
X358333Y498167D01*
X358750Y497833D01*
X359000Y497333D01*
Y495000D01*
G01X367283Y493333D02*
X366450Y494167D01*
X366033Y495000D01*
Y498333D01*
X366450Y499167D01*
X367283Y500000D01*
G01X373300Y495000D02*
X372800Y495083D01*
X372300Y495417D01*
X371967Y496000D01*
X371800Y496667D01*
X371967Y497333D01*
X372300Y497917D01*
X372800Y498250D01*
X373300Y498333D01*
X373800Y498250D01*
X374300Y497917D01*
X374633Y497333D01*
X374717Y496667D01*
X374633Y496000D01*
X374300Y495417D01*
X373800Y495083D01*
X373300Y495000D01*
G01X377483D02*
Y498333D01*
G01Y497500D02*
X377817Y497917D01*
X378317Y498250D01*
X378983Y498333D01*
X379567Y498250D01*
X380067Y497917D01*
X380317Y497333D01*
Y495000D01*
G01X388600D02*
Y500000D01*
G01Y497500D02*
X389017Y498000D01*
X389517Y498250D01*
X390017Y498333D01*
X390767Y498167D01*
X391267Y497833D01*
X391600Y497250D01*
Y496583D01*
X391433Y495917D01*
X391100Y495417D01*
X390517Y495083D01*
X390017Y495000D01*
X389517Y495083D01*
X389017Y495333D01*
X388600Y495750D01*
G01X394533Y495000D02*
Y498333D01*
G01Y497667D02*
X394950Y498000D01*
X395367Y498250D01*
X395950Y498333D01*
X396367Y498250D01*
X396867Y498000D01*
G01X400050Y497250D02*
X402717D01*
X402467Y497833D01*
X402050Y498167D01*
X401467Y498333D01*
X400883Y498250D01*
X400383Y498000D01*
X400050Y497417D01*
X399883Y496917D01*
Y496417D01*
X400050Y495917D01*
X400467Y495417D01*
X400967Y495083D01*
X401550Y495000D01*
X402133Y495167D01*
X402717Y495667D01*
G01X408400Y495000D02*
Y498333D01*
G01Y497750D02*
X408067Y498083D01*
X407567Y498250D01*
X406983Y498333D01*
X406400Y498167D01*
X405900Y497833D01*
X405567Y497333D01*
X405400Y496667D01*
X405567Y496000D01*
X405900Y495500D01*
X406400Y495167D01*
X406983Y495000D01*
X407567Y495083D01*
X408067Y495333D01*
X408400Y495667D01*
G01X411083Y495000D02*
Y500000D01*
G01X413750Y498333D02*
X411083Y496417D01*
G01X412167Y497167D02*
X413917Y495000D01*
G01X419600D02*
Y498333D01*
G01Y497750D02*
X419267Y498083D01*
X418767Y498250D01*
X418183Y498333D01*
X417600Y498167D01*
X417100Y497833D01*
X416767Y497333D01*
X416600Y496667D01*
X416767Y496000D01*
X417100Y495500D01*
X417600Y495167D01*
X418183Y495000D01*
X418767Y495083D01*
X419267Y495333D01*
X419600Y495667D01*
G01X421617Y498333D02*
X422617Y495000D01*
X423700Y498333D01*
X424783Y495000D01*
X425783Y498333D01*
G01X430800Y495000D02*
Y498333D01*
G01Y497750D02*
X430467Y498083D01*
X429967Y498250D01*
X429383Y498333D01*
X428800Y498167D01*
X428300Y497833D01*
X427967Y497333D01*
X427800Y496667D01*
X427967Y496000D01*
X428300Y495500D01*
X428800Y495167D01*
X429383Y495000D01*
X429967Y495083D01*
X430467Y495333D01*
X430800Y495667D01*
G01X433150Y493500D02*
X433650Y493333D01*
X434317Y493500D01*
X434733Y493833D01*
X435067Y494250D01*
X435567Y495583D01*
X436650Y498333D01*
G01X433983D02*
X435567Y495583D01*
G01X440917Y493333D02*
X441750Y494167D01*
X442167Y495000D01*
Y498333D01*
X441750Y499167D01*
X440917Y500000D01*
G01X270583Y525000D02*
Y530000D01*
X274417Y525000D01*
Y530000D01*
G01X276433Y525000D02*
Y530000D01*
X278433D01*
X279100Y529750D01*
X279600Y529167D01*
X279767Y528500D01*
X279600Y527833D01*
X279183Y527333D01*
X278433Y527083D01*
X276433D01*
G01X283700Y530000D02*
Y525000D01*
G01X281783Y530000D02*
X285617D01*
G01X287550Y525000D02*
Y530000D01*
G01X291050D02*
Y525000D01*
G01Y527500D02*
X287550D01*
G01X298750Y525667D02*
X299417Y525250D01*
X300167Y525000D01*
X300833D01*
X301500Y525250D01*
X302000Y525667D01*
X302250Y526250D01*
X302083Y526833D01*
X301667Y527333D01*
X300917Y527667D01*
X299917Y527833D01*
X299333Y528167D01*
X299083Y528750D01*
X299250Y529333D01*
X299667Y529750D01*
X300250Y530000D01*
X300833D01*
X301417Y529833D01*
X301917Y529417D01*
G01X306100Y528333D02*
Y525000D01*
G01Y529667D02*
X305933Y529750D01*
Y529917D01*
X306100Y530000D01*
X306267Y529917D01*
Y529750D01*
X306100Y529667D01*
G01X310450Y528333D02*
X312950D01*
X310450Y525000D01*
X312950D01*
G01X316050Y527250D02*
X318717D01*
X318467Y527833D01*
X318050Y528167D01*
X317467Y528333D01*
X316883Y528250D01*
X316383Y528000D01*
X316050Y527417D01*
X315883Y526917D01*
Y526417D01*
X316050Y525917D01*
X316467Y525417D01*
X316967Y525083D01*
X317550Y525000D01*
X318133Y525167D01*
X318717Y525667D01*
G01X324567Y525000D02*
X321233Y526667D01*
X324567Y528333D01*
G01X332267Y525750D02*
X332767Y525333D01*
X333350Y525083D01*
X334100Y525000D01*
X334850Y525167D01*
X335433Y525500D01*
X335850Y526083D01*
X335933Y526750D01*
X335767Y527417D01*
X335350Y527833D01*
X334767Y528167D01*
X334183Y528250D01*
X333600Y528167D01*
X332850Y527833D01*
X333100Y530000D01*
X335350D01*
G01X337200Y525000D02*
Y528333D01*
G01Y527417D02*
X337450Y527833D01*
X337867Y528167D01*
X338450Y528333D01*
X339033Y528167D01*
X339450Y527833D01*
X339700Y527417D01*
Y525000D01*
G01Y527417D02*
X339950Y527833D01*
X340367Y528167D01*
X340950Y528333D01*
X341533Y528167D01*
X341950Y527833D01*
X342200Y527333D01*
Y525000D01*
G01X342800D02*
Y528333D01*
G01Y527417D02*
X343050Y527833D01*
X343467Y528167D01*
X344050Y528333D01*
X344633Y528167D01*
X345050Y527833D01*
X345300Y527417D01*
Y525000D01*
G01Y527417D02*
X345550Y527833D01*
X345967Y528167D01*
X346550Y528333D01*
X347133Y528167D01*
X347550Y527833D01*
X347800Y527333D01*
Y525000D01*
G01X356083Y523333D02*
X355250Y524167D01*
X354833Y525000D01*
Y528333D01*
X355250Y529167D01*
X356083Y530000D01*
G01X360683Y525000D02*
Y528333D01*
G01Y527500D02*
X361017Y527917D01*
X361517Y528250D01*
X362183Y528333D01*
X362767Y528250D01*
X363267Y527917D01*
X363517Y527333D01*
Y525000D01*
G01X367700D02*
X367200Y525083D01*
X366700Y525417D01*
X366367Y526000D01*
X366200Y526667D01*
X366367Y527333D01*
X366700Y527917D01*
X367200Y528250D01*
X367700Y528333D01*
X368200Y528250D01*
X368700Y527917D01*
X369033Y527333D01*
X369117Y526667D01*
X369033Y526000D01*
X368700Y525417D01*
X368200Y525083D01*
X367700Y525000D01*
G01X373300Y530000D02*
Y525000D01*
G01X372133Y528333D02*
X374467D01*
G01X384500Y525000D02*
X384000Y525083D01*
X383500Y525417D01*
X383167Y526000D01*
X383000Y526667D01*
X383167Y527333D01*
X383500Y527917D01*
X384000Y528250D01*
X384500Y528333D01*
X385000Y528250D01*
X385500Y527917D01*
X385833Y527333D01*
X385917Y526667D01*
X385833Y526000D01*
X385500Y525417D01*
X385000Y525083D01*
X384500Y525000D01*
G01X388683D02*
Y528333D01*
G01Y527500D02*
X389017Y527917D01*
X389517Y528250D01*
X390183Y528333D01*
X390767Y528250D01*
X391267Y527917D01*
X391517Y527333D01*
Y525000D01*
G01X399800D02*
Y530000D01*
G01Y527500D02*
X400217Y528000D01*
X400717Y528250D01*
X401217Y528333D01*
X401967Y528167D01*
X402467Y527833D01*
X402800Y527250D01*
Y526583D01*
X402633Y525917D01*
X402300Y525417D01*
X401717Y525083D01*
X401217Y525000D01*
X400717Y525083D01*
X400217Y525333D01*
X399800Y525750D01*
G01X405733Y525000D02*
Y528333D01*
G01Y527667D02*
X406150Y528000D01*
X406567Y528250D01*
X407150Y528333D01*
X407567Y528250D01*
X408067Y528000D01*
G01X411250Y527250D02*
X413917D01*
X413667Y527833D01*
X413250Y528167D01*
X412667Y528333D01*
X412083Y528250D01*
X411583Y528000D01*
X411250Y527417D01*
X411083Y526917D01*
Y526417D01*
X411250Y525917D01*
X411667Y525417D01*
X412167Y525083D01*
X412750Y525000D01*
X413333Y525167D01*
X413917Y525667D01*
G01X419600Y525000D02*
Y528333D01*
G01Y527750D02*
X419267Y528083D01*
X418767Y528250D01*
X418183Y528333D01*
X417600Y528167D01*
X417100Y527833D01*
X416767Y527333D01*
X416600Y526667D01*
X416767Y526000D01*
X417100Y525500D01*
X417600Y525167D01*
X418183Y525000D01*
X418767Y525083D01*
X419267Y525333D01*
X419600Y525667D01*
G01X422283Y525000D02*
Y530000D01*
G01X424950Y528333D02*
X422283Y526417D01*
G01X423367Y527167D02*
X425117Y525000D01*
G01X430800D02*
Y528333D01*
G01Y527750D02*
X430467Y528083D01*
X429967Y528250D01*
X429383Y528333D01*
X428800Y528167D01*
X428300Y527833D01*
X427967Y527333D01*
X427800Y526667D01*
X427967Y526000D01*
X428300Y525500D01*
X428800Y525167D01*
X429383Y525000D01*
X429967Y525083D01*
X430467Y525333D01*
X430800Y525667D01*
G01X432817Y528333D02*
X433817Y525000D01*
X434900Y528333D01*
X435983Y525000D01*
X436983Y528333D01*
G01X442000Y525000D02*
Y528333D01*
G01Y527750D02*
X441667Y528083D01*
X441167Y528250D01*
X440583Y528333D01*
X440000Y528167D01*
X439500Y527833D01*
X439167Y527333D01*
X439000Y526667D01*
X439167Y526000D01*
X439500Y525500D01*
X440000Y525167D01*
X440583Y525000D01*
X441167Y525083D01*
X441667Y525333D01*
X442000Y525667D01*
G01X444350Y523500D02*
X444850Y523333D01*
X445517Y523500D01*
X445933Y523833D01*
X446267Y524250D01*
X446767Y525583D01*
X447850Y528333D01*
G01X445183D02*
X446767Y525583D01*
G01X452117Y523333D02*
X452950Y524167D01*
X453367Y525000D01*
Y528333D01*
X452950Y529167D01*
X452117Y530000D01*
G01X270667Y546500D02*
Y542917D01*
X271000Y542167D01*
X271667Y541667D01*
X272500Y541500D01*
X273333Y541667D01*
X274000Y542167D01*
X274333Y542917D01*
Y546500D01*
G01X276683Y541500D02*
Y544833D01*
G01Y544000D02*
X277017Y544417D01*
X277517Y544750D01*
X278183Y544833D01*
X278767Y544750D01*
X279267Y544417D01*
X279517Y543833D01*
Y541500D01*
G01X282617Y543167D02*
X284783D01*
G01X287800Y539833D02*
Y544833D01*
G01Y544083D02*
X288217Y544500D01*
X288633Y544750D01*
X289300Y544833D01*
X289883Y544750D01*
X290467Y544333D01*
X290717Y543750D01*
X290800Y543167D01*
X290717Y542583D01*
X290467Y542000D01*
X289967Y541667D01*
X289300Y541500D01*
X288717Y541583D01*
X288133Y541833D01*
X287800Y542167D01*
G01X294900Y541500D02*
Y546500D01*
G01X299083Y544833D02*
Y542500D01*
X299417Y541917D01*
X299917Y541583D01*
X300500Y541500D01*
X301083Y541583D01*
X301583Y541917D01*
X301917Y542500D01*
G01Y541500D02*
Y544833D01*
G01X304933Y540250D02*
X305517Y539917D01*
X306183Y539833D01*
X306767Y539917D01*
X307267Y540333D01*
X307600Y540917D01*
Y544833D01*
G01Y544167D02*
X307267Y544500D01*
X306767Y544750D01*
X306183Y544833D01*
X305517Y544667D01*
X305100Y544333D01*
X304767Y543750D01*
X304600Y543167D01*
X304683Y542667D01*
X305017Y542083D01*
X305517Y541667D01*
X306183Y541500D01*
X306683Y541583D01*
X307267Y541917D01*
X307600Y542250D01*
G01X310533Y540250D02*
X311117Y539917D01*
X311783Y539833D01*
X312367Y539917D01*
X312867Y540333D01*
X313200Y540917D01*
Y544833D01*
G01Y544167D02*
X312867Y544500D01*
X312367Y544750D01*
X311783Y544833D01*
X311117Y544667D01*
X310700Y544333D01*
X310367Y543750D01*
X310200Y543167D01*
X310283Y542667D01*
X310617Y542083D01*
X311117Y541667D01*
X311783Y541500D01*
X312283Y541583D01*
X312867Y541917D01*
X313200Y542250D01*
G01X316050Y543750D02*
X318717D01*
X318467Y544333D01*
X318050Y544667D01*
X317467Y544833D01*
X316883Y544750D01*
X316383Y544500D01*
X316050Y543917D01*
X315883Y543417D01*
Y542917D01*
X316050Y542417D01*
X316467Y541917D01*
X316967Y541583D01*
X317550Y541500D01*
X318133Y541667D01*
X318717Y542167D01*
G01X324400Y546500D02*
Y541500D01*
G01Y542250D02*
X324067Y541833D01*
X323567Y541583D01*
X322983Y541500D01*
X322317Y541667D01*
X321817Y542083D01*
X321483Y542583D01*
X321400Y543167D01*
X321483Y543750D01*
X321817Y544250D01*
X322317Y544667D01*
X322983Y544833D01*
X323567Y544750D01*
X323983Y544583D01*
X324400Y544250D01*
G01X332433Y541500D02*
Y546500D01*
X334433D01*
X335100Y546250D01*
X335600Y545667D01*
X335767Y545000D01*
X335600Y544333D01*
X335183Y543833D01*
X334433Y543583D01*
X332433D01*
G01X339700Y546500D02*
Y541500D01*
G01X337783Y546500D02*
X341617D01*
G01X343550Y541500D02*
Y546500D01*
G01X347050D02*
Y541500D01*
G01Y544000D02*
X343550D01*
G01X356083Y539833D02*
X355250Y540667D01*
X354833Y541500D01*
Y544833D01*
X355250Y545667D01*
X356083Y546500D01*
G01X360350Y541500D02*
Y546500D01*
G01X363850D02*
Y541500D01*
G01Y544000D02*
X360350D01*
G01X367700Y541500D02*
X367200Y541583D01*
X366700Y541917D01*
X366367Y542500D01*
X366200Y543167D01*
X366367Y543833D01*
X366700Y544417D01*
X367200Y544750D01*
X367700Y544833D01*
X368200Y544750D01*
X368700Y544417D01*
X369033Y543833D01*
X369117Y543167D01*
X369033Y542500D01*
X368700Y541917D01*
X368200Y541583D01*
X367700Y541500D01*
G01X373300D02*
Y546500D01*
G01X377650Y543750D02*
X380317D01*
X380067Y544333D01*
X379650Y544667D01*
X379067Y544833D01*
X378483Y544750D01*
X377983Y544500D01*
X377650Y543917D01*
X377483Y543417D01*
Y542917D01*
X377650Y542417D01*
X378067Y541917D01*
X378567Y541583D01*
X379150Y541500D01*
X379733Y541667D01*
X380317Y542167D01*
G01X388350D02*
X389017Y541750D01*
X389767Y541500D01*
X390433D01*
X391100Y541750D01*
X391600Y542167D01*
X391850Y542750D01*
X391683Y543333D01*
X391267Y543833D01*
X390517Y544167D01*
X389517Y544333D01*
X388933Y544667D01*
X388683Y545250D01*
X388850Y545833D01*
X389267Y546250D01*
X389850Y546500D01*
X390433D01*
X391017Y546333D01*
X391517Y545917D01*
G01X395700Y544833D02*
Y541500D01*
G01Y546167D02*
X395533Y546250D01*
Y546417D01*
X395700Y546500D01*
X395867Y546417D01*
Y546250D01*
X395700Y546167D01*
G01X400050Y544833D02*
X402550D01*
X400050Y541500D01*
X402550D01*
G01X405650Y543750D02*
X408317D01*
X408067Y544333D01*
X407650Y544667D01*
X407067Y544833D01*
X406483Y544750D01*
X405983Y544500D01*
X405650Y543917D01*
X405483Y543417D01*
Y542917D01*
X405650Y542417D01*
X406067Y541917D01*
X406567Y541583D01*
X407150Y541500D01*
X407733Y541667D01*
X408317Y542167D01*
G01X414167Y541500D02*
X410833Y543167D01*
X414167Y544833D01*
G01X418100Y541500D02*
Y546500D01*
X417100Y545500D01*
G01Y541500D02*
X419100D01*
G01X422283Y542083D02*
X422867Y541667D01*
X423533Y541500D01*
X424200Y541667D01*
X424783Y542167D01*
X425200Y542917D01*
X425367Y543667D01*
Y544583D01*
X425200Y545333D01*
X424783Y546000D01*
X424283Y546333D01*
X423700Y546500D01*
X423033Y546333D01*
X422533Y546000D01*
X422200Y545500D01*
X422033Y544833D01*
X422200Y544250D01*
X422617Y543667D01*
X423117Y543333D01*
X423700Y543250D01*
X424367Y543417D01*
X424867Y543833D01*
X425367Y544583D01*
G01X429133Y541500D02*
X429300Y542583D01*
X429550Y543500D01*
X429883Y544333D01*
X430300Y545250D01*
X430967Y546500D01*
X427633D01*
G01X432400Y541500D02*
Y544833D01*
G01Y543917D02*
X432650Y544333D01*
X433067Y544667D01*
X433650Y544833D01*
X434233Y544667D01*
X434650Y544333D01*
X434900Y543917D01*
Y541500D01*
G01Y543917D02*
X435150Y544333D01*
X435567Y544667D01*
X436150Y544833D01*
X436733Y544667D01*
X437150Y544333D01*
X437400Y543833D01*
Y541500D01*
G01X440500Y544833D02*
Y541500D01*
G01Y546167D02*
X440333Y546250D01*
Y546417D01*
X440500Y546500D01*
X440667Y546417D01*
Y546250D01*
X440500Y546167D01*
G01X446100Y541500D02*
Y546500D01*
G01X455217Y544833D02*
X456217Y541500D01*
X457300Y544833D01*
X458383Y541500D01*
X459383Y544833D01*
G01X462900D02*
Y541500D01*
G01Y546167D02*
X462733Y546250D01*
Y546417D01*
X462900Y546500D01*
X463067Y546417D01*
Y546250D01*
X462900Y546167D01*
G01X468500Y546500D02*
Y541500D01*
G01X467333Y544833D02*
X469667D01*
G01X472683Y541500D02*
Y546500D01*
G01Y544083D02*
X473100Y544500D01*
X473517Y544750D01*
X474183Y544833D01*
X474683Y544750D01*
X475267Y544417D01*
X475517Y543917D01*
Y541500D01*
G01X483550D02*
Y546500D01*
G01X487050D02*
Y541500D01*
G01Y544000D02*
X483550D01*
G01X488817Y541500D02*
X490900Y546500D01*
X492983Y541500D01*
G01X492233Y543250D02*
X489567D01*
G01X494750Y542167D02*
X495417Y541750D01*
X496167Y541500D01*
X496833D01*
X497500Y541750D01*
X498000Y542167D01*
X498250Y542750D01*
X498083Y543333D01*
X497667Y543833D01*
X496917Y544167D01*
X495917Y544333D01*
X495333Y544667D01*
X495083Y545250D01*
X495250Y545833D01*
X495667Y546250D01*
X496250Y546500D01*
X496833D01*
X497417Y546333D01*
X497917Y545917D01*
G01X500433Y546500D02*
Y541500D01*
X503767D01*
G01X511800Y539833D02*
Y544833D01*
G01Y544083D02*
X512217Y544500D01*
X512633Y544750D01*
X513300Y544833D01*
X513883Y544750D01*
X514467Y544333D01*
X514717Y543750D01*
X514800Y543167D01*
X514717Y542583D01*
X514467Y542000D01*
X513967Y541667D01*
X513300Y541500D01*
X512717Y541583D01*
X512133Y541833D01*
X511800Y542167D01*
G01X517733Y541500D02*
Y544833D01*
G01Y544167D02*
X518150Y544500D01*
X518567Y544750D01*
X519150Y544833D01*
X519567Y544750D01*
X520067Y544500D01*
G01X524500Y541500D02*
X524000Y541583D01*
X523500Y541917D01*
X523167Y542500D01*
X523000Y543167D01*
X523167Y543833D01*
X523500Y544417D01*
X524000Y544750D01*
X524500Y544833D01*
X525000Y544750D01*
X525500Y544417D01*
X525833Y543833D01*
X525917Y543167D01*
X525833Y542500D01*
X525500Y541917D01*
X525000Y541583D01*
X524500Y541500D01*
G01X531600Y546500D02*
Y541500D01*
G01Y542250D02*
X531267Y541833D01*
X530767Y541583D01*
X530183Y541500D01*
X529517Y541667D01*
X529017Y542083D01*
X528683Y542583D01*
X528600Y543167D01*
X528683Y543750D01*
X529017Y544250D01*
X529517Y544667D01*
X530183Y544833D01*
X530767Y544750D01*
X531183Y544583D01*
X531600Y544250D01*
G01X534283Y544833D02*
Y542500D01*
X534617Y541917D01*
X535117Y541583D01*
X535700Y541500D01*
X536283Y541583D01*
X536783Y541917D01*
X537117Y542500D01*
G01Y541500D02*
Y544833D01*
G01X542633Y544417D02*
X542050Y544750D01*
X541550Y544833D01*
X540883Y544667D01*
X540383Y544333D01*
X540050Y543750D01*
X539967Y543167D01*
X540050Y542583D01*
X540383Y542083D01*
X540883Y541667D01*
X541550Y541500D01*
X542133Y541667D01*
X542633Y542000D01*
G01X546900Y546500D02*
Y541500D01*
G01X545733Y544833D02*
X548067D01*
G01X551250Y542083D02*
X551667Y541750D01*
X552250Y541500D01*
X552750D01*
X553250Y541667D01*
X553583Y541917D01*
X553750Y542250D01*
X553667Y542750D01*
X553333Y543000D01*
X551833Y543500D01*
X551500Y544083D01*
X551667Y544500D01*
X552000Y544750D01*
X552500Y544833D01*
X553000Y544750D01*
X553500Y544500D01*
G01X558517Y539833D02*
X559350Y540667D01*
X559767Y541500D01*
Y544833D01*
X559350Y545667D01*
X558517Y546500D01*
G01X270667Y561500D02*
Y557917D01*
X271000Y557167D01*
X271667Y556667D01*
X272500Y556500D01*
X273333Y556667D01*
X274000Y557167D01*
X274333Y557917D01*
Y561500D01*
G01X276683Y556500D02*
Y559833D01*
G01Y559000D02*
X277017Y559417D01*
X277517Y559750D01*
X278183Y559833D01*
X278767Y559750D01*
X279267Y559417D01*
X279517Y558833D01*
Y556500D01*
G01X282617Y558167D02*
X284783D01*
G01X287800Y554833D02*
Y559833D01*
G01Y559083D02*
X288217Y559500D01*
X288633Y559750D01*
X289300Y559833D01*
X289883Y559750D01*
X290467Y559333D01*
X290717Y558750D01*
X290800Y558167D01*
X290717Y557583D01*
X290467Y557000D01*
X289967Y556667D01*
X289300Y556500D01*
X288717Y556583D01*
X288133Y556833D01*
X287800Y557167D01*
G01X294900Y556500D02*
Y561500D01*
G01X299083Y559833D02*
Y557500D01*
X299417Y556917D01*
X299917Y556583D01*
X300500Y556500D01*
X301083Y556583D01*
X301583Y556917D01*
X301917Y557500D01*
G01Y556500D02*
Y559833D01*
G01X304933Y555250D02*
X305517Y554917D01*
X306183Y554833D01*
X306767Y554917D01*
X307267Y555333D01*
X307600Y555917D01*
Y559833D01*
G01Y559167D02*
X307267Y559500D01*
X306767Y559750D01*
X306183Y559833D01*
X305517Y559667D01*
X305100Y559333D01*
X304767Y558750D01*
X304600Y558167D01*
X304683Y557667D01*
X305017Y557083D01*
X305517Y556667D01*
X306183Y556500D01*
X306683Y556583D01*
X307267Y556917D01*
X307600Y557250D01*
G01X310533Y555250D02*
X311117Y554917D01*
X311783Y554833D01*
X312367Y554917D01*
X312867Y555333D01*
X313200Y555917D01*
Y559833D01*
G01Y559167D02*
X312867Y559500D01*
X312367Y559750D01*
X311783Y559833D01*
X311117Y559667D01*
X310700Y559333D01*
X310367Y558750D01*
X310200Y558167D01*
X310283Y557667D01*
X310617Y557083D01*
X311117Y556667D01*
X311783Y556500D01*
X312283Y556583D01*
X312867Y556917D01*
X313200Y557250D01*
G01X316050Y558750D02*
X318717D01*
X318467Y559333D01*
X318050Y559667D01*
X317467Y559833D01*
X316883Y559750D01*
X316383Y559500D01*
X316050Y558917D01*
X315883Y558417D01*
Y557917D01*
X316050Y557417D01*
X316467Y556917D01*
X316967Y556583D01*
X317550Y556500D01*
X318133Y556667D01*
X318717Y557167D01*
G01X324400Y561500D02*
Y556500D01*
G01Y557250D02*
X324067Y556833D01*
X323567Y556583D01*
X322983Y556500D01*
X322317Y556667D01*
X321817Y557083D01*
X321483Y557583D01*
X321400Y558167D01*
X321483Y558750D01*
X321817Y559250D01*
X322317Y559667D01*
X322983Y559833D01*
X323567Y559750D01*
X323983Y559583D01*
X324400Y559250D01*
G01X332433Y556500D02*
Y561500D01*
X334433D01*
X335100Y561250D01*
X335600Y560667D01*
X335767Y560000D01*
X335600Y559333D01*
X335183Y558833D01*
X334433Y558583D01*
X332433D01*
G01X339700Y561500D02*
Y556500D01*
G01X337783Y561500D02*
X341617D01*
G01X343550Y556500D02*
Y561500D01*
G01X347050D02*
Y556500D01*
G01Y559000D02*
X343550D01*
G01X356083Y554833D02*
X355250Y555667D01*
X354833Y556500D01*
Y559833D01*
X355250Y560667D01*
X356083Y561500D01*
G01X360350Y556500D02*
Y561500D01*
G01X363850D02*
Y556500D01*
G01Y559000D02*
X360350D01*
G01X367700Y556500D02*
X367200Y556583D01*
X366700Y556917D01*
X366367Y557500D01*
X366200Y558167D01*
X366367Y558833D01*
X366700Y559417D01*
X367200Y559750D01*
X367700Y559833D01*
X368200Y559750D01*
X368700Y559417D01*
X369033Y558833D01*
X369117Y558167D01*
X369033Y557500D01*
X368700Y556917D01*
X368200Y556583D01*
X367700Y556500D01*
G01X373300D02*
Y561500D01*
G01X377650Y558750D02*
X380317D01*
X380067Y559333D01*
X379650Y559667D01*
X379067Y559833D01*
X378483Y559750D01*
X377983Y559500D01*
X377650Y558917D01*
X377483Y558417D01*
Y557917D01*
X377650Y557417D01*
X378067Y556917D01*
X378567Y556583D01*
X379150Y556500D01*
X379733Y556667D01*
X380317Y557167D01*
G01X388350D02*
X389017Y556750D01*
X389767Y556500D01*
X390433D01*
X391100Y556750D01*
X391600Y557167D01*
X391850Y557750D01*
X391683Y558333D01*
X391267Y558833D01*
X390517Y559167D01*
X389517Y559333D01*
X388933Y559667D01*
X388683Y560250D01*
X388850Y560833D01*
X389267Y561250D01*
X389850Y561500D01*
X390433D01*
X391017Y561333D01*
X391517Y560917D01*
G01X395700Y559833D02*
Y556500D01*
G01Y561167D02*
X395533Y561250D01*
Y561417D01*
X395700Y561500D01*
X395867Y561417D01*
Y561250D01*
X395700Y561167D01*
G01X400050Y559833D02*
X402550D01*
X400050Y556500D01*
X402550D01*
G01X405650Y558750D02*
X408317D01*
X408067Y559333D01*
X407650Y559667D01*
X407067Y559833D01*
X406483Y559750D01*
X405983Y559500D01*
X405650Y558917D01*
X405483Y558417D01*
Y557917D01*
X405650Y557417D01*
X406067Y556917D01*
X406567Y556583D01*
X407150Y556500D01*
X407733Y556667D01*
X408317Y557167D01*
G01X414167Y556500D02*
X410833Y558167D01*
X414167Y559833D01*
G01X418100Y556500D02*
Y561500D01*
X417100Y560500D01*
G01Y556500D02*
X419100D01*
G01X422283Y557083D02*
X422867Y556667D01*
X423533Y556500D01*
X424200Y556667D01*
X424783Y557167D01*
X425200Y557917D01*
X425367Y558667D01*
Y559583D01*
X425200Y560333D01*
X424783Y561000D01*
X424283Y561333D01*
X423700Y561500D01*
X423033Y561333D01*
X422533Y561000D01*
X422200Y560500D01*
X422033Y559833D01*
X422200Y559250D01*
X422617Y558667D01*
X423117Y558333D01*
X423700Y558250D01*
X424367Y558417D01*
X424867Y558833D01*
X425367Y559583D01*
G01X429133Y556500D02*
X429300Y557583D01*
X429550Y558500D01*
X429883Y559333D01*
X430300Y560250D01*
X430967Y561500D01*
X427633D01*
G01X432400Y556500D02*
Y559833D01*
G01Y558917D02*
X432650Y559333D01*
X433067Y559667D01*
X433650Y559833D01*
X434233Y559667D01*
X434650Y559333D01*
X434900Y558917D01*
Y556500D01*
G01Y558917D02*
X435150Y559333D01*
X435567Y559667D01*
X436150Y559833D01*
X436733Y559667D01*
X437150Y559333D01*
X437400Y558833D01*
Y556500D01*
G01X440500Y559833D02*
Y556500D01*
G01Y561167D02*
X440333Y561250D01*
Y561417D01*
X440500Y561500D01*
X440667Y561417D01*
Y561250D01*
X440500Y561167D01*
G01X446100Y556500D02*
Y561500D01*
G01X455217Y559833D02*
X456217Y556500D01*
X457300Y559833D01*
X458383Y556500D01*
X459383Y559833D01*
G01X462900D02*
Y556500D01*
G01Y561167D02*
X462733Y561250D01*
Y561417D01*
X462900Y561500D01*
X463067Y561417D01*
Y561250D01*
X462900Y561167D01*
G01X468500Y561500D02*
Y556500D01*
G01X467333Y559833D02*
X469667D01*
G01X472683Y556500D02*
Y561500D01*
G01Y559083D02*
X473100Y559500D01*
X473517Y559750D01*
X474183Y559833D01*
X474683Y559750D01*
X475267Y559417D01*
X475517Y558917D01*
Y556500D01*
G01X483883D02*
Y559833D01*
G01Y559000D02*
X484217Y559417D01*
X484717Y559750D01*
X485383Y559833D01*
X485967Y559750D01*
X486467Y559417D01*
X486717Y558833D01*
Y556500D01*
G01X490900D02*
X490400Y556583D01*
X489900Y556917D01*
X489567Y557500D01*
X489400Y558167D01*
X489567Y558833D01*
X489900Y559417D01*
X490400Y559750D01*
X490900Y559833D01*
X491400Y559750D01*
X491900Y559417D01*
X492233Y558833D01*
X492317Y558167D01*
X492233Y557500D01*
X491900Y556917D01*
X491400Y556583D01*
X490900Y556500D01*
G01X495083D02*
Y559833D01*
G01Y559000D02*
X495417Y559417D01*
X495917Y559750D01*
X496583Y559833D01*
X497167Y559750D01*
X497667Y559417D01*
X497917Y558833D01*
Y556500D01*
G01X501017Y558167D02*
X503183D01*
G01X505950Y556500D02*
Y561500D01*
G01X509450D02*
Y556500D01*
G01Y559000D02*
X505950D01*
G01X511217Y556500D02*
X513300Y561500D01*
X515383Y556500D01*
G01X514633Y558250D02*
X511967D01*
G01X517150Y557167D02*
X517817Y556750D01*
X518567Y556500D01*
X519233D01*
X519900Y556750D01*
X520400Y557167D01*
X520650Y557750D01*
X520483Y558333D01*
X520067Y558833D01*
X519317Y559167D01*
X518317Y559333D01*
X517733Y559667D01*
X517483Y560250D01*
X517650Y560833D01*
X518067Y561250D01*
X518650Y561500D01*
X519233D01*
X519817Y561333D01*
X520317Y560917D01*
G01X522833Y561500D02*
Y556500D01*
X526167D01*
G01X534200Y554833D02*
Y559833D01*
G01Y559083D02*
X534617Y559500D01*
X535033Y559750D01*
X535700Y559833D01*
X536283Y559750D01*
X536867Y559333D01*
X537117Y558750D01*
X537200Y558167D01*
X537117Y557583D01*
X536867Y557000D01*
X536367Y556667D01*
X535700Y556500D01*
X535117Y556583D01*
X534533Y556833D01*
X534200Y557167D01*
G01X540133Y556500D02*
Y559833D01*
G01Y559167D02*
X540550Y559500D01*
X540967Y559750D01*
X541550Y559833D01*
X541967Y559750D01*
X542467Y559500D01*
G01X546900Y556500D02*
X546400Y556583D01*
X545900Y556917D01*
X545567Y557500D01*
X545400Y558167D01*
X545567Y558833D01*
X545900Y559417D01*
X546400Y559750D01*
X546900Y559833D01*
X547400Y559750D01*
X547900Y559417D01*
X548233Y558833D01*
X548317Y558167D01*
X548233Y557500D01*
X547900Y556917D01*
X547400Y556583D01*
X546900Y556500D01*
G01X554000Y561500D02*
Y556500D01*
G01Y557250D02*
X553667Y556833D01*
X553167Y556583D01*
X552583Y556500D01*
X551917Y556667D01*
X551417Y557083D01*
X551083Y557583D01*
X551000Y558167D01*
X551083Y558750D01*
X551417Y559250D01*
X551917Y559667D01*
X552583Y559833D01*
X553167Y559750D01*
X553583Y559583D01*
X554000Y559250D01*
G01X556683Y559833D02*
Y557500D01*
X557017Y556917D01*
X557517Y556583D01*
X558100Y556500D01*
X558683Y556583D01*
X559183Y556917D01*
X559517Y557500D01*
G01Y556500D02*
Y559833D01*
G01X565033Y559417D02*
X564450Y559750D01*
X563950Y559833D01*
X563283Y559667D01*
X562783Y559333D01*
X562450Y558750D01*
X562367Y558167D01*
X562450Y557583D01*
X562783Y557083D01*
X563283Y556667D01*
X563950Y556500D01*
X564533Y556667D01*
X565033Y557000D01*
G01X569300Y561500D02*
Y556500D01*
G01X568133Y559833D02*
X570467D01*
G01X573650Y557083D02*
X574067Y556750D01*
X574650Y556500D01*
X575150D01*
X575650Y556667D01*
X575983Y556917D01*
X576150Y557250D01*
X576067Y557750D01*
X575733Y558000D01*
X574233Y558500D01*
X573900Y559083D01*
X574067Y559500D01*
X574400Y559750D01*
X574900Y559833D01*
X575400Y559750D01*
X575900Y559500D01*
G01X580917Y554833D02*
X581750Y555667D01*
X582167Y556500D01*
Y559833D01*
X581750Y560667D01*
X580917Y561500D01*
G01X262500Y490500D02*
X694500D01*
G01X262500Y505500D02*
X694500D01*
G01X262500Y520500D02*
X694500D01*
G01X262500Y535500D02*
X694500D01*
G01X262500Y550500D02*
X694500D01*
G01X270417Y600000D02*
X272500Y605000D01*
X274583Y600000D01*
G01X273833Y601750D02*
X271167D01*
G01X276683Y600000D02*
Y603333D01*
G01Y602500D02*
X277017Y602917D01*
X277517Y603250D01*
X278183Y603333D01*
X278767Y603250D01*
X279267Y602917D01*
X279517Y602333D01*
Y600000D01*
G01X281950Y598500D02*
X282450Y598333D01*
X283117Y598500D01*
X283533Y598833D01*
X283867Y599250D01*
X284367Y600583D01*
X285450Y603333D01*
G01X282783D02*
X284367Y600583D01*
G01X293483Y600000D02*
Y605000D01*
G01Y602583D02*
X293900Y603000D01*
X294317Y603250D01*
X294983Y603333D01*
X295483Y603250D01*
X296067Y602917D01*
X296317Y602417D01*
Y600000D01*
G01X300500D02*
X300000Y600083D01*
X299500Y600417D01*
X299167Y601000D01*
X299000Y601667D01*
X299167Y602333D01*
X299500Y602917D01*
X300000Y603250D01*
X300500Y603333D01*
X301000Y603250D01*
X301500Y602917D01*
X301833Y602333D01*
X301917Y601667D01*
X301833Y601000D01*
X301500Y600417D01*
X301000Y600083D01*
X300500Y600000D01*
G01X306100D02*
Y605000D01*
G01X310450Y602250D02*
X313117D01*
X312867Y602833D01*
X312450Y603167D01*
X311867Y603333D01*
X311283Y603250D01*
X310783Y603000D01*
X310450Y602417D01*
X310283Y601917D01*
Y601417D01*
X310450Y600917D01*
X310867Y600417D01*
X311367Y600083D01*
X311950Y600000D01*
X312533Y600167D01*
X313117Y600667D01*
G01X322900Y605000D02*
Y600000D01*
G01X321733Y603333D02*
X324067D01*
G01X328500Y600000D02*
X328000Y600083D01*
X327500Y600417D01*
X327167Y601000D01*
X327000Y601667D01*
X327167Y602333D01*
X327500Y602917D01*
X328000Y603250D01*
X328500Y603333D01*
X329000Y603250D01*
X329500Y602917D01*
X329833Y602333D01*
X329917Y601667D01*
X329833Y601000D01*
X329500Y600417D01*
X329000Y600083D01*
X328500Y600000D01*
G01X338283D02*
Y605000D01*
G01Y602583D02*
X338700Y603000D01*
X339117Y603250D01*
X339783Y603333D01*
X340283Y603250D01*
X340867Y602917D01*
X341117Y602417D01*
Y600000D01*
G01X345300D02*
X344800Y600083D01*
X344300Y600417D01*
X343967Y601000D01*
X343800Y601667D01*
X343967Y602333D01*
X344300Y602917D01*
X344800Y603250D01*
X345300Y603333D01*
X345800Y603250D01*
X346300Y602917D01*
X346633Y602333D01*
X346717Y601667D01*
X346633Y601000D01*
X346300Y600417D01*
X345800Y600083D01*
X345300Y600000D01*
G01X350900D02*
Y605000D01*
G01X355250Y602250D02*
X357917D01*
X357667Y602833D01*
X357250Y603167D01*
X356667Y603333D01*
X356083Y603250D01*
X355583Y603000D01*
X355250Y602417D01*
X355083Y601917D01*
Y601417D01*
X355250Y600917D01*
X355667Y600417D01*
X356167Y600083D01*
X356750Y600000D01*
X357333Y600167D01*
X357917Y600667D01*
G01X270917Y615500D02*
X273000Y620500D01*
X275083Y615500D01*
G01X274333Y617250D02*
X271667D01*
G01X277183Y615500D02*
Y618833D01*
G01Y618000D02*
X277517Y618417D01*
X278017Y618750D01*
X278683Y618833D01*
X279267Y618750D01*
X279767Y618417D01*
X280017Y617833D01*
Y615500D01*
G01X284200Y620500D02*
Y615500D01*
G01X283033Y618833D02*
X285367D01*
G01X289800D02*
Y615500D01*
G01Y620167D02*
X289633Y620250D01*
Y620417D01*
X289800Y620500D01*
X289967Y620417D01*
Y620250D01*
X289800Y620167D01*
G01X294317Y617167D02*
X296483D01*
G01X299500Y613833D02*
Y618833D01*
G01Y618083D02*
X299917Y618500D01*
X300333Y618750D01*
X301000Y618833D01*
X301583Y618750D01*
X302167Y618333D01*
X302417Y617750D01*
X302500Y617167D01*
X302417Y616583D01*
X302167Y616000D01*
X301667Y615667D01*
X301000Y615500D01*
X300417Y615583D01*
X299833Y615833D01*
X299500Y616167D01*
G01X308100Y615500D02*
Y618833D01*
G01Y618250D02*
X307767Y618583D01*
X307267Y618750D01*
X306683Y618833D01*
X306100Y618667D01*
X305600Y618333D01*
X305267Y617833D01*
X305100Y617167D01*
X305267Y616500D01*
X305600Y616000D01*
X306100Y615667D01*
X306683Y615500D01*
X307267Y615583D01*
X307767Y615833D01*
X308100Y616167D01*
G01X313700Y620500D02*
Y615500D01*
G01Y616250D02*
X313367Y615833D01*
X312867Y615583D01*
X312283Y615500D01*
X311617Y615667D01*
X311117Y616083D01*
X310783Y616583D01*
X310700Y617167D01*
X310783Y617750D01*
X311117Y618250D01*
X311617Y618667D01*
X312283Y618833D01*
X312867Y618750D01*
X313283Y618583D01*
X313700Y618250D01*
G01X322150Y616083D02*
X322567Y615750D01*
X323150Y615500D01*
X323650D01*
X324150Y615667D01*
X324483Y615917D01*
X324650Y616250D01*
X324567Y616750D01*
X324233Y617000D01*
X322733Y617500D01*
X322400Y618083D01*
X322567Y618500D01*
X322900Y618750D01*
X323400Y618833D01*
X323900Y618750D01*
X324400Y618500D01*
G01X329000Y618833D02*
Y615500D01*
G01Y620167D02*
X328833Y620250D01*
Y620417D01*
X329000Y620500D01*
X329167Y620417D01*
Y620250D01*
X329000Y620167D01*
G01X333350Y618833D02*
X335850D01*
X333350Y615500D01*
X335850D01*
G01X338950Y617750D02*
X341617D01*
X341367Y618333D01*
X340950Y618667D01*
X340367Y618833D01*
X339783Y618750D01*
X339283Y618500D01*
X338950Y617917D01*
X338783Y617417D01*
Y616917D01*
X338950Y616417D01*
X339367Y615917D01*
X339867Y615583D01*
X340450Y615500D01*
X341033Y615667D01*
X341617Y616167D01*
G01X270417Y636333D02*
X271417Y633000D01*
X272500Y636333D01*
X273583Y633000D01*
X274583Y636333D01*
G01X278100D02*
Y633000D01*
G01Y637667D02*
X277933Y637750D01*
Y637917D01*
X278100Y638000D01*
X278267Y637917D01*
Y637750D01*
X278100Y637667D01*
G01X283700Y638000D02*
Y633000D01*
G01X282533Y636333D02*
X284867D01*
G01X287883Y633000D02*
Y638000D01*
G01Y635583D02*
X288300Y636000D01*
X288717Y636250D01*
X289383Y636333D01*
X289883Y636250D01*
X290467Y635917D01*
X290717Y635417D01*
Y633000D01*
G01X294900D02*
X294400Y633083D01*
X293900Y633417D01*
X293567Y634000D01*
X293400Y634667D01*
X293567Y635333D01*
X293900Y635917D01*
X294400Y636250D01*
X294900Y636333D01*
X295400Y636250D01*
X295900Y635917D01*
X296233Y635333D01*
X296317Y634667D01*
X296233Y634000D01*
X295900Y633417D01*
X295400Y633083D01*
X294900Y633000D01*
G01X299083Y636333D02*
Y634000D01*
X299417Y633417D01*
X299917Y633083D01*
X300500Y633000D01*
X301083Y633083D01*
X301583Y633417D01*
X301917Y634000D01*
G01Y633000D02*
Y636333D01*
G01X306100Y638000D02*
Y633000D01*
G01X304933Y636333D02*
X307267D01*
G01X318633Y635917D02*
X318050Y636250D01*
X317550Y636333D01*
X316883Y636167D01*
X316383Y635833D01*
X316050Y635250D01*
X315967Y634667D01*
X316050Y634083D01*
X316383Y633583D01*
X316883Y633167D01*
X317550Y633000D01*
X318133Y633167D01*
X318633Y633500D01*
G01X322900Y633000D02*
X322400Y633083D01*
X321900Y633417D01*
X321567Y634000D01*
X321400Y634667D01*
X321567Y635333D01*
X321900Y635917D01*
X322400Y636250D01*
X322900Y636333D01*
X323400Y636250D01*
X323900Y635917D01*
X324233Y635333D01*
X324317Y634667D01*
X324233Y634000D01*
X323900Y633417D01*
X323400Y633083D01*
X322900Y633000D01*
G01X327083D02*
Y636333D01*
G01Y635500D02*
X327417Y635917D01*
X327917Y636250D01*
X328583Y636333D01*
X329167Y636250D01*
X329667Y635917D01*
X329917Y635333D01*
Y633000D01*
G01X332683D02*
Y636333D01*
G01Y635500D02*
X333017Y635917D01*
X333517Y636250D01*
X334183Y636333D01*
X334767Y636250D01*
X335267Y635917D01*
X335517Y635333D01*
Y633000D01*
G01X338450Y635250D02*
X341117D01*
X340867Y635833D01*
X340450Y636167D01*
X339867Y636333D01*
X339283Y636250D01*
X338783Y636000D01*
X338450Y635417D01*
X338283Y634917D01*
Y634417D01*
X338450Y633917D01*
X338867Y633417D01*
X339367Y633083D01*
X339950Y633000D01*
X340533Y633167D01*
X341117Y633667D01*
G01X346633Y635917D02*
X346050Y636250D01*
X345550Y636333D01*
X344883Y636167D01*
X344383Y635833D01*
X344050Y635250D01*
X343967Y634667D01*
X344050Y634083D01*
X344383Y633583D01*
X344883Y633167D01*
X345550Y633000D01*
X346133Y633167D01*
X346633Y633500D01*
G01X350900Y638000D02*
Y633000D01*
G01X349733Y636333D02*
X352067D01*
G01X356500D02*
Y633000D01*
G01Y637667D02*
X356333Y637750D01*
Y637917D01*
X356500Y638000D01*
X356667Y637917D01*
Y637750D01*
X356500Y637667D01*
G01X360683Y633000D02*
Y636333D01*
G01Y635500D02*
X361017Y635917D01*
X361517Y636250D01*
X362183Y636333D01*
X362767Y636250D01*
X363267Y635917D01*
X363517Y635333D01*
Y633000D01*
G01X366533Y631750D02*
X367117Y631417D01*
X367783Y631333D01*
X368367Y631417D01*
X368867Y631833D01*
X369200Y632417D01*
Y636333D01*
G01Y635667D02*
X368867Y636000D01*
X368367Y636250D01*
X367783Y636333D01*
X367117Y636167D01*
X366700Y635833D01*
X366367Y635250D01*
X366200Y634667D01*
X366283Y634167D01*
X366617Y633583D01*
X367117Y633167D01*
X367783Y633000D01*
X368283Y633083D01*
X368867Y633417D01*
X369200Y633750D01*
G01X378900Y638000D02*
Y633000D01*
G01X377733Y636333D02*
X380067D01*
G01X384500Y633000D02*
X384000Y633083D01*
X383500Y633417D01*
X383167Y634000D01*
X383000Y634667D01*
X383167Y635333D01*
X383500Y635917D01*
X384000Y636250D01*
X384500Y636333D01*
X385000Y636250D01*
X385500Y635917D01*
X385833Y635333D01*
X385917Y634667D01*
X385833Y634000D01*
X385500Y633417D01*
X385000Y633083D01*
X384500Y633000D01*
G01X395700D02*
X395200Y633083D01*
X394700Y633417D01*
X394367Y634000D01*
X394200Y634667D01*
X394367Y635333D01*
X394700Y635917D01*
X395200Y636250D01*
X395700Y636333D01*
X396200Y636250D01*
X396700Y635917D01*
X397033Y635333D01*
X397117Y634667D01*
X397033Y634000D01*
X396700Y633417D01*
X396200Y633083D01*
X395700Y633000D01*
G01X401300Y638000D02*
Y633000D01*
G01X400133Y636333D02*
X402467D01*
G01X405483Y633000D02*
Y638000D01*
G01Y635583D02*
X405900Y636000D01*
X406317Y636250D01*
X406983Y636333D01*
X407483Y636250D01*
X408067Y635917D01*
X408317Y635417D01*
Y633000D01*
G01X411250Y635250D02*
X413917D01*
X413667Y635833D01*
X413250Y636167D01*
X412667Y636333D01*
X412083Y636250D01*
X411583Y636000D01*
X411250Y635417D01*
X411083Y634917D01*
Y634417D01*
X411250Y633917D01*
X411667Y633417D01*
X412167Y633083D01*
X412750Y633000D01*
X413333Y633167D01*
X413917Y633667D01*
G01X416933Y633000D02*
Y636333D01*
G01Y635667D02*
X417350Y636000D01*
X417767Y636250D01*
X418350Y636333D01*
X418767Y636250D01*
X419267Y636000D01*
G01X429300Y633000D02*
Y638000D01*
G01X436400Y633000D02*
Y636333D01*
G01Y635750D02*
X436067Y636083D01*
X435567Y636250D01*
X434983Y636333D01*
X434400Y636167D01*
X433900Y635833D01*
X433567Y635333D01*
X433400Y634667D01*
X433567Y634000D01*
X433900Y633500D01*
X434400Y633167D01*
X434983Y633000D01*
X435567Y633083D01*
X436067Y633333D01*
X436400Y633667D01*
G01X438750Y631500D02*
X439250Y631333D01*
X439917Y631500D01*
X440333Y631833D01*
X440667Y632250D01*
X441167Y633583D01*
X442250Y636333D01*
G01X439583D02*
X441167Y633583D01*
G01X444850Y635250D02*
X447517D01*
X447267Y635833D01*
X446850Y636167D01*
X446267Y636333D01*
X445683Y636250D01*
X445183Y636000D01*
X444850Y635417D01*
X444683Y634917D01*
Y634417D01*
X444850Y633917D01*
X445267Y633417D01*
X445767Y633083D01*
X446350Y633000D01*
X446933Y633167D01*
X447517Y633667D01*
G01X450533Y633000D02*
Y636333D01*
G01Y635667D02*
X450950Y636000D01*
X451367Y636250D01*
X451950Y636333D01*
X452367Y636250D01*
X452867Y636000D01*
G01X456050Y633583D02*
X456467Y633250D01*
X457050Y633000D01*
X457550D01*
X458050Y633167D01*
X458383Y633417D01*
X458550Y633750D01*
X458467Y634250D01*
X458133Y634500D01*
X456633Y635000D01*
X456300Y635583D01*
X456467Y636000D01*
X456800Y636250D01*
X457300Y636333D01*
X457800Y636250D01*
X458300Y636000D01*
G01X463317Y631333D02*
X464150Y632167D01*
X464567Y633000D01*
Y636333D01*
X464150Y637167D01*
X463317Y638000D01*
G01X270667Y643500D02*
Y648500D01*
X272333D01*
X273000Y648250D01*
X273500Y647917D01*
X273917Y647417D01*
X274250Y646833D01*
X274333Y646000D01*
X274250Y645167D01*
X273917Y644583D01*
X273500Y644083D01*
X273000Y643750D01*
X272333Y643500D01*
X270667D01*
G01X276850Y645750D02*
X279517D01*
X279267Y646333D01*
X278850Y646667D01*
X278267Y646833D01*
X277683Y646750D01*
X277183Y646500D01*
X276850Y645917D01*
X276683Y645417D01*
Y644917D01*
X276850Y644417D01*
X277267Y643917D01*
X277767Y643583D01*
X278350Y643500D01*
X278933Y643667D01*
X279517Y644167D01*
G01X283700Y643500D02*
Y648500D01*
G01X288050Y645750D02*
X290717D01*
X290467Y646333D01*
X290050Y646667D01*
X289467Y646833D01*
X288883Y646750D01*
X288383Y646500D01*
X288050Y645917D01*
X287883Y645417D01*
Y644917D01*
X288050Y644417D01*
X288467Y643917D01*
X288967Y643583D01*
X289550Y643500D01*
X290133Y643667D01*
X290717Y644167D01*
G01X294900Y648500D02*
Y643500D01*
G01X293733Y646833D02*
X296067D01*
G01X299250Y645750D02*
X301917D01*
X301667Y646333D01*
X301250Y646667D01*
X300667Y646833D01*
X300083Y646750D01*
X299583Y646500D01*
X299250Y645917D01*
X299083Y645417D01*
Y644917D01*
X299250Y644417D01*
X299667Y643917D01*
X300167Y643583D01*
X300750Y643500D01*
X301333Y643667D01*
X301917Y644167D01*
G01X310283Y643500D02*
Y646833D01*
G01Y646000D02*
X310617Y646417D01*
X311117Y646750D01*
X311783Y646833D01*
X312367Y646750D01*
X312867Y646417D01*
X313117Y645833D01*
Y643500D01*
G01X317300D02*
X316800Y643583D01*
X316300Y643917D01*
X315967Y644500D01*
X315800Y645167D01*
X315967Y645833D01*
X316300Y646417D01*
X316800Y646750D01*
X317300Y646833D01*
X317800Y646750D01*
X318300Y646417D01*
X318633Y645833D01*
X318717Y645167D01*
X318633Y644500D01*
X318300Y643917D01*
X317800Y643583D01*
X317300Y643500D01*
G01X321483D02*
Y646833D01*
G01Y646000D02*
X321817Y646417D01*
X322317Y646750D01*
X322983Y646833D01*
X323567Y646750D01*
X324067Y646417D01*
X324317Y645833D01*
Y643500D01*
G01X327417Y645167D02*
X329583D01*
G01X333600Y643500D02*
Y647750D01*
X333767Y648167D01*
X334100Y648417D01*
X334600Y648500D01*
X335100Y648333D01*
X335350Y647917D01*
G01X334350Y646500D02*
X332683D01*
G01X338283Y646833D02*
Y644500D01*
X338617Y643917D01*
X339117Y643583D01*
X339700Y643500D01*
X340283Y643583D01*
X340783Y643917D01*
X341117Y644500D01*
G01Y643500D02*
Y646833D01*
G01X343883Y643500D02*
Y646833D01*
G01Y646000D02*
X344217Y646417D01*
X344717Y646750D01*
X345383Y646833D01*
X345967Y646750D01*
X346467Y646417D01*
X346717Y645833D01*
Y643500D01*
G01X352233Y646417D02*
X351650Y646750D01*
X351150Y646833D01*
X350483Y646667D01*
X349983Y646333D01*
X349650Y645750D01*
X349567Y645167D01*
X349650Y644583D01*
X349983Y644083D01*
X350483Y643667D01*
X351150Y643500D01*
X351733Y643667D01*
X352233Y644000D01*
G01X356500Y648500D02*
Y643500D01*
G01X355333Y646833D02*
X357667D01*
G01X362100D02*
Y643500D01*
G01Y648167D02*
X361933Y648250D01*
Y648417D01*
X362100Y648500D01*
X362267Y648417D01*
Y648250D01*
X362100Y648167D01*
G01X367700Y643500D02*
X367200Y643583D01*
X366700Y643917D01*
X366367Y644500D01*
X366200Y645167D01*
X366367Y645833D01*
X366700Y646417D01*
X367200Y646750D01*
X367700Y646833D01*
X368200Y646750D01*
X368700Y646417D01*
X369033Y645833D01*
X369117Y645167D01*
X369033Y644500D01*
X368700Y643917D01*
X368200Y643583D01*
X367700Y643500D01*
G01X371883D02*
Y646833D01*
G01Y646000D02*
X372217Y646417D01*
X372717Y646750D01*
X373383Y646833D01*
X373967Y646750D01*
X374467Y646417D01*
X374717Y645833D01*
Y643500D01*
G01X380400D02*
Y646833D01*
G01Y646250D02*
X380067Y646583D01*
X379567Y646750D01*
X378983Y646833D01*
X378400Y646667D01*
X377900Y646333D01*
X377567Y645833D01*
X377400Y645167D01*
X377567Y644500D01*
X377900Y644000D01*
X378400Y643667D01*
X378983Y643500D01*
X379567Y643583D01*
X380067Y643833D01*
X380400Y644167D01*
G01X384500Y643500D02*
Y648500D01*
G01X394200Y641833D02*
Y646833D01*
G01Y646083D02*
X394617Y646500D01*
X395033Y646750D01*
X395700Y646833D01*
X396283Y646750D01*
X396867Y646333D01*
X397117Y645750D01*
X397200Y645167D01*
X397117Y644583D01*
X396867Y644000D01*
X396367Y643667D01*
X395700Y643500D01*
X395117Y643583D01*
X394533Y643833D01*
X394200Y644167D01*
G01X402800Y643500D02*
Y646833D01*
G01Y646250D02*
X402467Y646583D01*
X401967Y646750D01*
X401383Y646833D01*
X400800Y646667D01*
X400300Y646333D01*
X399967Y645833D01*
X399800Y645167D01*
X399967Y644500D01*
X400300Y644000D01*
X400800Y643667D01*
X401383Y643500D01*
X401967Y643583D01*
X402467Y643833D01*
X402800Y644167D01*
G01X408400Y648500D02*
Y643500D01*
G01Y644250D02*
X408067Y643833D01*
X407567Y643583D01*
X406983Y643500D01*
X406317Y643667D01*
X405817Y644083D01*
X405483Y644583D01*
X405400Y645167D01*
X405483Y645750D01*
X405817Y646250D01*
X406317Y646667D01*
X406983Y646833D01*
X407567Y646750D01*
X407983Y646583D01*
X408400Y646250D01*
G01X418100Y646833D02*
Y643500D01*
G01Y648167D02*
X417933Y648250D01*
Y648417D01*
X418100Y648500D01*
X418267Y648417D01*
Y648250D01*
X418100Y648167D01*
G01X422283Y643500D02*
Y646833D01*
G01Y646000D02*
X422617Y646417D01*
X423117Y646750D01*
X423783Y646833D01*
X424367Y646750D01*
X424867Y646417D01*
X425117Y645833D01*
Y643500D01*
G01X436400D02*
Y646833D01*
G01Y646250D02*
X436067Y646583D01*
X435567Y646750D01*
X434983Y646833D01*
X434400Y646667D01*
X433900Y646333D01*
X433567Y645833D01*
X433400Y645167D01*
X433567Y644500D01*
X433900Y644000D01*
X434400Y643667D01*
X434983Y643500D01*
X435567Y643583D01*
X436067Y643833D01*
X436400Y644167D01*
G01X440500Y643500D02*
Y648500D01*
G01X446100Y643500D02*
Y648500D01*
G01X455800Y641833D02*
Y646833D01*
G01Y646083D02*
X456217Y646500D01*
X456633Y646750D01*
X457300Y646833D01*
X457883Y646750D01*
X458467Y646333D01*
X458717Y645750D01*
X458800Y645167D01*
X458717Y644583D01*
X458467Y644000D01*
X457967Y643667D01*
X457300Y643500D01*
X456717Y643583D01*
X456133Y643833D01*
X455800Y644167D01*
G01X461733Y643500D02*
Y646833D01*
G01Y646167D02*
X462150Y646500D01*
X462567Y646750D01*
X463150Y646833D01*
X463567Y646750D01*
X464067Y646500D01*
G01X468500Y643500D02*
X468000Y643583D01*
X467500Y643917D01*
X467167Y644500D01*
X467000Y645167D01*
X467167Y645833D01*
X467500Y646417D01*
X468000Y646750D01*
X468500Y646833D01*
X469000Y646750D01*
X469500Y646417D01*
X469833Y645833D01*
X469917Y645167D01*
X469833Y644500D01*
X469500Y643917D01*
X469000Y643583D01*
X468500Y643500D01*
G01X475600Y648500D02*
Y643500D01*
G01Y644250D02*
X475267Y643833D01*
X474767Y643583D01*
X474183Y643500D01*
X473517Y643667D01*
X473017Y644083D01*
X472683Y644583D01*
X472600Y645167D01*
X472683Y645750D01*
X473017Y646250D01*
X473517Y646667D01*
X474183Y646833D01*
X474767Y646750D01*
X475183Y646583D01*
X475600Y646250D01*
G01X478283Y646833D02*
Y644500D01*
X478617Y643917D01*
X479117Y643583D01*
X479700Y643500D01*
X480283Y643583D01*
X480783Y643917D01*
X481117Y644500D01*
G01Y643500D02*
Y646833D01*
G01X486633Y646417D02*
X486050Y646750D01*
X485550Y646833D01*
X484883Y646667D01*
X484383Y646333D01*
X484050Y645750D01*
X483967Y645167D01*
X484050Y644583D01*
X484383Y644083D01*
X484883Y643667D01*
X485550Y643500D01*
X486133Y643667D01*
X486633Y644000D01*
G01X490900Y648500D02*
Y643500D01*
G01X489733Y646833D02*
X492067D01*
G01X495250Y644083D02*
X495667Y643750D01*
X496250Y643500D01*
X496750D01*
X497250Y643667D01*
X497583Y643917D01*
X497750Y644250D01*
X497667Y644750D01*
X497333Y645000D01*
X495833Y645500D01*
X495500Y646083D01*
X495667Y646500D01*
X496000Y646750D01*
X496500Y646833D01*
X497000Y646750D01*
X497500Y646500D01*
G01X502100Y643333D02*
X501933Y643417D01*
Y643583D01*
X502100Y643667D01*
X502267Y643583D01*
Y643417D01*
X502100Y643333D01*
G01X507283Y641833D02*
X506450Y642667D01*
X506033Y643500D01*
Y646833D01*
X506450Y647667D01*
X507283Y648500D01*
G01X512300D02*
X514300D01*
G01X513300D02*
Y643500D01*
G01X512300D02*
X514300D01*
G01X517650Y644083D02*
X518067Y643750D01*
X518650Y643500D01*
X519150D01*
X519650Y643667D01*
X519983Y643917D01*
X520150Y644250D01*
X520067Y644750D01*
X519733Y645000D01*
X518233Y645500D01*
X517900Y646083D01*
X518067Y646500D01*
X518400Y646750D01*
X518900Y646833D01*
X519400Y646750D01*
X519900Y646500D01*
G01X524500Y643500D02*
X524000Y643583D01*
X523500Y643917D01*
X523167Y644500D01*
X523000Y645167D01*
X523167Y645833D01*
X523500Y646417D01*
X524000Y646750D01*
X524500Y646833D01*
X525000Y646750D01*
X525500Y646417D01*
X525833Y645833D01*
X525917Y645167D01*
X525833Y644500D01*
X525500Y643917D01*
X525000Y643583D01*
X524500Y643500D01*
G01X530100D02*
Y648500D01*
G01X537200Y643500D02*
Y646833D01*
G01Y646250D02*
X536867Y646583D01*
X536367Y646750D01*
X535783Y646833D01*
X535200Y646667D01*
X534700Y646333D01*
X534367Y645833D01*
X534200Y645167D01*
X534367Y644500D01*
X534700Y644000D01*
X535200Y643667D01*
X535783Y643500D01*
X536367Y643583D01*
X536867Y643833D01*
X537200Y644167D01*
G01X541300Y648500D02*
Y643500D01*
G01X540133Y646833D02*
X542467D01*
G01X545650Y645750D02*
X548317D01*
X548067Y646333D01*
X547650Y646667D01*
X547067Y646833D01*
X546483Y646750D01*
X545983Y646500D01*
X545650Y645917D01*
X545483Y645417D01*
Y644917D01*
X545650Y644417D01*
X546067Y643917D01*
X546567Y643583D01*
X547150Y643500D01*
X547733Y643667D01*
X548317Y644167D01*
G01X556600Y641833D02*
Y646833D01*
G01Y646083D02*
X557017Y646500D01*
X557433Y646750D01*
X558100Y646833D01*
X558683Y646750D01*
X559267Y646333D01*
X559517Y645750D01*
X559600Y645167D01*
X559517Y644583D01*
X559267Y644000D01*
X558767Y643667D01*
X558100Y643500D01*
X557517Y643583D01*
X556933Y643833D01*
X556600Y644167D01*
G01X565200Y643500D02*
Y646833D01*
G01Y646250D02*
X564867Y646583D01*
X564367Y646750D01*
X563783Y646833D01*
X563200Y646667D01*
X562700Y646333D01*
X562367Y645833D01*
X562200Y645167D01*
X562367Y644500D01*
X562700Y644000D01*
X563200Y643667D01*
X563783Y643500D01*
X564367Y643583D01*
X564867Y643833D01*
X565200Y644167D01*
G01X570800Y648500D02*
Y643500D01*
G01Y644250D02*
X570467Y643833D01*
X569967Y643583D01*
X569383Y643500D01*
X568717Y643667D01*
X568217Y644083D01*
X567883Y644583D01*
X567800Y645167D01*
X567883Y645750D01*
X568217Y646250D01*
X568717Y646667D01*
X569383Y646833D01*
X569967Y646750D01*
X570383Y646583D01*
X570800Y646250D01*
G01X270833Y586500D02*
Y591500D01*
X272833D01*
X273500Y591250D01*
X274000Y590667D01*
X274167Y590000D01*
X274000Y589333D01*
X273583Y588833D01*
X272833Y588583D01*
X270833D01*
G01X278100Y586500D02*
Y591500D01*
G01X282283Y589833D02*
Y587500D01*
X282617Y586917D01*
X283117Y586583D01*
X283700Y586500D01*
X284283Y586583D01*
X284783Y586917D01*
X285117Y587500D01*
G01Y586500D02*
Y589833D01*
G01X288133Y585250D02*
X288717Y584917D01*
X289383Y584833D01*
X289967Y584917D01*
X290467Y585333D01*
X290800Y585917D01*
Y589833D01*
G01Y589167D02*
X290467Y589500D01*
X289967Y589750D01*
X289383Y589833D01*
X288717Y589667D01*
X288300Y589333D01*
X287967Y588750D01*
X287800Y588167D01*
X287883Y587667D01*
X288217Y587083D01*
X288717Y586667D01*
X289383Y586500D01*
X289883Y586583D01*
X290467Y586917D01*
X290800Y587250D01*
G01X293733Y585250D02*
X294317Y584917D01*
X294983Y584833D01*
X295567Y584917D01*
X296067Y585333D01*
X296400Y585917D01*
Y589833D01*
G01Y589167D02*
X296067Y589500D01*
X295567Y589750D01*
X294983Y589833D01*
X294317Y589667D01*
X293900Y589333D01*
X293567Y588750D01*
X293400Y588167D01*
X293483Y587667D01*
X293817Y587083D01*
X294317Y586667D01*
X294983Y586500D01*
X295483Y586583D01*
X296067Y586917D01*
X296400Y587250D01*
G01X299250Y588750D02*
X301917D01*
X301667Y589333D01*
X301250Y589667D01*
X300667Y589833D01*
X300083Y589750D01*
X299583Y589500D01*
X299250Y588917D01*
X299083Y588417D01*
Y587917D01*
X299250Y587417D01*
X299667Y586917D01*
X300167Y586583D01*
X300750Y586500D01*
X301333Y586667D01*
X301917Y587167D01*
G01X307600Y591500D02*
Y586500D01*
G01Y587250D02*
X307267Y586833D01*
X306767Y586583D01*
X306183Y586500D01*
X305517Y586667D01*
X305017Y587083D01*
X304683Y587583D01*
X304600Y588167D01*
X304683Y588750D01*
X305017Y589250D01*
X305517Y589667D01*
X306183Y589833D01*
X306767Y589750D01*
X307183Y589583D01*
X307600Y589250D01*
G01X315217Y591500D02*
X317300Y586500D01*
X319383Y591500D01*
G01X322900Y589833D02*
Y586500D01*
G01Y591167D02*
X322733Y591250D01*
Y591417D01*
X322900Y591500D01*
X323067Y591417D01*
Y591250D01*
X322900Y591167D01*
G01X330000Y586500D02*
Y589833D01*
G01Y589250D02*
X329667Y589583D01*
X329167Y589750D01*
X328583Y589833D01*
X328000Y589667D01*
X327500Y589333D01*
X327167Y588833D01*
X327000Y588167D01*
X327167Y587500D01*
X327500Y587000D01*
X328000Y586667D01*
X328583Y586500D01*
X329167Y586583D01*
X329667Y586833D01*
X330000Y587167D01*
G01X333683Y584833D02*
X332850Y585667D01*
X332433Y586500D01*
Y589833D01*
X332850Y590667D01*
X333683Y591500D01*
G01X338283Y586500D02*
Y591500D01*
G01Y589083D02*
X338700Y589500D01*
X339117Y589750D01*
X339783Y589833D01*
X340283Y589750D01*
X340867Y589417D01*
X341117Y588917D01*
Y586500D01*
G01X345300D02*
X344800Y586583D01*
X344300Y586917D01*
X343967Y587500D01*
X343800Y588167D01*
X343967Y588833D01*
X344300Y589417D01*
X344800Y589750D01*
X345300Y589833D01*
X345800Y589750D01*
X346300Y589417D01*
X346633Y588833D01*
X346717Y588167D01*
X346633Y587500D01*
X346300Y586917D01*
X345800Y586583D01*
X345300Y586500D01*
G01X350900D02*
Y591500D01*
G01X355250Y588750D02*
X357917D01*
X357667Y589333D01*
X357250Y589667D01*
X356667Y589833D01*
X356083Y589750D01*
X355583Y589500D01*
X355250Y588917D01*
X355083Y588417D01*
Y587917D01*
X355250Y587417D01*
X355667Y586917D01*
X356167Y586583D01*
X356750Y586500D01*
X357333Y586667D01*
X357917Y587167D01*
G01X366450Y587083D02*
X366867Y586750D01*
X367450Y586500D01*
X367950D01*
X368450Y586667D01*
X368783Y586917D01*
X368950Y587250D01*
X368867Y587750D01*
X368533Y588000D01*
X367033Y588500D01*
X366700Y589083D01*
X366867Y589500D01*
X367200Y589750D01*
X367700Y589833D01*
X368200Y589750D01*
X368700Y589500D01*
G01X373300Y589833D02*
Y586500D01*
G01Y591167D02*
X373133Y591250D01*
Y591417D01*
X373300Y591500D01*
X373467Y591417D01*
Y591250D01*
X373300Y591167D01*
G01X377650Y589833D02*
X380150D01*
X377650Y586500D01*
X380150D01*
G01X383250Y588750D02*
X385917D01*
X385667Y589333D01*
X385250Y589667D01*
X384667Y589833D01*
X384083Y589750D01*
X383583Y589500D01*
X383250Y588917D01*
X383083Y588417D01*
Y587917D01*
X383250Y587417D01*
X383667Y586917D01*
X384167Y586583D01*
X384750Y586500D01*
X385333Y586667D01*
X385917Y587167D01*
G01X391767Y586500D02*
X388433Y588167D01*
X391767Y589833D01*
G01X395700Y586500D02*
Y591500D01*
X394700Y590500D01*
G01Y586500D02*
X396700D01*
G01X399717Y588583D02*
X400300Y589167D01*
X400800Y589500D01*
X401467Y589667D01*
X402050Y589500D01*
X402467Y589167D01*
X402800Y588667D01*
X402883Y588083D01*
X402800Y587583D01*
X402467Y587083D01*
X401967Y586667D01*
X401383Y586500D01*
X400717Y586667D01*
X400133Y587167D01*
X399800Y587917D01*
X399717Y588750D01*
X399883Y589833D01*
X400133Y590417D01*
X400550Y591000D01*
X401133Y591417D01*
X401717Y591500D01*
X402300Y591333D01*
X402717Y590917D01*
G01X410000Y586500D02*
Y589833D01*
G01Y588917D02*
X410250Y589333D01*
X410667Y589667D01*
X411250Y589833D01*
X411833Y589667D01*
X412250Y589333D01*
X412500Y588917D01*
Y586500D01*
G01Y588917D02*
X412750Y589333D01*
X413167Y589667D01*
X413750Y589833D01*
X414333Y589667D01*
X414750Y589333D01*
X415000Y588833D01*
Y586500D01*
G01X418100Y589833D02*
Y586500D01*
G01Y591167D02*
X417933Y591250D01*
Y591417D01*
X418100Y591500D01*
X418267Y591417D01*
Y591250D01*
X418100Y591167D01*
G01X423700Y586500D02*
Y591500D01*
G01X429717Y584833D02*
X430550Y585667D01*
X430967Y586500D01*
Y589833D01*
X430550Y590667D01*
X429717Y591500D01*
G01X270833Y571500D02*
Y576500D01*
X272833D01*
X273500Y576250D01*
X274000Y575667D01*
X274167Y575000D01*
X274000Y574333D01*
X273583Y573833D01*
X272833Y573583D01*
X270833D01*
G01X278100Y571500D02*
Y576500D01*
G01X282283Y574833D02*
Y572500D01*
X282617Y571917D01*
X283117Y571583D01*
X283700Y571500D01*
X284283Y571583D01*
X284783Y571917D01*
X285117Y572500D01*
G01Y571500D02*
Y574833D01*
G01X288133Y570250D02*
X288717Y569917D01*
X289383Y569833D01*
X289967Y569917D01*
X290467Y570333D01*
X290800Y570917D01*
Y574833D01*
G01Y574167D02*
X290467Y574500D01*
X289967Y574750D01*
X289383Y574833D01*
X288717Y574667D01*
X288300Y574333D01*
X287967Y573750D01*
X287800Y573167D01*
X287883Y572667D01*
X288217Y572083D01*
X288717Y571667D01*
X289383Y571500D01*
X289883Y571583D01*
X290467Y571917D01*
X290800Y572250D01*
G01X293733Y570250D02*
X294317Y569917D01*
X294983Y569833D01*
X295567Y569917D01*
X296067Y570333D01*
X296400Y570917D01*
Y574833D01*
G01Y574167D02*
X296067Y574500D01*
X295567Y574750D01*
X294983Y574833D01*
X294317Y574667D01*
X293900Y574333D01*
X293567Y573750D01*
X293400Y573167D01*
X293483Y572667D01*
X293817Y572083D01*
X294317Y571667D01*
X294983Y571500D01*
X295483Y571583D01*
X296067Y571917D01*
X296400Y572250D01*
G01X299250Y573750D02*
X301917D01*
X301667Y574333D01*
X301250Y574667D01*
X300667Y574833D01*
X300083Y574750D01*
X299583Y574500D01*
X299250Y573917D01*
X299083Y573417D01*
Y572917D01*
X299250Y572417D01*
X299667Y571917D01*
X300167Y571583D01*
X300750Y571500D01*
X301333Y571667D01*
X301917Y572167D01*
G01X307600Y576500D02*
Y571500D01*
G01Y572250D02*
X307267Y571833D01*
X306767Y571583D01*
X306183Y571500D01*
X305517Y571667D01*
X305017Y572083D01*
X304683Y572583D01*
X304600Y573167D01*
X304683Y573750D01*
X305017Y574250D01*
X305517Y574667D01*
X306183Y574833D01*
X306767Y574750D01*
X307183Y574583D01*
X307600Y574250D01*
G01X315633Y571500D02*
Y576500D01*
X317633D01*
X318300Y576250D01*
X318800Y575667D01*
X318967Y575000D01*
X318800Y574333D01*
X318383Y573833D01*
X317633Y573583D01*
X315633D01*
G01X322900Y576500D02*
Y571500D01*
G01X320983Y576500D02*
X324817D01*
G01X326750Y571500D02*
Y576500D01*
G01X330250D02*
Y571500D01*
G01Y574000D02*
X326750D01*
G01X333683Y569833D02*
X332850Y570667D01*
X332433Y571500D01*
Y574833D01*
X332850Y575667D01*
X333683Y576500D01*
G01X338283Y571500D02*
Y576500D01*
G01Y574083D02*
X338700Y574500D01*
X339117Y574750D01*
X339783Y574833D01*
X340283Y574750D01*
X340867Y574417D01*
X341117Y573917D01*
Y571500D01*
G01X345300D02*
X344800Y571583D01*
X344300Y571917D01*
X343967Y572500D01*
X343800Y573167D01*
X343967Y573833D01*
X344300Y574417D01*
X344800Y574750D01*
X345300Y574833D01*
X345800Y574750D01*
X346300Y574417D01*
X346633Y573833D01*
X346717Y573167D01*
X346633Y572500D01*
X346300Y571917D01*
X345800Y571583D01*
X345300Y571500D01*
G01X350900D02*
Y576500D01*
G01X355250Y573750D02*
X357917D01*
X357667Y574333D01*
X357250Y574667D01*
X356667Y574833D01*
X356083Y574750D01*
X355583Y574500D01*
X355250Y573917D01*
X355083Y573417D01*
Y572917D01*
X355250Y572417D01*
X355667Y571917D01*
X356167Y571583D01*
X356750Y571500D01*
X357333Y571667D01*
X357917Y572167D01*
G01X366450Y572083D02*
X366867Y571750D01*
X367450Y571500D01*
X367950D01*
X368450Y571667D01*
X368783Y571917D01*
X368950Y572250D01*
X368867Y572750D01*
X368533Y573000D01*
X367033Y573500D01*
X366700Y574083D01*
X366867Y574500D01*
X367200Y574750D01*
X367700Y574833D01*
X368200Y574750D01*
X368700Y574500D01*
G01X373300Y574833D02*
Y571500D01*
G01Y576167D02*
X373133Y576250D01*
Y576417D01*
X373300Y576500D01*
X373467Y576417D01*
Y576250D01*
X373300Y576167D01*
G01X377650Y574833D02*
X380150D01*
X377650Y571500D01*
X380150D01*
G01X383250Y573750D02*
X385917D01*
X385667Y574333D01*
X385250Y574667D01*
X384667Y574833D01*
X384083Y574750D01*
X383583Y574500D01*
X383250Y573917D01*
X383083Y573417D01*
Y572917D01*
X383250Y572417D01*
X383667Y571917D01*
X384167Y571583D01*
X384750Y571500D01*
X385333Y571667D01*
X385917Y572167D01*
G01X388433Y571500D02*
X391767Y573167D01*
X388433Y574833D01*
G01X394617Y572417D02*
X396783D01*
G01Y573917D02*
X394617D01*
G01X401300Y571500D02*
Y576500D01*
X400300Y575500D01*
G01Y571500D02*
X402300D01*
G01X405317Y573583D02*
X405900Y574167D01*
X406400Y574500D01*
X407067Y574667D01*
X407650Y574500D01*
X408067Y574167D01*
X408400Y573667D01*
X408483Y573083D01*
X408400Y572583D01*
X408067Y572083D01*
X407567Y571667D01*
X406983Y571500D01*
X406317Y571667D01*
X405733Y572167D01*
X405400Y572917D01*
X405317Y573750D01*
X405483Y574833D01*
X405733Y575417D01*
X406150Y576000D01*
X406733Y576417D01*
X407317Y576500D01*
X407900Y576333D01*
X408317Y575917D01*
G01X415600Y571500D02*
Y574833D01*
G01Y573917D02*
X415850Y574333D01*
X416267Y574667D01*
X416850Y574833D01*
X417433Y574667D01*
X417850Y574333D01*
X418100Y573917D01*
Y571500D01*
G01Y573917D02*
X418350Y574333D01*
X418767Y574667D01*
X419350Y574833D01*
X419933Y574667D01*
X420350Y574333D01*
X420600Y573833D01*
Y571500D01*
G01X423700Y574833D02*
Y571500D01*
G01Y576167D02*
X423533Y576250D01*
Y576417D01*
X423700Y576500D01*
X423867Y576417D01*
Y576250D01*
X423700Y576167D01*
G01X429300Y571500D02*
Y576500D01*
G01X435317Y569833D02*
X436150Y570667D01*
X436567Y571500D01*
Y574833D01*
X436150Y575667D01*
X435317Y576500D01*
G01X262500Y565500D02*
X694500D01*
G01X262500Y580500D02*
X694500D01*
G01X404500Y666833D02*
Y663500D01*
G01Y668167D02*
X404333Y668250D01*
Y668417D01*
X404500Y668500D01*
X404667Y668417D01*
Y668250D01*
X404500Y668167D01*
G01X410100Y668500D02*
Y663500D01*
G01X408933Y666833D02*
X411267D01*
G01X414450Y665750D02*
X417117D01*
X416867Y666333D01*
X416450Y666667D01*
X415867Y666833D01*
X415283Y666750D01*
X414783Y666500D01*
X414450Y665917D01*
X414283Y665417D01*
Y664917D01*
X414450Y664417D01*
X414867Y663917D01*
X415367Y663583D01*
X415950Y663500D01*
X416533Y663667D01*
X417117Y664167D01*
G01X418800Y663500D02*
Y666833D01*
G01Y665917D02*
X419050Y666333D01*
X419467Y666667D01*
X420050Y666833D01*
X420633Y666667D01*
X421050Y666333D01*
X421300Y665917D01*
Y663500D01*
G01Y665917D02*
X421550Y666333D01*
X421967Y666667D01*
X422550Y666833D01*
X423133Y666667D01*
X423550Y666333D01*
X423800Y665833D01*
Y663500D01*
G01X590417Y860000D02*
X592500Y855000D01*
X594583Y860000D01*
G01X596267Y856000D02*
X596767Y855417D01*
X597433Y855083D01*
X598183Y855000D01*
X598850Y855083D01*
X599517Y855500D01*
X599933Y856000D01*
X600017Y856500D01*
X599850Y857083D01*
X599267Y857500D01*
X598683Y857667D01*
X597933D01*
G01X598683D02*
X599183Y857917D01*
X599600Y858333D01*
X599767Y858833D01*
X599600Y859333D01*
X599183Y859750D01*
X598433Y860000D01*
X597683Y859917D01*
X596933Y859583D01*
G01X603700Y854833D02*
X603533Y854917D01*
Y855083D01*
X603700Y855167D01*
X603867Y855083D01*
Y854917D01*
X603700Y854833D01*
G01X610300Y855000D02*
Y860000D01*
X607217Y856417D01*
X611383D01*
G01X624517Y859167D02*
X625017Y859667D01*
X625600Y859917D01*
X626267Y860000D01*
X627100Y859833D01*
X627683Y859417D01*
X627850Y858917D01*
X627767Y858417D01*
X627433Y858000D01*
X625767Y857167D01*
X625017Y856583D01*
X624517Y855750D01*
X624350Y855000D01*
X627850D01*
G01X631700Y860000D02*
X631033Y859833D01*
X630533Y859417D01*
X630200Y858917D01*
X629950Y858250D01*
X629867Y857500D01*
X629950Y856750D01*
X630200Y856083D01*
X630533Y855583D01*
X631033Y855167D01*
X631700Y855000D01*
X632367Y855167D01*
X632867Y855583D01*
X633200Y856083D01*
X633450Y856750D01*
X633533Y857500D01*
X633450Y858250D01*
X633200Y858917D01*
X632867Y859417D01*
X632367Y859833D01*
X631700Y860000D01*
G01X637300Y855000D02*
Y860000D01*
X636300Y859000D01*
G01Y855000D02*
X638300D01*
G01X643900D02*
Y860000D01*
X640817Y856417D01*
X644983D01*
G01X647000Y854833D02*
X650000Y860000D01*
G01X654100D02*
X653433Y859833D01*
X652933Y859417D01*
X652600Y858917D01*
X652350Y858250D01*
X652267Y857500D01*
X652350Y856750D01*
X652600Y856083D01*
X652933Y855583D01*
X653433Y855167D01*
X654100Y855000D01*
X654767Y855167D01*
X655267Y855583D01*
X655600Y856083D01*
X655850Y856750D01*
X655933Y857500D01*
X655850Y858250D01*
X655600Y858917D01*
X655267Y859417D01*
X654767Y859833D01*
X654100Y860000D01*
G01X659533Y855000D02*
X659700Y856083D01*
X659950Y857000D01*
X660283Y857833D01*
X660700Y858750D01*
X661367Y860000D01*
X658033D01*
G01X663800Y854833D02*
X666800Y860000D01*
G01X606583Y63167D02*
X608583D01*
G01X607500Y64250D02*
Y62083D01*
G01X611600Y61333D02*
X614600Y66500D01*
G01X617617Y63167D02*
X619783D01*
G01X622467Y62250D02*
X622967Y61833D01*
X623550Y61583D01*
X624300Y61500D01*
X625050Y61667D01*
X625633Y62000D01*
X626050Y62583D01*
X626133Y63250D01*
X625967Y63917D01*
X625550Y64333D01*
X624967Y64667D01*
X624383Y64750D01*
X623800Y64667D01*
X623050Y64333D01*
X623300Y66500D01*
X625550D01*
G01X627400Y61500D02*
Y64833D01*
G01Y63917D02*
X627650Y64333D01*
X628067Y64667D01*
X628650Y64833D01*
X629233Y64667D01*
X629650Y64333D01*
X629900Y63917D01*
Y61500D01*
G01Y63917D02*
X630150Y64333D01*
X630567Y64667D01*
X631150Y64833D01*
X631733Y64667D01*
X632150Y64333D01*
X632400Y63833D01*
Y61500D01*
G01X635500Y64833D02*
Y61500D01*
G01Y66167D02*
X635333Y66250D01*
Y66417D01*
X635500Y66500D01*
X635667Y66417D01*
Y66250D01*
X635500Y66167D01*
G01X641100Y61500D02*
Y66500D01*
G01X606583Y48167D02*
X608583D01*
G01X607500Y49250D02*
Y47083D01*
G01X611600Y46333D02*
X614600Y51500D01*
G01X617617Y48167D02*
X619783D01*
G01X622467Y47250D02*
X622967Y46833D01*
X623550Y46583D01*
X624300Y46500D01*
X625050Y46667D01*
X625633Y47000D01*
X626050Y47583D01*
X626133Y48250D01*
X625967Y48917D01*
X625550Y49333D01*
X624967Y49667D01*
X624383Y49750D01*
X623800Y49667D01*
X623050Y49333D01*
X623300Y51500D01*
X625550D01*
G01X627400Y46500D02*
Y49833D01*
G01Y48917D02*
X627650Y49333D01*
X628067Y49667D01*
X628650Y49833D01*
X629233Y49667D01*
X629650Y49333D01*
X629900Y48917D01*
Y46500D01*
G01Y48917D02*
X630150Y49333D01*
X630567Y49667D01*
X631150Y49833D01*
X631733Y49667D01*
X632150Y49333D01*
X632400Y48833D01*
Y46500D01*
G01X635500Y49833D02*
Y46500D01*
G01Y51167D02*
X635333Y51250D01*
Y51417D01*
X635500Y51500D01*
X635667Y51417D01*
Y51250D01*
X635500Y51167D01*
G01X641100Y46500D02*
Y51500D01*
G01X606583Y33167D02*
X608583D01*
G01X607500Y34250D02*
Y32083D01*
G01X611600Y31333D02*
X614600Y36500D01*
G01X617617Y33167D02*
X619783D01*
G01X622717Y35667D02*
X623217Y36167D01*
X623800Y36417D01*
X624467Y36500D01*
X625300Y36333D01*
X625883Y35917D01*
X626050Y35417D01*
X625967Y34917D01*
X625633Y34500D01*
X623967Y33667D01*
X623217Y33083D01*
X622717Y32250D01*
X622550Y31500D01*
X626050D01*
G01X627400D02*
Y34833D01*
G01Y33917D02*
X627650Y34333D01*
X628067Y34667D01*
X628650Y34833D01*
X629233Y34667D01*
X629650Y34333D01*
X629900Y33917D01*
Y31500D01*
G01Y33917D02*
X630150Y34333D01*
X630567Y34667D01*
X631150Y34833D01*
X631733Y34667D01*
X632150Y34333D01*
X632400Y33833D01*
Y31500D01*
G01X635500Y34833D02*
Y31500D01*
G01Y36167D02*
X635333Y36250D01*
Y36417D01*
X635500Y36500D01*
X635667Y36417D01*
Y36250D01*
X635500Y36167D01*
G01X641100Y31500D02*
Y36500D01*
G01X607083Y5833D02*
X606250Y6667D01*
X605833Y7500D01*
Y10833D01*
X606250Y11667D01*
X607083Y12500D01*
G01X613100Y7500D02*
Y12500D01*
X612100Y11500D01*
G01Y7500D02*
X614100D01*
G01X618700Y7333D02*
X618533Y7417D01*
Y7583D01*
X618700Y7667D01*
X618867Y7583D01*
Y7417D01*
X618700Y7333D01*
G01X622717Y11667D02*
X623217Y12167D01*
X623800Y12417D01*
X624467Y12500D01*
X625300Y12333D01*
X625883Y11917D01*
X626050Y11417D01*
X625967Y10917D01*
X625633Y10500D01*
X623967Y9667D01*
X623217Y9083D01*
X622717Y8250D01*
X622550Y7500D01*
X626050D01*
G01X627400D02*
Y10833D01*
G01Y9917D02*
X627650Y10333D01*
X628067Y10667D01*
X628650Y10833D01*
X629233Y10667D01*
X629650Y10333D01*
X629900Y9917D01*
Y7500D01*
G01Y9917D02*
X630150Y10333D01*
X630567Y10667D01*
X631150Y10833D01*
X631733Y10667D01*
X632150Y10333D01*
X632400Y9833D01*
Y7500D01*
G01X633000D02*
Y10833D01*
G01Y9917D02*
X633250Y10333D01*
X633667Y10667D01*
X634250Y10833D01*
X634833Y10667D01*
X635250Y10333D01*
X635500Y9917D01*
Y7500D01*
G01Y9917D02*
X635750Y10333D01*
X636167Y10667D01*
X636750Y10833D01*
X637333Y10667D01*
X637750Y10333D01*
X638000Y9833D01*
Y7500D01*
G01X644533D02*
Y12500D01*
X646700Y8333D01*
X648867Y12500D01*
Y7500D01*
G01X653800D02*
Y10833D01*
G01Y10250D02*
X653467Y10583D01*
X652967Y10750D01*
X652383Y10833D01*
X651800Y10667D01*
X651300Y10333D01*
X650967Y9833D01*
X650800Y9167D01*
X650967Y8500D01*
X651300Y8000D01*
X651800Y7667D01*
X652383Y7500D01*
X652967Y7583D01*
X653467Y7833D01*
X653800Y8167D01*
G01X656650Y10833D02*
X659150Y7500D01*
G01Y10833D02*
X656650Y7500D01*
G01X663917Y5833D02*
X664750Y6667D01*
X665167Y7500D01*
Y10833D01*
X664750Y11667D01*
X663917Y12500D01*
G01X609167Y18000D02*
X605833Y19667D01*
X609167Y21333D01*
G01X612017Y18917D02*
X614183D01*
G01Y20417D02*
X612017D01*
G01X618700Y23000D02*
X618033Y22833D01*
X617533Y22417D01*
X617200Y21917D01*
X616950Y21250D01*
X616867Y20500D01*
X616950Y19750D01*
X617200Y19083D01*
X617533Y18583D01*
X618033Y18167D01*
X618700Y18000D01*
X619367Y18167D01*
X619867Y18583D01*
X620200Y19083D01*
X620450Y19750D01*
X620533Y20500D01*
X620450Y21250D01*
X620200Y21917D01*
X619867Y22417D01*
X619367Y22833D01*
X618700Y23000D01*
G01X624300Y17833D02*
X624133Y17917D01*
Y18083D01*
X624300Y18167D01*
X624467Y18083D01*
Y17917D01*
X624300Y17833D01*
G01X629733Y18000D02*
X629900Y19083D01*
X630150Y20000D01*
X630483Y20833D01*
X630900Y21750D01*
X631567Y23000D01*
X628233D01*
G01X633667Y18750D02*
X634167Y18333D01*
X634750Y18083D01*
X635500Y18000D01*
X636250Y18167D01*
X636833Y18500D01*
X637250Y19083D01*
X637333Y19750D01*
X637167Y20417D01*
X636750Y20833D01*
X636167Y21167D01*
X635583Y21250D01*
X635000Y21167D01*
X634250Y20833D01*
X634500Y23000D01*
X636750D01*
G01X639600Y17833D02*
X642600Y23000D01*
G01X639600D02*
X639100Y22833D01*
X638850Y22583D01*
X638683Y22083D01*
X638850Y21583D01*
X639100Y21333D01*
X639600Y21167D01*
X640100Y21333D01*
X640350Y21583D01*
X640517Y22083D01*
X640350Y22583D01*
X640100Y22833D01*
X639600Y23000D01*
G01X642600Y19667D02*
X642100Y19500D01*
X641850Y19250D01*
X641683Y18750D01*
X641850Y18250D01*
X642100Y18000D01*
X642600Y17833D01*
X643100Y18000D01*
X643350Y18250D01*
X643517Y18750D01*
X643350Y19250D01*
X643100Y19500D01*
X642600Y19667D01*
G01X595500Y500D02*
Y445500D01*
G01X606583Y139667D02*
X608583D01*
G01X607500Y140750D02*
Y138583D01*
G01X611600Y137833D02*
X614600Y143000D01*
G01X617617Y139667D02*
X619783D01*
G01X624300Y138000D02*
Y143000D01*
X623300Y142000D01*
G01Y138000D02*
X625300D01*
G01X627400D02*
Y141333D01*
G01Y140417D02*
X627650Y140833D01*
X628067Y141167D01*
X628650Y141333D01*
X629233Y141167D01*
X629650Y140833D01*
X629900Y140417D01*
Y138000D01*
G01Y140417D02*
X630150Y140833D01*
X630567Y141167D01*
X631150Y141333D01*
X631733Y141167D01*
X632150Y140833D01*
X632400Y140333D01*
Y138000D01*
G01X635500Y141333D02*
Y138000D01*
G01Y142667D02*
X635333Y142750D01*
Y142917D01*
X635500Y143000D01*
X635667Y142917D01*
Y142750D01*
X635500Y142667D01*
G01X641100Y138000D02*
Y143000D01*
G01X607500Y126500D02*
X606833Y126333D01*
X606333Y125917D01*
X606000Y125417D01*
X605750Y124750D01*
X605667Y124000D01*
X605750Y123250D01*
X606000Y122583D01*
X606333Y122083D01*
X606833Y121667D01*
X607500Y121500D01*
X608167Y121667D01*
X608667Y122083D01*
X609000Y122583D01*
X609250Y123250D01*
X609333Y124000D01*
X609250Y124750D01*
X609000Y125417D01*
X608667Y125917D01*
X608167Y126333D01*
X607500Y126500D01*
G01X613100Y121333D02*
X612933Y121417D01*
Y121583D01*
X613100Y121667D01*
X613267Y121583D01*
Y121417D01*
X613100Y121333D01*
G01X616867Y122500D02*
X617367Y121917D01*
X618033Y121583D01*
X618783Y121500D01*
X619450Y121583D01*
X620117Y122000D01*
X620533Y122500D01*
X620617Y123000D01*
X620450Y123583D01*
X619867Y124000D01*
X619283Y124167D01*
X618533D01*
G01X619283D02*
X619783Y124417D01*
X620200Y124833D01*
X620367Y125333D01*
X620200Y125833D01*
X619783Y126250D01*
X619033Y126500D01*
X618283Y126417D01*
X617533Y126083D01*
G01X621800Y123167D02*
X622633Y124833D01*
X623467D01*
X625133Y121500D01*
X625967D01*
X626800Y123167D01*
G01X629900Y126500D02*
X629233Y126333D01*
X628733Y125917D01*
X628400Y125417D01*
X628150Y124750D01*
X628067Y124000D01*
X628150Y123250D01*
X628400Y122583D01*
X628733Y122083D01*
X629233Y121667D01*
X629900Y121500D01*
X630567Y121667D01*
X631067Y122083D01*
X631400Y122583D01*
X631650Y123250D01*
X631733Y124000D01*
X631650Y124750D01*
X631400Y125417D01*
X631067Y125917D01*
X630567Y126333D01*
X629900Y126500D01*
G01X635500Y121333D02*
X635333Y121417D01*
Y121583D01*
X635500Y121667D01*
X635667Y121583D01*
Y121417D01*
X635500Y121333D01*
G01X640933Y121500D02*
X641100Y122583D01*
X641350Y123500D01*
X641683Y124333D01*
X642100Y125250D01*
X642767Y126500D01*
X639433D01*
G01X644200Y121500D02*
Y124833D01*
G01Y123917D02*
X644450Y124333D01*
X644867Y124667D01*
X645450Y124833D01*
X646033Y124667D01*
X646450Y124333D01*
X646700Y123917D01*
Y121500D01*
G01Y123917D02*
X646950Y124333D01*
X647367Y124667D01*
X647950Y124833D01*
X648533Y124667D01*
X648950Y124333D01*
X649200Y123833D01*
Y121500D01*
G01X652300Y124833D02*
Y121500D01*
G01Y126167D02*
X652133Y126250D01*
Y126417D01*
X652300Y126500D01*
X652467Y126417D01*
Y126250D01*
X652300Y126167D01*
G01X657900Y121500D02*
Y126500D01*
G01X607500Y113000D02*
X606833Y112833D01*
X606333Y112417D01*
X606000Y111917D01*
X605750Y111250D01*
X605667Y110500D01*
X605750Y109750D01*
X606000Y109083D01*
X606333Y108583D01*
X606833Y108167D01*
X607500Y108000D01*
X608167Y108167D01*
X608667Y108583D01*
X609000Y109083D01*
X609250Y109750D01*
X609333Y110500D01*
X609250Y111250D01*
X609000Y111917D01*
X608667Y112417D01*
X608167Y112833D01*
X607500Y113000D01*
G01X613100Y107833D02*
X612933Y107917D01*
Y108083D01*
X613100Y108167D01*
X613267Y108083D01*
Y107917D01*
X613100Y107833D01*
G01X616867Y109000D02*
X617367Y108417D01*
X618033Y108083D01*
X618783Y108000D01*
X619450Y108083D01*
X620117Y108500D01*
X620533Y109000D01*
X620617Y109500D01*
X620450Y110083D01*
X619867Y110500D01*
X619283Y110667D01*
X618533D01*
G01X619283D02*
X619783Y110917D01*
X620200Y111333D01*
X620367Y111833D01*
X620200Y112333D01*
X619783Y112750D01*
X619033Y113000D01*
X618283Y112917D01*
X617533Y112583D01*
G01X621800Y109667D02*
X622633Y111333D01*
X623467D01*
X625133Y108000D01*
X625967D01*
X626800Y109667D01*
G01X629900Y113000D02*
X629233Y112833D01*
X628733Y112417D01*
X628400Y111917D01*
X628150Y111250D01*
X628067Y110500D01*
X628150Y109750D01*
X628400Y109083D01*
X628733Y108583D01*
X629233Y108167D01*
X629900Y108000D01*
X630567Y108167D01*
X631067Y108583D01*
X631400Y109083D01*
X631650Y109750D01*
X631733Y110500D01*
X631650Y111250D01*
X631400Y111917D01*
X631067Y112417D01*
X630567Y112833D01*
X629900Y113000D01*
G01X635500Y107833D02*
X635333Y107917D01*
Y108083D01*
X635500Y108167D01*
X635667Y108083D01*
Y107917D01*
X635500Y107833D01*
G01X640933Y108000D02*
X641100Y109083D01*
X641350Y110000D01*
X641683Y110833D01*
X642100Y111750D01*
X642767Y113000D01*
X639433D01*
G01X644200Y108000D02*
Y111333D01*
G01Y110417D02*
X644450Y110833D01*
X644867Y111167D01*
X645450Y111333D01*
X646033Y111167D01*
X646450Y110833D01*
X646700Y110417D01*
Y108000D01*
G01Y110417D02*
X646950Y110833D01*
X647367Y111167D01*
X647950Y111333D01*
X648533Y111167D01*
X648950Y110833D01*
X649200Y110333D01*
Y108000D01*
G01X652300Y111333D02*
Y108000D01*
G01Y112667D02*
X652133Y112750D01*
Y112917D01*
X652300Y113000D01*
X652467Y112917D01*
Y112750D01*
X652300Y112667D01*
G01X657900Y108000D02*
Y113000D01*
G01X609167Y93000D02*
X605833Y94667D01*
X609167Y96333D01*
G01X612017Y93917D02*
X614183D01*
G01Y95417D02*
X612017D01*
G01X618700Y93000D02*
Y98000D01*
X617700Y97000D01*
G01Y93000D02*
X619700D01*
G01X624300Y92833D02*
X624133Y92917D01*
Y93083D01*
X624300Y93167D01*
X624467Y93083D01*
Y92917D01*
X624300Y92833D01*
G01X630900Y93000D02*
Y98000D01*
X627817Y94417D01*
X631983D01*
G01X633000Y93000D02*
Y96333D01*
G01Y95417D02*
X633250Y95833D01*
X633667Y96167D01*
X634250Y96333D01*
X634833Y96167D01*
X635250Y95833D01*
X635500Y95417D01*
Y93000D01*
G01Y95417D02*
X635750Y95833D01*
X636167Y96167D01*
X636750Y96333D01*
X637333Y96167D01*
X637750Y95833D01*
X638000Y95333D01*
Y93000D01*
G01X641100Y96333D02*
Y93000D01*
G01Y97667D02*
X640933Y97750D01*
Y97917D01*
X641100Y98000D01*
X641267Y97917D01*
Y97750D01*
X641100Y97667D01*
G01X646700Y93000D02*
Y98000D01*
G01X605583Y76500D02*
Y81500D01*
X609417Y76500D01*
Y81500D01*
G01X611600Y76333D02*
X614600Y81500D01*
G01X616617Y76500D02*
X618700Y81500D01*
X620783Y76500D01*
G01X620033Y78250D02*
X617367D01*
G01X606583Y214667D02*
X608583D01*
G01X607500Y215750D02*
Y213583D01*
G01X611600Y212833D02*
X614600Y218000D01*
G01X617617Y214667D02*
X619783D01*
G01X624300Y213000D02*
Y218000D01*
X623300Y217000D01*
G01Y213000D02*
X625300D01*
G01X628067Y213750D02*
X628567Y213333D01*
X629150Y213083D01*
X629900Y213000D01*
X630650Y213167D01*
X631233Y213500D01*
X631650Y214083D01*
X631733Y214750D01*
X631567Y215417D01*
X631150Y215833D01*
X630567Y216167D01*
X629983Y216250D01*
X629400Y216167D01*
X628650Y215833D01*
X628900Y218000D01*
X631150D01*
G01X634000Y212833D02*
X637000Y218000D01*
G01X634000D02*
X633500Y217833D01*
X633250Y217583D01*
X633083Y217083D01*
X633250Y216583D01*
X633500Y216333D01*
X634000Y216167D01*
X634500Y216333D01*
X634750Y216583D01*
X634917Y217083D01*
X634750Y217583D01*
X634500Y217833D01*
X634000Y218000D01*
G01X637000Y214667D02*
X636500Y214500D01*
X636250Y214250D01*
X636083Y213750D01*
X636250Y213250D01*
X636500Y213000D01*
X637000Y212833D01*
X637500Y213000D01*
X637750Y213250D01*
X637917Y213750D01*
X637750Y214250D01*
X637500Y214500D01*
X637000Y214667D01*
G01X606583Y229667D02*
X608583D01*
G01X607500Y230750D02*
Y228583D01*
G01X611600Y227833D02*
X614600Y233000D01*
G01X617617Y229667D02*
X619783D01*
G01X624300Y228000D02*
Y233000D01*
X623300Y232000D01*
G01Y228000D02*
X625300D01*
G01X627400D02*
Y231333D01*
G01Y230417D02*
X627650Y230833D01*
X628067Y231167D01*
X628650Y231333D01*
X629233Y231167D01*
X629650Y230833D01*
X629900Y230417D01*
Y228000D01*
G01Y230417D02*
X630150Y230833D01*
X630567Y231167D01*
X631150Y231333D01*
X631733Y231167D01*
X632150Y230833D01*
X632400Y230333D01*
Y228000D01*
G01X635500Y231333D02*
Y228000D01*
G01Y232667D02*
X635333Y232750D01*
Y232917D01*
X635500Y233000D01*
X635667Y232917D01*
Y232750D01*
X635500Y232667D01*
G01X641100Y228000D02*
Y233000D01*
G01X606583Y195167D02*
X608583D01*
G01X607500Y196250D02*
Y194083D01*
G01X611600Y193333D02*
X614600Y198500D01*
G01X617617Y195167D02*
X619783D01*
G01X622717Y197667D02*
X623217Y198167D01*
X623800Y198417D01*
X624467Y198500D01*
X625300Y198333D01*
X625883Y197917D01*
X626050Y197417D01*
X625967Y196917D01*
X625633Y196500D01*
X623967Y195667D01*
X623217Y195083D01*
X622717Y194250D01*
X622550Y193500D01*
X626050D01*
G01X627400D02*
Y196833D01*
G01Y195917D02*
X627650Y196333D01*
X628067Y196667D01*
X628650Y196833D01*
X629233Y196667D01*
X629650Y196333D01*
X629900Y195917D01*
Y193500D01*
G01Y195917D02*
X630150Y196333D01*
X630567Y196667D01*
X631150Y196833D01*
X631733Y196667D01*
X632150Y196333D01*
X632400Y195833D01*
Y193500D01*
G01X635500Y196833D02*
Y193500D01*
G01Y198167D02*
X635333Y198250D01*
Y198417D01*
X635500Y198500D01*
X635667Y198417D01*
Y198250D01*
X635500Y198167D01*
G01X641100Y193500D02*
Y198500D01*
G01X606583Y171167D02*
X608583D01*
G01X607500Y172250D02*
Y170083D01*
G01X611600Y169333D02*
X614600Y174500D01*
G01X617617Y171167D02*
X619783D01*
G01X624300Y169500D02*
Y174500D01*
X623300Y173500D01*
G01Y169500D02*
X625300D01*
G01X627400D02*
Y172833D01*
G01Y171917D02*
X627650Y172333D01*
X628067Y172667D01*
X628650Y172833D01*
X629233Y172667D01*
X629650Y172333D01*
X629900Y171917D01*
Y169500D01*
G01Y171917D02*
X630150Y172333D01*
X630567Y172667D01*
X631150Y172833D01*
X631733Y172667D01*
X632150Y172333D01*
X632400Y171833D01*
Y169500D01*
G01X635500Y172833D02*
Y169500D01*
G01Y174167D02*
X635333Y174250D01*
Y174417D01*
X635500Y174500D01*
X635667Y174417D01*
Y174250D01*
X635500Y174167D01*
G01X641100Y169500D02*
Y174500D01*
G01X606583Y154667D02*
X608583D01*
G01X607500Y155750D02*
Y153583D01*
G01X611600Y152833D02*
X614600Y158000D01*
G01X617617Y154667D02*
X619783D01*
G01X622717Y157167D02*
X623217Y157667D01*
X623800Y157917D01*
X624467Y158000D01*
X625300Y157833D01*
X625883Y157417D01*
X626050Y156917D01*
X625967Y156417D01*
X625633Y156000D01*
X623967Y155167D01*
X623217Y154583D01*
X622717Y153750D01*
X622550Y153000D01*
X626050D01*
G01X627400D02*
Y156333D01*
G01Y155417D02*
X627650Y155833D01*
X628067Y156167D01*
X628650Y156333D01*
X629233Y156167D01*
X629650Y155833D01*
X629900Y155417D01*
Y153000D01*
G01Y155417D02*
X630150Y155833D01*
X630567Y156167D01*
X631150Y156333D01*
X631733Y156167D01*
X632150Y155833D01*
X632400Y155333D01*
Y153000D01*
G01X635500Y156333D02*
Y153000D01*
G01Y157667D02*
X635333Y157750D01*
Y157917D01*
X635500Y158000D01*
X635667Y157917D01*
Y157750D01*
X635500Y157667D01*
G01X641100Y153000D02*
Y158000D01*
G01X605833Y315000D02*
X609167Y316667D01*
X605833Y318333D01*
G01X612017Y315917D02*
X614183D01*
G01Y317417D02*
X612017D01*
G01X618700Y315000D02*
Y320000D01*
X617700Y319000D01*
G01Y315000D02*
X619700D01*
G01X624300Y314833D02*
X624133Y314917D01*
Y315083D01*
X624300Y315167D01*
X624467Y315083D01*
Y314917D01*
X624300Y314833D01*
G01X628067Y316000D02*
X628567Y315417D01*
X629233Y315083D01*
X629983Y315000D01*
X630650Y315083D01*
X631317Y315500D01*
X631733Y316000D01*
X631817Y316500D01*
X631650Y317083D01*
X631067Y317500D01*
X630483Y317667D01*
X629733D01*
G01X630483D02*
X630983Y317917D01*
X631400Y318333D01*
X631567Y318833D01*
X631400Y319333D01*
X630983Y319750D01*
X630233Y320000D01*
X629483Y319917D01*
X628733Y319583D01*
G01X633000Y315000D02*
Y318333D01*
G01Y317417D02*
X633250Y317833D01*
X633667Y318167D01*
X634250Y318333D01*
X634833Y318167D01*
X635250Y317833D01*
X635500Y317417D01*
Y315000D01*
G01Y317417D02*
X635750Y317833D01*
X636167Y318167D01*
X636750Y318333D01*
X637333Y318167D01*
X637750Y317833D01*
X638000Y317333D01*
Y315000D01*
G01X641100Y318333D02*
Y315000D01*
G01Y319667D02*
X640933Y319750D01*
Y319917D01*
X641100Y320000D01*
X641267Y319917D01*
Y319750D01*
X641100Y319667D01*
G01X646700Y315000D02*
Y320000D01*
G01X605833Y292500D02*
X609167Y294167D01*
X605833Y295833D01*
G01X612017Y293417D02*
X614183D01*
G01Y294917D02*
X612017D01*
G01X618700Y292500D02*
Y297500D01*
X617700Y296500D01*
G01Y292500D02*
X619700D01*
G01X624300Y292333D02*
X624133Y292417D01*
Y292583D01*
X624300Y292667D01*
X624467Y292583D01*
Y292417D01*
X624300Y292333D01*
G01X628067Y293250D02*
X628567Y292833D01*
X629150Y292583D01*
X629900Y292500D01*
X630650Y292667D01*
X631233Y293000D01*
X631650Y293583D01*
X631733Y294250D01*
X631567Y294917D01*
X631150Y295333D01*
X630567Y295667D01*
X629983Y295750D01*
X629400Y295667D01*
X628650Y295333D01*
X628900Y297500D01*
X631150D01*
G01X633000Y292500D02*
Y295833D01*
G01Y294917D02*
X633250Y295333D01*
X633667Y295667D01*
X634250Y295833D01*
X634833Y295667D01*
X635250Y295333D01*
X635500Y294917D01*
Y292500D01*
G01Y294917D02*
X635750Y295333D01*
X636167Y295667D01*
X636750Y295833D01*
X637333Y295667D01*
X637750Y295333D01*
X638000Y294833D01*
Y292500D01*
G01X641100Y295833D02*
Y292500D01*
G01Y297167D02*
X640933Y297250D01*
Y297417D01*
X641100Y297500D01*
X641267Y297417D01*
Y297250D01*
X641100Y297167D01*
G01X646700Y292500D02*
Y297500D01*
G01X605833Y273000D02*
X609167Y274667D01*
X605833Y276333D01*
G01X612017Y273917D02*
X614183D01*
G01Y275417D02*
X612017D01*
G01X618700Y273000D02*
Y278000D01*
X617700Y277000D01*
G01Y273000D02*
X619700D01*
G01X624300Y272833D02*
X624133Y272917D01*
Y273083D01*
X624300Y273167D01*
X624467Y273083D01*
Y272917D01*
X624300Y272833D01*
G01X629900Y278000D02*
X629233Y277833D01*
X628733Y277417D01*
X628400Y276917D01*
X628150Y276250D01*
X628067Y275500D01*
X628150Y274750D01*
X628400Y274083D01*
X628733Y273583D01*
X629233Y273167D01*
X629900Y273000D01*
X630567Y273167D01*
X631067Y273583D01*
X631400Y274083D01*
X631650Y274750D01*
X631733Y275500D01*
X631650Y276250D01*
X631400Y276917D01*
X631067Y277417D01*
X630567Y277833D01*
X629900Y278000D01*
G01X633000Y273000D02*
Y276333D01*
G01Y275417D02*
X633250Y275833D01*
X633667Y276167D01*
X634250Y276333D01*
X634833Y276167D01*
X635250Y275833D01*
X635500Y275417D01*
Y273000D01*
G01Y275417D02*
X635750Y275833D01*
X636167Y276167D01*
X636750Y276333D01*
X637333Y276167D01*
X637750Y275833D01*
X638000Y275333D01*
Y273000D01*
G01X641100Y276333D02*
Y273000D01*
G01Y277667D02*
X640933Y277750D01*
Y277917D01*
X641100Y278000D01*
X641267Y277917D01*
Y277750D01*
X641100Y277667D01*
G01X646700Y273000D02*
Y278000D01*
G01X606583Y244667D02*
X608583D01*
G01X607500Y245750D02*
Y243583D01*
G01X611600Y242833D02*
X614600Y248000D01*
G01X617617Y244667D02*
X619783D01*
G01X622717Y247167D02*
X623217Y247667D01*
X623800Y247917D01*
X624467Y248000D01*
X625300Y247833D01*
X625883Y247417D01*
X626050Y246917D01*
X625967Y246417D01*
X625633Y246000D01*
X623967Y245167D01*
X623217Y244583D01*
X622717Y243750D01*
X622550Y243000D01*
X626050D01*
G01X629900Y248000D02*
X629233Y247833D01*
X628733Y247417D01*
X628400Y246917D01*
X628150Y246250D01*
X628067Y245500D01*
X628150Y244750D01*
X628400Y244083D01*
X628733Y243583D01*
X629233Y243167D01*
X629900Y243000D01*
X630567Y243167D01*
X631067Y243583D01*
X631400Y244083D01*
X631650Y244750D01*
X631733Y245500D01*
X631650Y246250D01*
X631400Y246917D01*
X631067Y247417D01*
X630567Y247833D01*
X629900Y248000D01*
G01X634000Y242833D02*
X637000Y248000D01*
G01X634000D02*
X633500Y247833D01*
X633250Y247583D01*
X633083Y247083D01*
X633250Y246583D01*
X633500Y246333D01*
X634000Y246167D01*
X634500Y246333D01*
X634750Y246583D01*
X634917Y247083D01*
X634750Y247583D01*
X634500Y247833D01*
X634000Y248000D01*
G01X637000Y244667D02*
X636500Y244500D01*
X636250Y244250D01*
X636083Y243750D01*
X636250Y243250D01*
X636500Y243000D01*
X637000Y242833D01*
X637500Y243000D01*
X637750Y243250D01*
X637917Y243750D01*
X637750Y244250D01*
X637500Y244500D01*
X637000Y244667D01*
G01X606583Y259667D02*
X608583D01*
G01X607500Y260750D02*
Y258583D01*
G01X611600Y257833D02*
X614600Y263000D01*
G01X617617Y259667D02*
X619783D01*
G01X622467Y259000D02*
X622967Y258417D01*
X623633Y258083D01*
X624383Y258000D01*
X625050Y258083D01*
X625717Y258500D01*
X626133Y259000D01*
X626217Y259500D01*
X626050Y260083D01*
X625467Y260500D01*
X624883Y260667D01*
X624133D01*
G01X624883D02*
X625383Y260917D01*
X625800Y261333D01*
X625967Y261833D01*
X625800Y262333D01*
X625383Y262750D01*
X624633Y263000D01*
X623883Y262917D01*
X623133Y262583D01*
G01X627400Y258000D02*
Y261333D01*
G01Y260417D02*
X627650Y260833D01*
X628067Y261167D01*
X628650Y261333D01*
X629233Y261167D01*
X629650Y260833D01*
X629900Y260417D01*
Y258000D01*
G01Y260417D02*
X630150Y260833D01*
X630567Y261167D01*
X631150Y261333D01*
X631733Y261167D01*
X632150Y260833D01*
X632400Y260333D01*
Y258000D01*
G01X635500Y261333D02*
Y258000D01*
G01Y262667D02*
X635333Y262750D01*
Y262917D01*
X635500Y263000D01*
X635667Y262917D01*
Y262750D01*
X635500Y262667D01*
G01X641100Y258000D02*
Y263000D01*
G01X608583Y387500D02*
Y392500D01*
X612417Y387500D01*
Y392500D01*
G01X614600Y387333D02*
X617600Y392500D01*
G01X619617Y387500D02*
X621700Y392500D01*
X623783Y387500D01*
G01X623033Y389250D02*
X620367D01*
G01X607000Y423000D02*
Y427250D01*
X607167Y427667D01*
X607500Y427917D01*
X608000Y428000D01*
X608500Y427833D01*
X608750Y427417D01*
G01X607750Y426000D02*
X606083D01*
G01X613100Y423000D02*
X612600Y423083D01*
X612100Y423417D01*
X611767Y424000D01*
X611600Y424667D01*
X611767Y425333D01*
X612100Y425917D01*
X612600Y426250D01*
X613100Y426333D01*
X613600Y426250D01*
X614100Y425917D01*
X614433Y425333D01*
X614517Y424667D01*
X614433Y424000D01*
X614100Y423417D01*
X613600Y423083D01*
X613100Y423000D01*
G01X618700D02*
Y428000D01*
G01X624300Y423000D02*
Y428000D01*
G01X629900Y423000D02*
X629400Y423083D01*
X628900Y423417D01*
X628567Y424000D01*
X628400Y424667D01*
X628567Y425333D01*
X628900Y425917D01*
X629400Y426250D01*
X629900Y426333D01*
X630400Y426250D01*
X630900Y425917D01*
X631233Y425333D01*
X631317Y424667D01*
X631233Y424000D01*
X630900Y423417D01*
X630400Y423083D01*
X629900Y423000D01*
G01X633417Y426333D02*
X634417Y423000D01*
X635500Y426333D01*
X636583Y423000D01*
X637583Y426333D01*
G01X648200Y428000D02*
Y423000D01*
G01Y423750D02*
X647867Y423333D01*
X647367Y423083D01*
X646783Y423000D01*
X646117Y423167D01*
X645617Y423583D01*
X645283Y424083D01*
X645200Y424667D01*
X645283Y425250D01*
X645617Y425750D01*
X646117Y426167D01*
X646783Y426333D01*
X647367Y426250D01*
X647783Y426083D01*
X648200Y425750D01*
G01X651133Y423000D02*
Y426333D01*
G01Y425667D02*
X651550Y426000D01*
X651967Y426250D01*
X652550Y426333D01*
X652967Y426250D01*
X653467Y426000D01*
G01X659400Y423000D02*
Y426333D01*
G01Y425750D02*
X659067Y426083D01*
X658567Y426250D01*
X657983Y426333D01*
X657400Y426167D01*
X656900Y425833D01*
X656567Y425333D01*
X656400Y424667D01*
X656567Y424000D01*
X656900Y423500D01*
X657400Y423167D01*
X657983Y423000D01*
X658567Y423083D01*
X659067Y423333D01*
X659400Y423667D01*
G01X661417Y426333D02*
X662417Y423000D01*
X663500Y426333D01*
X664583Y423000D01*
X665583Y426333D01*
G01X669100D02*
Y423000D01*
G01Y427667D02*
X668933Y427750D01*
Y427917D01*
X669100Y428000D01*
X669267Y427917D01*
Y427750D01*
X669100Y427667D01*
G01X673283Y423000D02*
Y426333D01*
G01Y425500D02*
X673617Y425917D01*
X674117Y426250D01*
X674783Y426333D01*
X675367Y426250D01*
X675867Y425917D01*
X676117Y425333D01*
Y423000D01*
G01X679133Y421750D02*
X679717Y421417D01*
X680383Y421333D01*
X680967Y421417D01*
X681467Y421833D01*
X681800Y422417D01*
Y426333D01*
G01Y425667D02*
X681467Y426000D01*
X680967Y426250D01*
X680383Y426333D01*
X679717Y426167D01*
X679300Y425833D01*
X678967Y425250D01*
X678800Y424667D01*
X678883Y424167D01*
X679217Y423583D01*
X679717Y423167D01*
X680383Y423000D01*
X680883Y423083D01*
X681467Y423417D01*
X681800Y423750D01*
G01X686317Y421333D02*
X687150Y422167D01*
X687567Y423000D01*
Y426333D01*
X687150Y427167D01*
X686317Y428000D01*
G01X652083Y434833D02*
X651250Y435667D01*
X650833Y436500D01*
Y439833D01*
X651250Y440667D01*
X652083Y441500D01*
G01X658100Y436500D02*
X657600Y436583D01*
X657100Y436917D01*
X656767Y437500D01*
X656600Y438167D01*
X656767Y438833D01*
X657100Y439417D01*
X657600Y439750D01*
X658100Y439833D01*
X658600Y439750D01*
X659100Y439417D01*
X659433Y438833D01*
X659517Y438167D01*
X659433Y437500D01*
X659100Y436917D01*
X658600Y436583D01*
X658100Y436500D01*
G01X662533D02*
Y439833D01*
G01Y439167D02*
X662950Y439500D01*
X663367Y439750D01*
X663950Y439833D01*
X664367Y439750D01*
X664867Y439500D01*
G01X606583Y436667D02*
X608583D01*
G01X607500Y437750D02*
Y435583D01*
G01X611600Y434833D02*
X614600Y440000D01*
G01X617617Y436667D02*
X619783D01*
G01X622467Y435750D02*
X622967Y435333D01*
X623550Y435083D01*
X624300Y435000D01*
X625050Y435167D01*
X625633Y435500D01*
X626050Y436083D01*
X626133Y436750D01*
X625967Y437417D01*
X625550Y437833D01*
X624967Y438167D01*
X624383Y438250D01*
X623800Y438167D01*
X623050Y437833D01*
X623300Y440000D01*
X625550D01*
G01X627400Y435000D02*
Y438333D01*
G01Y437417D02*
X627650Y437833D01*
X628067Y438167D01*
X628650Y438333D01*
X629233Y438167D01*
X629650Y437833D01*
X629900Y437417D01*
Y435000D01*
G01Y437417D02*
X630150Y437833D01*
X630567Y438167D01*
X631150Y438333D01*
X631733Y438167D01*
X632150Y437833D01*
X632400Y437333D01*
Y435000D01*
G01X635500Y438333D02*
Y435000D01*
G01Y439667D02*
X635333Y439750D01*
Y439917D01*
X635500Y440000D01*
X635667Y439917D01*
Y439750D01*
X635500Y439667D01*
G01X641100Y435000D02*
Y440000D01*
G01X607500Y448500D02*
Y453500D01*
X606500Y452500D01*
G01Y448500D02*
X608500D01*
G01X613100Y448333D02*
X612933Y448417D01*
Y448583D01*
X613100Y448667D01*
X613267Y448583D01*
Y448417D01*
X613100Y448333D01*
G01X618700Y453500D02*
X618033Y453333D01*
X617533Y452917D01*
X617200Y452417D01*
X616950Y451750D01*
X616867Y451000D01*
X616950Y450250D01*
X617200Y449583D01*
X617533Y449083D01*
X618033Y448667D01*
X618700Y448500D01*
X619367Y448667D01*
X619867Y449083D01*
X620200Y449583D01*
X620450Y450250D01*
X620533Y451000D01*
X620450Y451750D01*
X620200Y452417D01*
X619867Y452917D01*
X619367Y453333D01*
X618700Y453500D01*
G01X621800Y448500D02*
Y451833D01*
G01Y450917D02*
X622050Y451333D01*
X622467Y451667D01*
X623050Y451833D01*
X623633Y451667D01*
X624050Y451333D01*
X624300Y450917D01*
Y448500D01*
G01Y450917D02*
X624550Y451333D01*
X624967Y451667D01*
X625550Y451833D01*
X626133Y451667D01*
X626550Y451333D01*
X626800Y450833D01*
Y448500D01*
G01X629900Y451833D02*
Y448500D01*
G01Y453167D02*
X629733Y453250D01*
Y453417D01*
X629900Y453500D01*
X630067Y453417D01*
Y453250D01*
X629900Y453167D01*
G01X635500Y448500D02*
Y453500D01*
G01X644200Y448500D02*
Y451833D01*
G01Y450917D02*
X644450Y451333D01*
X644867Y451667D01*
X645450Y451833D01*
X646033Y451667D01*
X646450Y451333D01*
X646700Y450917D01*
Y448500D01*
G01Y450917D02*
X646950Y451333D01*
X647367Y451667D01*
X647950Y451833D01*
X648533Y451667D01*
X648950Y451333D01*
X649200Y450833D01*
Y448500D01*
G01X653800D02*
Y451833D01*
G01Y451250D02*
X653467Y451583D01*
X652967Y451750D01*
X652383Y451833D01*
X651800Y451667D01*
X651300Y451333D01*
X650967Y450833D01*
X650800Y450167D01*
X650967Y449500D01*
X651300Y449000D01*
X651800Y448667D01*
X652383Y448500D01*
X652967Y448583D01*
X653467Y448833D01*
X653800Y449167D01*
G01X656650Y451833D02*
X659150Y448500D01*
G01Y451833D02*
X656650Y448500D01*
G01X606583Y468167D02*
X608583D01*
G01X607500Y469250D02*
Y467083D01*
G01X611600Y466333D02*
X614600Y471500D01*
G01X617617Y468167D02*
X619783D01*
G01X622467Y467250D02*
X622967Y466833D01*
X623550Y466583D01*
X624300Y466500D01*
X625050Y466667D01*
X625633Y467000D01*
X626050Y467583D01*
X626133Y468250D01*
X625967Y468917D01*
X625550Y469333D01*
X624967Y469667D01*
X624383Y469750D01*
X623800Y469667D01*
X623050Y469333D01*
X623300Y471500D01*
X625550D01*
G01X627400Y466500D02*
Y469833D01*
G01Y468917D02*
X627650Y469333D01*
X628067Y469667D01*
X628650Y469833D01*
X629233Y469667D01*
X629650Y469333D01*
X629900Y468917D01*
Y466500D01*
G01Y468917D02*
X630150Y469333D01*
X630567Y469667D01*
X631150Y469833D01*
X631733Y469667D01*
X632150Y469333D01*
X632400Y468833D01*
Y466500D01*
G01X635500Y469833D02*
Y466500D01*
G01Y471167D02*
X635333Y471250D01*
Y471417D01*
X635500Y471500D01*
X635667Y471417D01*
Y471250D01*
X635500Y471167D01*
G01X641100Y466500D02*
Y471500D01*
G01X606583Y483167D02*
X608583D01*
G01X607500Y484250D02*
Y482083D01*
G01X611600Y481333D02*
X614600Y486500D01*
G01X617617Y483167D02*
X619783D01*
G01X622467Y482250D02*
X622967Y481833D01*
X623550Y481583D01*
X624300Y481500D01*
X625050Y481667D01*
X625633Y482000D01*
X626050Y482583D01*
X626133Y483250D01*
X625967Y483917D01*
X625550Y484333D01*
X624967Y484667D01*
X624383Y484750D01*
X623800Y484667D01*
X623050Y484333D01*
X623300Y486500D01*
X625550D01*
G01X627400Y481500D02*
Y484833D01*
G01Y483917D02*
X627650Y484333D01*
X628067Y484667D01*
X628650Y484833D01*
X629233Y484667D01*
X629650Y484333D01*
X629900Y483917D01*
Y481500D01*
G01Y483917D02*
X630150Y484333D01*
X630567Y484667D01*
X631150Y484833D01*
X631733Y484667D01*
X632150Y484333D01*
X632400Y483833D01*
Y481500D01*
G01X635500Y484833D02*
Y481500D01*
G01Y486167D02*
X635333Y486250D01*
Y486417D01*
X635500Y486500D01*
X635667Y486417D01*
Y486250D01*
X635500Y486167D01*
G01X641100Y481500D02*
Y486500D01*
G01X595500Y679000D02*
Y445500D01*
G01X606583Y558167D02*
X608583D01*
G01X607500Y559250D02*
Y557083D01*
G01X611600Y556333D02*
X614600Y561500D01*
G01X617617Y558167D02*
X619783D01*
G01X622717Y560667D02*
X623217Y561167D01*
X623800Y561417D01*
X624467Y561500D01*
X625300Y561333D01*
X625883Y560917D01*
X626050Y560417D01*
X625967Y559917D01*
X625633Y559500D01*
X623967Y558667D01*
X623217Y558083D01*
X622717Y557250D01*
X622550Y556500D01*
X626050D01*
G01X627400D02*
Y559833D01*
G01Y558917D02*
X627650Y559333D01*
X628067Y559667D01*
X628650Y559833D01*
X629233Y559667D01*
X629650Y559333D01*
X629900Y558917D01*
Y556500D01*
G01Y558917D02*
X630150Y559333D01*
X630567Y559667D01*
X631150Y559833D01*
X631733Y559667D01*
X632150Y559333D01*
X632400Y558833D01*
Y556500D01*
G01X635500Y559833D02*
Y556500D01*
G01Y561167D02*
X635333Y561250D01*
Y561417D01*
X635500Y561500D01*
X635667Y561417D01*
Y561250D01*
X635500Y561167D01*
G01X641100Y556500D02*
Y561500D01*
G01X606583Y498167D02*
X608583D01*
G01X607500Y499250D02*
Y497083D01*
G01X611600Y496333D02*
X614600Y501500D01*
G01X617617Y498167D02*
X619783D01*
G01X622717Y500667D02*
X623217Y501167D01*
X623800Y501417D01*
X624467Y501500D01*
X625300Y501333D01*
X625883Y500917D01*
X626050Y500417D01*
X625967Y499917D01*
X625633Y499500D01*
X623967Y498667D01*
X623217Y498083D01*
X622717Y497250D01*
X622550Y496500D01*
X626050D01*
G01X627400D02*
Y499833D01*
G01Y498917D02*
X627650Y499333D01*
X628067Y499667D01*
X628650Y499833D01*
X629233Y499667D01*
X629650Y499333D01*
X629900Y498917D01*
Y496500D01*
G01Y498917D02*
X630150Y499333D01*
X630567Y499667D01*
X631150Y499833D01*
X631733Y499667D01*
X632150Y499333D01*
X632400Y498833D01*
Y496500D01*
G01X635500Y499833D02*
Y496500D01*
G01Y501167D02*
X635333Y501250D01*
Y501417D01*
X635500Y501500D01*
X635667Y501417D01*
Y501250D01*
X635500Y501167D01*
G01X641100Y496500D02*
Y501500D01*
G01X606583Y513167D02*
X608583D01*
G01X607500Y514250D02*
Y512083D01*
G01X611267Y512500D02*
X611767Y511917D01*
X612433Y511583D01*
X613183Y511500D01*
X613850Y511583D01*
X614517Y512000D01*
X614933Y512500D01*
X615017Y513000D01*
X614850Y513583D01*
X614267Y514000D01*
X613683Y514167D01*
X612933D01*
G01X613683D02*
X614183Y514417D01*
X614600Y514833D01*
X614767Y515333D01*
X614600Y515833D01*
X614183Y516250D01*
X613433Y516500D01*
X612683Y516417D01*
X611933Y516083D01*
G01X617200Y511333D02*
X620200Y516500D01*
G01X623217Y513167D02*
X625383D01*
G01X629900Y516500D02*
X629233Y516333D01*
X628733Y515917D01*
X628400Y515417D01*
X628150Y514750D01*
X628067Y514000D01*
X628150Y513250D01*
X628400Y512583D01*
X628733Y512083D01*
X629233Y511667D01*
X629900Y511500D01*
X630567Y511667D01*
X631067Y512083D01*
X631400Y512583D01*
X631650Y513250D01*
X631733Y514000D01*
X631650Y514750D01*
X631400Y515417D01*
X631067Y515917D01*
X630567Y516333D01*
X629900Y516500D01*
G01X633000Y511500D02*
Y514833D01*
G01Y513917D02*
X633250Y514333D01*
X633667Y514667D01*
X634250Y514833D01*
X634833Y514667D01*
X635250Y514333D01*
X635500Y513917D01*
Y511500D01*
G01Y513917D02*
X635750Y514333D01*
X636167Y514667D01*
X636750Y514833D01*
X637333Y514667D01*
X637750Y514333D01*
X638000Y513833D01*
Y511500D01*
G01X641100Y514833D02*
Y511500D01*
G01Y516167D02*
X640933Y516250D01*
Y516417D01*
X641100Y516500D01*
X641267Y516417D01*
Y516250D01*
X641100Y516167D01*
G01X646700Y511500D02*
Y516500D01*
G01X606583Y528167D02*
X608583D01*
G01X607500Y529250D02*
Y527083D01*
G01X611600Y526333D02*
X614600Y531500D01*
G01X617617Y528167D02*
X619783D01*
G01X622717Y530667D02*
X623217Y531167D01*
X623800Y531417D01*
X624467Y531500D01*
X625300Y531333D01*
X625883Y530917D01*
X626050Y530417D01*
X625967Y529917D01*
X625633Y529500D01*
X623967Y528667D01*
X623217Y528083D01*
X622717Y527250D01*
X622550Y526500D01*
X626050D01*
G01X627400D02*
Y529833D01*
G01Y528917D02*
X627650Y529333D01*
X628067Y529667D01*
X628650Y529833D01*
X629233Y529667D01*
X629650Y529333D01*
X629900Y528917D01*
Y526500D01*
G01Y528917D02*
X630150Y529333D01*
X630567Y529667D01*
X631150Y529833D01*
X631733Y529667D01*
X632150Y529333D01*
X632400Y528833D01*
Y526500D01*
G01X635500Y529833D02*
Y526500D01*
G01Y531167D02*
X635333Y531250D01*
Y531417D01*
X635500Y531500D01*
X635667Y531417D01*
Y531250D01*
X635500Y531167D01*
G01X641100Y526500D02*
Y531500D01*
G01X606583Y541667D02*
X608583D01*
G01X607500Y542750D02*
Y540583D01*
G01X611600Y539833D02*
X614600Y545000D01*
G01X617617Y541667D02*
X619783D01*
G01X622467Y541000D02*
X622967Y540417D01*
X623633Y540083D01*
X624383Y540000D01*
X625050Y540083D01*
X625717Y540500D01*
X626133Y541000D01*
X626217Y541500D01*
X626050Y542083D01*
X625467Y542500D01*
X624883Y542667D01*
X624133D01*
G01X624883D02*
X625383Y542917D01*
X625800Y543333D01*
X625967Y543833D01*
X625800Y544333D01*
X625383Y544750D01*
X624633Y545000D01*
X623883Y544917D01*
X623133Y544583D01*
G01X627400Y540000D02*
Y543333D01*
G01Y542417D02*
X627650Y542833D01*
X628067Y543167D01*
X628650Y543333D01*
X629233Y543167D01*
X629650Y542833D01*
X629900Y542417D01*
Y540000D01*
G01Y542417D02*
X630150Y542833D01*
X630567Y543167D01*
X631150Y543333D01*
X631733Y543167D01*
X632150Y542833D01*
X632400Y542333D01*
Y540000D01*
G01X635500Y543333D02*
Y540000D01*
G01Y544667D02*
X635333Y544750D01*
Y544917D01*
X635500Y545000D01*
X635667Y544917D01*
Y544750D01*
X635500Y544667D01*
G01X641100Y540000D02*
Y545000D01*
G01X606583Y603167D02*
X608583D01*
G01X607500Y604250D02*
Y602083D01*
G01X611600Y601333D02*
X614600Y606500D01*
G01X617617Y603167D02*
X619783D01*
G01X622467Y602500D02*
X622967Y601917D01*
X623633Y601583D01*
X624383Y601500D01*
X625050Y601583D01*
X625717Y602000D01*
X626133Y602500D01*
X626217Y603000D01*
X626050Y603583D01*
X625467Y604000D01*
X624883Y604167D01*
X624133D01*
G01X624883D02*
X625383Y604417D01*
X625800Y604833D01*
X625967Y605333D01*
X625800Y605833D01*
X625383Y606250D01*
X624633Y606500D01*
X623883Y606417D01*
X623133Y606083D01*
G01X627400Y601500D02*
Y604833D01*
G01Y603917D02*
X627650Y604333D01*
X628067Y604667D01*
X628650Y604833D01*
X629233Y604667D01*
X629650Y604333D01*
X629900Y603917D01*
Y601500D01*
G01Y603917D02*
X630150Y604333D01*
X630567Y604667D01*
X631150Y604833D01*
X631733Y604667D01*
X632150Y604333D01*
X632400Y603833D01*
Y601500D01*
G01X635500Y604833D02*
Y601500D01*
G01Y606167D02*
X635333Y606250D01*
Y606417D01*
X635500Y606500D01*
X635667Y606417D01*
Y606250D01*
X635500Y606167D01*
G01X641100Y601500D02*
Y606500D01*
G01X606583Y616667D02*
X608583D01*
G01X607500Y617750D02*
Y615583D01*
G01X611600Y614833D02*
X614600Y620000D01*
G01X617617Y616667D02*
X619783D01*
G01X622717Y619167D02*
X623217Y619667D01*
X623800Y619917D01*
X624467Y620000D01*
X625300Y619833D01*
X625883Y619417D01*
X626050Y618917D01*
X625967Y618417D01*
X625633Y618000D01*
X623967Y617167D01*
X623217Y616583D01*
X622717Y615750D01*
X622550Y615000D01*
X626050D01*
G01X627400D02*
Y618333D01*
G01Y617417D02*
X627650Y617833D01*
X628067Y618167D01*
X628650Y618333D01*
X629233Y618167D01*
X629650Y617833D01*
X629900Y617417D01*
Y615000D01*
G01Y617417D02*
X630150Y617833D01*
X630567Y618167D01*
X631150Y618333D01*
X631733Y618167D01*
X632150Y617833D01*
X632400Y617333D01*
Y615000D01*
G01X635500Y618333D02*
Y615000D01*
G01Y619667D02*
X635333Y619750D01*
Y619917D01*
X635500Y620000D01*
X635667Y619917D01*
Y619750D01*
X635500Y619667D01*
G01X641100Y615000D02*
Y620000D01*
G01X605583Y637500D02*
Y642500D01*
X609417Y637500D01*
Y642500D01*
G01X611600Y637333D02*
X614600Y642500D01*
G01X616617Y637500D02*
X618700Y642500D01*
X620783Y637500D01*
G01X620033Y639250D02*
X617367D01*
G01X606583Y586667D02*
X608583D01*
G01X607500Y587750D02*
Y585583D01*
G01X611517Y589167D02*
X612017Y589667D01*
X612600Y589917D01*
X613267Y590000D01*
X614100Y589833D01*
X614683Y589417D01*
X614850Y588917D01*
X614767Y588417D01*
X614433Y588000D01*
X612767Y587167D01*
X612017Y586583D01*
X611517Y585750D01*
X611350Y585000D01*
X614850D01*
G01X617200Y584833D02*
X620200Y590000D01*
G01X623217Y586667D02*
X625383D01*
G01X630900Y585000D02*
Y590000D01*
X627817Y586417D01*
X631983D01*
G01X633000Y585000D02*
Y588333D01*
G01Y587417D02*
X633250Y587833D01*
X633667Y588167D01*
X634250Y588333D01*
X634833Y588167D01*
X635250Y587833D01*
X635500Y587417D01*
Y585000D01*
G01Y587417D02*
X635750Y587833D01*
X636167Y588167D01*
X636750Y588333D01*
X637333Y588167D01*
X637750Y587833D01*
X638000Y587333D01*
Y585000D01*
G01X641100Y588333D02*
Y585000D01*
G01Y589667D02*
X640933Y589750D01*
Y589917D01*
X641100Y590000D01*
X641267Y589917D01*
Y589750D01*
X641100Y589667D01*
G01X646700Y585000D02*
Y590000D01*
G01X606583Y573167D02*
X608583D01*
G01X607500Y574250D02*
Y572083D01*
G01X611600Y571333D02*
X614600Y576500D01*
G01X617617Y573167D02*
X619783D01*
G01X622717Y575667D02*
X623217Y576167D01*
X623800Y576417D01*
X624467Y576500D01*
X625300Y576333D01*
X625883Y575917D01*
X626050Y575417D01*
X625967Y574917D01*
X625633Y574500D01*
X623967Y573667D01*
X623217Y573083D01*
X622717Y572250D01*
X622550Y571500D01*
X626050D01*
G01X627400D02*
Y574833D01*
G01Y573917D02*
X627650Y574333D01*
X628067Y574667D01*
X628650Y574833D01*
X629233Y574667D01*
X629650Y574333D01*
X629900Y573917D01*
Y571500D01*
G01Y573917D02*
X630150Y574333D01*
X630567Y574667D01*
X631150Y574833D01*
X631733Y574667D01*
X632150Y574333D01*
X632400Y573833D01*
Y571500D01*
G01X635500Y574833D02*
Y571500D01*
G01Y576167D02*
X635333Y576250D01*
Y576417D01*
X635500Y576500D01*
X635667Y576417D01*
Y576250D01*
X635500Y576167D01*
G01X641100Y571500D02*
Y576500D01*
G01X617500Y668500D02*
Y663500D01*
G01X615583Y668500D02*
X619417D01*
G01X623100Y663500D02*
X622600Y663583D01*
X622100Y663917D01*
X621767Y664500D01*
X621600Y665167D01*
X621767Y665833D01*
X622100Y666417D01*
X622600Y666750D01*
X623100Y666833D01*
X623600Y666750D01*
X624100Y666417D01*
X624433Y665833D01*
X624517Y665167D01*
X624433Y664500D01*
X624100Y663917D01*
X623600Y663583D01*
X623100Y663500D01*
G01X628700D02*
Y668500D01*
G01X633050Y665750D02*
X635717D01*
X635467Y666333D01*
X635050Y666667D01*
X634467Y666833D01*
X633883Y666750D01*
X633383Y666500D01*
X633050Y665917D01*
X632883Y665417D01*
Y664917D01*
X633050Y664417D01*
X633467Y663917D01*
X633967Y663583D01*
X634550Y663500D01*
X635133Y663667D01*
X635717Y664167D01*
G01X638733Y663500D02*
Y666833D01*
G01Y666167D02*
X639150Y666500D01*
X639567Y666750D01*
X640150Y666833D01*
X640567Y666750D01*
X641067Y666500D01*
G01X647000Y663500D02*
Y666833D01*
G01Y666250D02*
X646667Y666583D01*
X646167Y666750D01*
X645583Y666833D01*
X645000Y666667D01*
X644500Y666333D01*
X644167Y665833D01*
X644000Y665167D01*
X644167Y664500D01*
X644500Y664000D01*
X645000Y663667D01*
X645583Y663500D01*
X646167Y663583D01*
X646667Y663833D01*
X647000Y664167D01*
G01X649683Y663500D02*
Y666833D01*
G01Y666000D02*
X650017Y666417D01*
X650517Y666750D01*
X651183Y666833D01*
X651767Y666750D01*
X652267Y666417D01*
X652517Y665833D01*
Y663500D01*
G01X658033Y666417D02*
X657450Y666750D01*
X656950Y666833D01*
X656283Y666667D01*
X655783Y666333D01*
X655450Y665750D01*
X655367Y665167D01*
X655450Y664583D01*
X655783Y664083D01*
X656283Y663667D01*
X656950Y663500D01*
X657533Y663667D01*
X658033Y664000D01*
G01X661050Y665750D02*
X663717D01*
X663467Y666333D01*
X663050Y666667D01*
X662467Y666833D01*
X661883Y666750D01*
X661383Y666500D01*
X661050Y665917D01*
X660883Y665417D01*
Y664917D01*
X661050Y664417D01*
X661467Y663917D01*
X661967Y663583D01*
X662550Y663500D01*
X663133Y663667D01*
X663717Y664167D01*
G01X713000Y852000D02*
Y0D01*
X1343000D01*
Y852000D01*
X713000D01*
G01X694500Y729000D02*
Y0D01*
G01X713000Y138500D02*
X1343000D01*
G01X725500Y442500D02*
Y447500D01*
X722417Y443917D01*
X726583D01*
G01X730100Y442333D02*
X729933Y442417D01*
Y442583D01*
X730100Y442667D01*
X730267Y442583D01*
Y442417D01*
X730100Y442333D01*
G01X739800Y442500D02*
Y447500D01*
G01Y445000D02*
X740217Y445500D01*
X740717Y445750D01*
X741217Y445833D01*
X741967Y445667D01*
X742467Y445333D01*
X742800Y444750D01*
Y444083D01*
X742633Y443417D01*
X742300Y442917D01*
X741717Y442583D01*
X741217Y442500D01*
X740717Y442583D01*
X740217Y442833D01*
X739800Y443250D01*
G01X748400Y442500D02*
Y445833D01*
G01Y445250D02*
X748067Y445583D01*
X747567Y445750D01*
X746983Y445833D01*
X746400Y445667D01*
X745900Y445333D01*
X745567Y444833D01*
X745400Y444167D01*
X745567Y443500D01*
X745900Y443000D01*
X746400Y442667D01*
X746983Y442500D01*
X747567Y442583D01*
X748067Y442833D01*
X748400Y443167D01*
G01X753833Y445417D02*
X753250Y445750D01*
X752750Y445833D01*
X752083Y445667D01*
X751583Y445333D01*
X751250Y444750D01*
X751167Y444167D01*
X751250Y443583D01*
X751583Y443083D01*
X752083Y442667D01*
X752750Y442500D01*
X753333Y442667D01*
X753833Y443000D01*
G01X756683Y442500D02*
Y447500D01*
G01X759350Y445833D02*
X756683Y443917D01*
G01X757767Y444667D02*
X759517Y442500D01*
G01X765200Y447500D02*
Y442500D01*
G01Y443250D02*
X764867Y442833D01*
X764367Y442583D01*
X763783Y442500D01*
X763117Y442667D01*
X762617Y443083D01*
X762283Y443583D01*
X762200Y444167D01*
X762283Y444750D01*
X762617Y445250D01*
X763117Y445667D01*
X763783Y445833D01*
X764367Y445750D01*
X764783Y445583D01*
X765200Y445250D01*
G01X768133Y442500D02*
Y445833D01*
G01Y445167D02*
X768550Y445500D01*
X768967Y445750D01*
X769550Y445833D01*
X769967Y445750D01*
X770467Y445500D01*
G01X774900Y445833D02*
Y442500D01*
G01Y447167D02*
X774733Y447250D01*
Y447417D01*
X774900Y447500D01*
X775067Y447417D01*
Y447250D01*
X774900Y447167D01*
G01X780500Y442500D02*
Y447500D01*
G01X786100Y442500D02*
Y447500D01*
G01X798800Y442500D02*
Y445833D01*
G01Y445250D02*
X798467Y445583D01*
X797967Y445750D01*
X797383Y445833D01*
X796800Y445667D01*
X796300Y445333D01*
X795967Y444833D01*
X795800Y444167D01*
X795967Y443500D01*
X796300Y443000D01*
X796800Y442667D01*
X797383Y442500D01*
X797967Y442583D01*
X798467Y442833D01*
X798800Y443167D01*
G01X801483Y442500D02*
Y445833D01*
G01Y445000D02*
X801817Y445417D01*
X802317Y445750D01*
X802983Y445833D01*
X803567Y445750D01*
X804067Y445417D01*
X804317Y444833D01*
Y442500D01*
G01X810000Y447500D02*
Y442500D01*
G01Y443250D02*
X809667Y442833D01*
X809167Y442583D01*
X808583Y442500D01*
X807917Y442667D01*
X807417Y443083D01*
X807083Y443583D01*
X807000Y444167D01*
X807083Y444750D01*
X807417Y445250D01*
X807917Y445667D01*
X808583Y445833D01*
X809167Y445750D01*
X809583Y445583D01*
X810000Y445250D01*
G01X818450Y443083D02*
X818867Y442750D01*
X819450Y442500D01*
X819950D01*
X820450Y442667D01*
X820783Y442917D01*
X820950Y443250D01*
X820867Y443750D01*
X820533Y444000D01*
X819033Y444500D01*
X818700Y445083D01*
X818867Y445500D01*
X819200Y445750D01*
X819700Y445833D01*
X820200Y445750D01*
X820700Y445500D01*
G01X826800Y440833D02*
Y445833D01*
G01Y445083D02*
X826383Y445500D01*
X825883Y445750D01*
X825300Y445833D01*
X824800Y445750D01*
X824217Y445333D01*
X823883Y444750D01*
X823800Y444167D01*
X823883Y443583D01*
X824217Y443000D01*
X824800Y442583D01*
X825300Y442500D01*
X825883Y442583D01*
X826383Y442833D01*
X826800Y443250D01*
G01X829483Y445833D02*
Y443500D01*
X829817Y442917D01*
X830317Y442583D01*
X830900Y442500D01*
X831483Y442583D01*
X831983Y442917D01*
X832317Y443500D01*
G01Y442500D02*
Y445833D01*
G01X838000Y442500D02*
Y445833D01*
G01Y445250D02*
X837667Y445583D01*
X837167Y445750D01*
X836583Y445833D01*
X836000Y445667D01*
X835500Y445333D01*
X835167Y444833D01*
X835000Y444167D01*
X835167Y443500D01*
X835500Y443000D01*
X836000Y442667D01*
X836583Y442500D01*
X837167Y442583D01*
X837667Y442833D01*
X838000Y443167D01*
G01X840933Y442500D02*
Y445833D01*
G01Y445167D02*
X841350Y445500D01*
X841767Y445750D01*
X842350Y445833D01*
X842767Y445750D01*
X843267Y445500D01*
G01X846450Y444750D02*
X849117D01*
X848867Y445333D01*
X848450Y445667D01*
X847867Y445833D01*
X847283Y445750D01*
X846783Y445500D01*
X846450Y444917D01*
X846283Y444417D01*
Y443917D01*
X846450Y443417D01*
X846867Y442917D01*
X847367Y442583D01*
X847950Y442500D01*
X848533Y442667D01*
X849117Y443167D01*
G01X857483Y442500D02*
Y447500D01*
G01Y445083D02*
X857900Y445500D01*
X858317Y445750D01*
X858983Y445833D01*
X859483Y445750D01*
X860067Y445417D01*
X860317Y444917D01*
Y442500D01*
G01X864500D02*
X864000Y442583D01*
X863500Y442917D01*
X863167Y443500D01*
X863000Y444167D01*
X863167Y444833D01*
X863500Y445417D01*
X864000Y445750D01*
X864500Y445833D01*
X865000Y445750D01*
X865500Y445417D01*
X865833Y444833D01*
X865917Y444167D01*
X865833Y443500D01*
X865500Y442917D01*
X865000Y442583D01*
X864500Y442500D01*
G01X870100D02*
Y447500D01*
G01X874450Y444750D02*
X877117D01*
X876867Y445333D01*
X876450Y445667D01*
X875867Y445833D01*
X875283Y445750D01*
X874783Y445500D01*
X874450Y444917D01*
X874283Y444417D01*
Y443917D01*
X874450Y443417D01*
X874867Y442917D01*
X875367Y442583D01*
X875950Y442500D01*
X876533Y442667D01*
X877117Y443167D01*
G01X881300Y442333D02*
X881133Y442417D01*
Y442583D01*
X881300Y442667D01*
X881467Y442583D01*
Y442417D01*
X881300Y442333D01*
G01Y444583D02*
X881133Y444667D01*
Y444833D01*
X881300Y444917D01*
X881467Y444833D01*
Y444667D01*
X881300Y444583D01*
G01X720917Y481000D02*
X723000Y476000D01*
X725083Y481000D01*
G01X728600Y479333D02*
Y476000D01*
G01Y480667D02*
X728433Y480750D01*
Y480917D01*
X728600Y481000D01*
X728767Y480917D01*
Y480750D01*
X728600Y480667D01*
G01X735700Y476000D02*
Y479333D01*
G01Y478750D02*
X735367Y479083D01*
X734867Y479250D01*
X734283Y479333D01*
X733700Y479167D01*
X733200Y478833D01*
X732867Y478333D01*
X732700Y477667D01*
X732867Y477000D01*
X733200Y476500D01*
X733700Y476167D01*
X734283Y476000D01*
X734867Y476083D01*
X735367Y476333D01*
X735700Y476667D01*
G01X744400Y481000D02*
X746400D01*
G01X745400D02*
Y476000D01*
G01X744400D02*
X746400D01*
G01X749583D02*
Y479333D01*
G01Y478500D02*
X749917Y478917D01*
X750417Y479250D01*
X751083Y479333D01*
X751667Y479250D01*
X752167Y478917D01*
X752417Y478333D01*
Y476000D01*
G01X760533D02*
Y481000D01*
X762533D01*
X763200Y480750D01*
X763700Y480167D01*
X763867Y479500D01*
X763700Y478833D01*
X763283Y478333D01*
X762533Y478083D01*
X760533D01*
G01X769300Y476000D02*
Y479333D01*
G01Y478750D02*
X768967Y479083D01*
X768467Y479250D01*
X767883Y479333D01*
X767300Y479167D01*
X766800Y478833D01*
X766467Y478333D01*
X766300Y477667D01*
X766467Y477000D01*
X766800Y476500D01*
X767300Y476167D01*
X767883Y476000D01*
X768467Y476083D01*
X768967Y476333D01*
X769300Y476667D01*
G01X774900Y481000D02*
Y476000D01*
G01Y476750D02*
X774567Y476333D01*
X774067Y476083D01*
X773483Y476000D01*
X772817Y476167D01*
X772317Y476583D01*
X771983Y477083D01*
X771900Y477667D01*
X771983Y478250D01*
X772317Y478750D01*
X772817Y479167D01*
X773483Y479333D01*
X774067Y479250D01*
X774483Y479083D01*
X774900Y478750D01*
G01X778583Y474333D02*
X777750Y475167D01*
X777333Y476000D01*
Y479333D01*
X777750Y480167D01*
X778583Y481000D01*
G01X782517D02*
X784600Y476000D01*
X786683Y481000D01*
G01X789200D02*
X791200D01*
G01X790200D02*
Y476000D01*
G01X789200D02*
X791200D01*
G01X794133D02*
Y481000D01*
X796133D01*
X796800Y480750D01*
X797300Y480167D01*
X797467Y479500D01*
X797300Y478833D01*
X796883Y478333D01*
X796133Y478083D01*
X794133D01*
G01X801817Y474333D02*
X802650Y475167D01*
X803067Y476000D01*
Y479333D01*
X802650Y480167D01*
X801817Y481000D01*
G01X713000Y428500D02*
X1343000D01*
G01X713000Y458500D02*
X1343000D01*
G01X720917Y509500D02*
X723000Y504500D01*
X725083Y509500D01*
G01X728600Y507833D02*
Y504500D01*
G01Y509167D02*
X728433Y509250D01*
Y509417D01*
X728600Y509500D01*
X728767Y509417D01*
Y509250D01*
X728600Y509167D01*
G01X735700Y504500D02*
Y507833D01*
G01Y507250D02*
X735367Y507583D01*
X734867Y507750D01*
X734283Y507833D01*
X733700Y507667D01*
X733200Y507333D01*
X732867Y506833D01*
X732700Y506167D01*
X732867Y505500D01*
X733200Y505000D01*
X733700Y504667D01*
X734283Y504500D01*
X734867Y504583D01*
X735367Y504833D01*
X735700Y505167D01*
G01X745400Y504500D02*
X744733Y504583D01*
X744150Y504917D01*
X743650Y505417D01*
X743317Y506000D01*
X743150Y506667D01*
Y507333D01*
X743317Y508000D01*
X743650Y508583D01*
X744150Y509083D01*
X744733Y509417D01*
X745400Y509500D01*
X746067Y509417D01*
X746650Y509083D01*
X747150Y508583D01*
X747483Y508000D01*
X747650Y507333D01*
Y506667D01*
X747483Y506000D01*
X747150Y505417D01*
X746650Y504917D01*
X746067Y504583D01*
X745400Y504500D01*
G01X749583D02*
Y507833D01*
G01Y507000D02*
X749917Y507417D01*
X750417Y507750D01*
X751083Y507833D01*
X751667Y507750D01*
X752167Y507417D01*
X752417Y506833D01*
Y504500D01*
G01X760533D02*
Y509500D01*
X762533D01*
X763200Y509250D01*
X763700Y508667D01*
X763867Y508000D01*
X763700Y507333D01*
X763283Y506833D01*
X762533Y506583D01*
X760533D01*
G01X769300Y504500D02*
Y507833D01*
G01Y507250D02*
X768967Y507583D01*
X768467Y507750D01*
X767883Y507833D01*
X767300Y507667D01*
X766800Y507333D01*
X766467Y506833D01*
X766300Y506167D01*
X766467Y505500D01*
X766800Y505000D01*
X767300Y504667D01*
X767883Y504500D01*
X768467Y504583D01*
X768967Y504833D01*
X769300Y505167D01*
G01X774900Y509500D02*
Y504500D01*
G01Y505250D02*
X774567Y504833D01*
X774067Y504583D01*
X773483Y504500D01*
X772817Y504667D01*
X772317Y505083D01*
X771983Y505583D01*
X771900Y506167D01*
X771983Y506750D01*
X772317Y507250D01*
X772817Y507667D01*
X773483Y507833D01*
X774067Y507750D01*
X774483Y507583D01*
X774900Y507250D01*
G01X778583Y502833D02*
X777750Y503667D01*
X777333Y504500D01*
Y507833D01*
X777750Y508667D01*
X778583Y509500D01*
G01X782517D02*
X784600Y504500D01*
X786683Y509500D01*
G01X790200Y504500D02*
X789533Y504583D01*
X788950Y504917D01*
X788450Y505417D01*
X788117Y506000D01*
X787950Y506667D01*
Y507333D01*
X788117Y508000D01*
X788450Y508583D01*
X788950Y509083D01*
X789533Y509417D01*
X790200Y509500D01*
X790867Y509417D01*
X791450Y509083D01*
X791950Y508583D01*
X792283Y508000D01*
X792450Y507333D01*
Y506667D01*
X792283Y506000D01*
X791950Y505417D01*
X791450Y504917D01*
X790867Y504583D01*
X790200Y504500D01*
G01X794133D02*
Y509500D01*
X796133D01*
X796800Y509250D01*
X797300Y508667D01*
X797467Y508000D01*
X797300Y507333D01*
X796883Y506833D01*
X796133Y506583D01*
X794133D01*
G01X801817Y502833D02*
X802650Y503667D01*
X803067Y504500D01*
Y507833D01*
X802650Y508667D01*
X801817Y509500D01*
G01X723667Y528167D02*
X724000Y528417D01*
X724250Y528833D01*
X724417Y529417D01*
X724250Y529917D01*
X723917Y530250D01*
X723333Y530500D01*
X721083D01*
Y525500D01*
X723833D01*
X724417Y525833D01*
X724750Y526333D01*
X724917Y526917D01*
X724750Y527500D01*
X724250Y528000D01*
X723667Y528167D01*
X721083D01*
G01X727183Y528833D02*
Y526500D01*
X727517Y525917D01*
X728017Y525583D01*
X728600Y525500D01*
X729183Y525583D01*
X729683Y525917D01*
X730017Y526500D01*
G01Y525500D02*
Y528833D01*
G01X733033Y525500D02*
Y528833D01*
G01Y528167D02*
X733450Y528500D01*
X733867Y528750D01*
X734450Y528833D01*
X734867Y528750D01*
X735367Y528500D01*
G01X739800Y528833D02*
Y525500D01*
G01Y530167D02*
X739633Y530250D01*
Y530417D01*
X739800Y530500D01*
X739967Y530417D01*
Y530250D01*
X739800Y530167D01*
G01X744150Y527750D02*
X746817D01*
X746567Y528333D01*
X746150Y528667D01*
X745567Y528833D01*
X744983Y528750D01*
X744483Y528500D01*
X744150Y527917D01*
X743983Y527417D01*
Y526917D01*
X744150Y526417D01*
X744567Y525917D01*
X745067Y525583D01*
X745650Y525500D01*
X746233Y525667D01*
X746817Y526167D01*
G01X752500Y530500D02*
Y525500D01*
G01Y526250D02*
X752167Y525833D01*
X751667Y525583D01*
X751083Y525500D01*
X750417Y525667D01*
X749917Y526083D01*
X749583Y526583D01*
X749500Y527167D01*
X749583Y527750D01*
X749917Y528250D01*
X750417Y528667D01*
X751083Y528833D01*
X751667Y528750D01*
X752083Y528583D01*
X752500Y528250D01*
G01X760783Y525500D02*
Y530500D01*
G01Y528083D02*
X761200Y528500D01*
X761617Y528750D01*
X762283Y528833D01*
X762783Y528750D01*
X763367Y528417D01*
X763617Y527917D01*
Y525500D01*
G01X767800D02*
X767300Y525583D01*
X766800Y525917D01*
X766467Y526500D01*
X766300Y527167D01*
X766467Y527833D01*
X766800Y528417D01*
X767300Y528750D01*
X767800Y528833D01*
X768300Y528750D01*
X768800Y528417D01*
X769133Y527833D01*
X769217Y527167D01*
X769133Y526500D01*
X768800Y525917D01*
X768300Y525583D01*
X767800Y525500D01*
G01X773400D02*
Y530500D01*
G01X777750Y527750D02*
X780417D01*
X780167Y528333D01*
X779750Y528667D01*
X779167Y528833D01*
X778583Y528750D01*
X778083Y528500D01*
X777750Y527917D01*
X777583Y527417D01*
Y526917D01*
X777750Y526417D01*
X778167Y525917D01*
X778667Y525583D01*
X779250Y525500D01*
X779833Y525667D01*
X780417Y526167D01*
G01X721417Y546500D02*
Y551500D01*
X724583D01*
G01X723417Y549083D02*
X721417D01*
G01X727183Y549833D02*
Y547500D01*
X727517Y546917D01*
X728017Y546583D01*
X728600Y546500D01*
X729183Y546583D01*
X729683Y546917D01*
X730017Y547500D01*
G01Y546500D02*
Y549833D01*
G01X734200Y546500D02*
Y551500D01*
G01X739800Y546500D02*
Y551500D01*
G01X749500Y544833D02*
Y549833D01*
G01Y549083D02*
X749917Y549500D01*
X750333Y549750D01*
X751000Y549833D01*
X751583Y549750D01*
X752167Y549333D01*
X752417Y548750D01*
X752500Y548167D01*
X752417Y547583D01*
X752167Y547000D01*
X751667Y546667D01*
X751000Y546500D01*
X750417Y546583D01*
X749833Y546833D01*
X749500Y547167D01*
G01X756600Y546500D02*
Y551500D01*
G01X760783Y549833D02*
Y547500D01*
X761117Y546917D01*
X761617Y546583D01*
X762200Y546500D01*
X762783Y546583D01*
X763283Y546917D01*
X763617Y547500D01*
G01Y546500D02*
Y549833D01*
G01X766633Y545250D02*
X767217Y544917D01*
X767883Y544833D01*
X768467Y544917D01*
X768967Y545333D01*
X769300Y545917D01*
Y549833D01*
G01Y549167D02*
X768967Y549500D01*
X768467Y549750D01*
X767883Y549833D01*
X767217Y549667D01*
X766800Y549333D01*
X766467Y548750D01*
X766300Y548167D01*
X766383Y547667D01*
X766717Y547083D01*
X767217Y546667D01*
X767883Y546500D01*
X768383Y546583D01*
X768967Y546917D01*
X769300Y547250D01*
G01X772233Y545250D02*
X772817Y544917D01*
X773483Y544833D01*
X774067Y544917D01*
X774567Y545333D01*
X774900Y545917D01*
Y549833D01*
G01Y549167D02*
X774567Y549500D01*
X774067Y549750D01*
X773483Y549833D01*
X772817Y549667D01*
X772400Y549333D01*
X772067Y548750D01*
X771900Y548167D01*
X771983Y547667D01*
X772317Y547083D01*
X772817Y546667D01*
X773483Y546500D01*
X773983Y546583D01*
X774567Y546917D01*
X774900Y547250D01*
G01X779000Y549833D02*
Y546500D01*
G01Y551167D02*
X778833Y551250D01*
Y551417D01*
X779000Y551500D01*
X779167Y551417D01*
Y551250D01*
X779000Y551167D01*
G01X783183Y546500D02*
Y549833D01*
G01Y549000D02*
X783517Y549417D01*
X784017Y549750D01*
X784683Y549833D01*
X785267Y549750D01*
X785767Y549417D01*
X786017Y548833D01*
Y546500D01*
G01X789033Y545250D02*
X789617Y544917D01*
X790283Y544833D01*
X790867Y544917D01*
X791367Y545333D01*
X791700Y545917D01*
Y549833D01*
G01Y549167D02*
X791367Y549500D01*
X790867Y549750D01*
X790283Y549833D01*
X789617Y549667D01*
X789200Y549333D01*
X788867Y548750D01*
X788700Y548167D01*
X788783Y547667D01*
X789117Y547083D01*
X789617Y546667D01*
X790283Y546500D01*
X790783Y546583D01*
X791367Y546917D01*
X791700Y547250D01*
G01X713000Y493500D02*
X1343000D01*
G01X713000Y520500D02*
X1343000D01*
G01X713000Y535500D02*
X1343000D01*
G01X713000Y562500D02*
X1343000D01*
G01X721250Y615000D02*
Y620000D01*
G01X724750D02*
Y615000D01*
G01Y617500D02*
X721250D01*
G01X730100Y615000D02*
Y618333D01*
G01Y617750D02*
X729767Y618083D01*
X729267Y618250D01*
X728683Y618333D01*
X728100Y618167D01*
X727600Y617833D01*
X727267Y617333D01*
X727100Y616667D01*
X727267Y616000D01*
X727600Y615500D01*
X728100Y615167D01*
X728683Y615000D01*
X729267Y615083D01*
X729767Y615333D01*
X730100Y615667D01*
G01X734200Y615000D02*
Y620000D01*
G01X739300Y615000D02*
Y619250D01*
X739467Y619667D01*
X739800Y619917D01*
X740300Y620000D01*
X740800Y619833D01*
X741050Y619417D01*
G01X740050Y618000D02*
X738383D01*
G01X749333Y615000D02*
Y620000D01*
X751333D01*
X752000Y619750D01*
X752500Y619167D01*
X752667Y618500D01*
X752500Y617833D01*
X752083Y617333D01*
X751333Y617083D01*
X749333D01*
G01X756600Y615000D02*
Y620000D01*
G01X760783Y618333D02*
Y616000D01*
X761117Y615417D01*
X761617Y615083D01*
X762200Y615000D01*
X762783Y615083D01*
X763283Y615417D01*
X763617Y616000D01*
G01Y615000D02*
Y618333D01*
G01X766633Y613750D02*
X767217Y613417D01*
X767883Y613333D01*
X768467Y613417D01*
X768967Y613833D01*
X769300Y614417D01*
Y618333D01*
G01Y617667D02*
X768967Y618000D01*
X768467Y618250D01*
X767883Y618333D01*
X767217Y618167D01*
X766800Y617833D01*
X766467Y617250D01*
X766300Y616667D01*
X766383Y616167D01*
X766717Y615583D01*
X767217Y615167D01*
X767883Y615000D01*
X768383Y615083D01*
X768967Y615417D01*
X769300Y615750D01*
G01X772233Y613750D02*
X772817Y613417D01*
X773483Y613333D01*
X774067Y613417D01*
X774567Y613833D01*
X774900Y614417D01*
Y618333D01*
G01Y617667D02*
X774567Y618000D01*
X774067Y618250D01*
X773483Y618333D01*
X772817Y618167D01*
X772400Y617833D01*
X772067Y617250D01*
X771900Y616667D01*
X771983Y616167D01*
X772317Y615583D01*
X772817Y615167D01*
X773483Y615000D01*
X773983Y615083D01*
X774567Y615417D01*
X774900Y615750D01*
G01X779000Y618333D02*
Y615000D01*
G01Y619667D02*
X778833Y619750D01*
Y619917D01*
X779000Y620000D01*
X779167Y619917D01*
Y619750D01*
X779000Y619667D01*
G01X783183Y615000D02*
Y618333D01*
G01Y617500D02*
X783517Y617917D01*
X784017Y618250D01*
X784683Y618333D01*
X785267Y618250D01*
X785767Y617917D01*
X786017Y617333D01*
Y615000D01*
G01X789033Y613750D02*
X789617Y613417D01*
X790283Y613333D01*
X790867Y613417D01*
X791367Y613833D01*
X791700Y614417D01*
Y618333D01*
G01Y617667D02*
X791367Y618000D01*
X790867Y618250D01*
X790283Y618333D01*
X789617Y618167D01*
X789200Y617833D01*
X788867Y617250D01*
X788700Y616667D01*
X788783Y616167D01*
X789117Y615583D01*
X789617Y615167D01*
X790283Y615000D01*
X790783Y615083D01*
X791367Y615417D01*
X791700Y615750D01*
G01X722833Y669000D02*
Y674000D01*
X724833D01*
X725500Y673750D01*
X726000Y673167D01*
X726167Y672500D01*
X726000Y671833D01*
X725583Y671333D01*
X724833Y671083D01*
X722833D01*
G01X730100Y669000D02*
Y674000D01*
G01X734283Y672333D02*
Y670000D01*
X734617Y669417D01*
X735117Y669083D01*
X735700Y669000D01*
X736283Y669083D01*
X736783Y669417D01*
X737117Y670000D01*
G01Y669000D02*
Y672333D01*
G01X740133Y667750D02*
X740717Y667417D01*
X741383Y667333D01*
X741967Y667417D01*
X742467Y667833D01*
X742800Y668417D01*
Y672333D01*
G01Y671667D02*
X742467Y672000D01*
X741967Y672250D01*
X741383Y672333D01*
X740717Y672167D01*
X740300Y671833D01*
X739967Y671250D01*
X739800Y670667D01*
X739883Y670167D01*
X740217Y669583D01*
X740717Y669167D01*
X741383Y669000D01*
X741883Y669083D01*
X742467Y669417D01*
X742800Y669750D01*
G01X745733Y667750D02*
X746317Y667417D01*
X746983Y667333D01*
X747567Y667417D01*
X748067Y667833D01*
X748400Y668417D01*
Y672333D01*
G01Y671667D02*
X748067Y672000D01*
X747567Y672250D01*
X746983Y672333D01*
X746317Y672167D01*
X745900Y671833D01*
X745567Y671250D01*
X745400Y670667D01*
X745483Y670167D01*
X745817Y669583D01*
X746317Y669167D01*
X746983Y669000D01*
X747483Y669083D01*
X748067Y669417D01*
X748400Y669750D01*
G01X752500Y672333D02*
Y669000D01*
G01Y673667D02*
X752333Y673750D01*
Y673917D01*
X752500Y674000D01*
X752667Y673917D01*
Y673750D01*
X752500Y673667D01*
G01X756683Y669000D02*
Y672333D01*
G01Y671500D02*
X757017Y671917D01*
X757517Y672250D01*
X758183Y672333D01*
X758767Y672250D01*
X759267Y671917D01*
X759517Y671333D01*
Y669000D01*
G01X762533Y667750D02*
X763117Y667417D01*
X763783Y667333D01*
X764367Y667417D01*
X764867Y667833D01*
X765200Y668417D01*
Y672333D01*
G01Y671667D02*
X764867Y672000D01*
X764367Y672250D01*
X763783Y672333D01*
X763117Y672167D01*
X762700Y671833D01*
X762367Y671250D01*
X762200Y670667D01*
X762283Y670167D01*
X762617Y669583D01*
X763117Y669167D01*
X763783Y669000D01*
X764283Y669083D01*
X764867Y669417D01*
X765200Y669750D01*
G01X776400Y674000D02*
Y669000D01*
G01Y669750D02*
X776067Y669333D01*
X775567Y669083D01*
X774983Y669000D01*
X774317Y669167D01*
X773817Y669583D01*
X773483Y670083D01*
X773400Y670667D01*
X773483Y671250D01*
X773817Y671750D01*
X774317Y672167D01*
X774983Y672333D01*
X775567Y672250D01*
X775983Y672083D01*
X776400Y671750D01*
G01X779250Y671250D02*
X781917D01*
X781667Y671833D01*
X781250Y672167D01*
X780667Y672333D01*
X780083Y672250D01*
X779583Y672000D01*
X779250Y671417D01*
X779083Y670917D01*
Y670417D01*
X779250Y669917D01*
X779667Y669417D01*
X780167Y669083D01*
X780750Y669000D01*
X781333Y669167D01*
X781917Y669667D01*
G01X785600Y669000D02*
Y673250D01*
X785767Y673667D01*
X786100Y673917D01*
X786600Y674000D01*
X787100Y673833D01*
X787350Y673417D01*
G01X786350Y672000D02*
X784683D01*
G01X791700Y672333D02*
Y669000D01*
G01Y673667D02*
X791533Y673750D01*
Y673917D01*
X791700Y674000D01*
X791867Y673917D01*
Y673750D01*
X791700Y673667D01*
G01X795883Y669000D02*
Y672333D01*
G01Y671500D02*
X796217Y671917D01*
X796717Y672250D01*
X797383Y672333D01*
X797967Y672250D01*
X798467Y671917D01*
X798717Y671333D01*
Y669000D01*
G01X801650Y671250D02*
X804317D01*
X804067Y671833D01*
X803650Y672167D01*
X803067Y672333D01*
X802483Y672250D01*
X801983Y672000D01*
X801650Y671417D01*
X801483Y670917D01*
Y670417D01*
X801650Y669917D01*
X802067Y669417D01*
X802567Y669083D01*
X803150Y669000D01*
X803733Y669167D01*
X804317Y669667D01*
G01X713000Y664500D02*
X1343000D01*
G01X713000Y679500D02*
X1343000D01*
G01X722667Y835000D02*
X723167Y834417D01*
X723833Y834083D01*
X724583Y834000D01*
X725250Y834083D01*
X725917Y834500D01*
X726333Y835000D01*
X726417Y835500D01*
X726250Y836083D01*
X725667Y836500D01*
X725083Y836667D01*
X724333D01*
G01X725083D02*
X725583Y836917D01*
X726000Y837333D01*
X726167Y837833D01*
X726000Y838333D01*
X725583Y838750D01*
X724833Y839000D01*
X724083Y838917D01*
X723333Y838583D01*
G01X730100Y833833D02*
X729933Y833917D01*
Y834083D01*
X730100Y834167D01*
X730267Y834083D01*
Y833917D01*
X730100Y833833D01*
G01X739633Y834000D02*
Y839000D01*
X741633D01*
X742300Y838750D01*
X742800Y838167D01*
X742967Y837500D01*
X742800Y836833D01*
X742383Y836333D01*
X741633Y836083D01*
X739633D01*
G01X746900Y834000D02*
Y839000D01*
G01X751083Y837333D02*
Y835000D01*
X751417Y834417D01*
X751917Y834083D01*
X752500Y834000D01*
X753083Y834083D01*
X753583Y834417D01*
X753917Y835000D01*
G01Y834000D02*
Y837333D01*
G01X756933Y832750D02*
X757517Y832417D01*
X758183Y832333D01*
X758767Y832417D01*
X759267Y832833D01*
X759600Y833417D01*
Y837333D01*
G01Y836667D02*
X759267Y837000D01*
X758767Y837250D01*
X758183Y837333D01*
X757517Y837167D01*
X757100Y836833D01*
X756767Y836250D01*
X756600Y835667D01*
X756683Y835167D01*
X757017Y834583D01*
X757517Y834167D01*
X758183Y834000D01*
X758683Y834083D01*
X759267Y834417D01*
X759600Y834750D01*
G01X767800Y837333D02*
X769300Y834000D01*
X770800Y837333D01*
G01X774900D02*
Y834000D01*
G01Y838667D02*
X774733Y838750D01*
Y838917D01*
X774900Y839000D01*
X775067Y838917D01*
Y838750D01*
X774900Y838667D01*
G01X782000Y834000D02*
Y837333D01*
G01Y836750D02*
X781667Y837083D01*
X781167Y837250D01*
X780583Y837333D01*
X780000Y837167D01*
X779500Y836833D01*
X779167Y836333D01*
X779000Y835667D01*
X779167Y835000D01*
X779500Y834500D01*
X780000Y834167D01*
X780583Y834000D01*
X781167Y834083D01*
X781667Y834333D01*
X782000Y834667D01*
G01X790200Y833833D02*
X793200Y839000D01*
G01X795217D02*
X797300Y834000D01*
X799383Y839000D01*
G01X802900Y834000D02*
X802233Y834083D01*
X801650Y834417D01*
X801150Y834917D01*
X800817Y835500D01*
X800650Y836167D01*
Y836833D01*
X800817Y837500D01*
X801150Y838083D01*
X801650Y838583D01*
X802233Y838917D01*
X802900Y839000D01*
X803567Y838917D01*
X804150Y838583D01*
X804650Y838083D01*
X804983Y837500D01*
X805150Y836833D01*
Y836167D01*
X804983Y835500D01*
X804650Y834917D01*
X804150Y834417D01*
X803567Y834083D01*
X802900Y834000D01*
G01X806833D02*
Y839000D01*
X808833D01*
X809500Y838750D01*
X810000Y838167D01*
X810167Y837500D01*
X810000Y836833D01*
X809583Y836333D01*
X808833Y836083D01*
X806833D01*
G01X812600Y833833D02*
X815600Y839000D01*
G01X817617D02*
X819700Y834000D01*
X821783Y839000D01*
G01X824300D02*
X826300D01*
G01X825300D02*
Y834000D01*
G01X824300D02*
X826300D01*
G01X829233D02*
Y839000D01*
X831233D01*
X831900Y838750D01*
X832400Y838167D01*
X832567Y837500D01*
X832400Y836833D01*
X831983Y836333D01*
X831233Y836083D01*
X829233D01*
G01X836500Y833833D02*
X836333Y833917D01*
Y834083D01*
X836500Y834167D01*
X836667Y834083D01*
Y833917D01*
X836500Y833833D01*
G01Y836083D02*
X836333Y836167D01*
Y836333D01*
X836500Y836417D01*
X836667Y836333D01*
Y836167D01*
X836500Y836083D01*
G01X713000Y822000D02*
X1344500D01*
G01X802167Y22500D02*
Y27500D01*
X803833D01*
X804500Y27250D01*
X805000Y26917D01*
X805417Y26417D01*
X805750Y25833D01*
X805833Y25000D01*
X805750Y24167D01*
X805417Y23583D01*
X805000Y23083D01*
X804500Y22750D01*
X803833Y22500D01*
X802167D01*
G01X809600D02*
Y27500D01*
X808600Y26500D01*
G01Y22500D02*
X810600D01*
G01X813617Y24583D02*
X814200Y25167D01*
X814700Y25500D01*
X815367Y25667D01*
X815950Y25500D01*
X816367Y25167D01*
X816700Y24667D01*
X816783Y24083D01*
X816700Y23583D01*
X816367Y23083D01*
X815867Y22667D01*
X815283Y22500D01*
X814617Y22667D01*
X814033Y23167D01*
X813700Y23917D01*
X813617Y24750D01*
X813783Y25833D01*
X814033Y26417D01*
X814450Y27000D01*
X815033Y27417D01*
X815617Y27500D01*
X816200Y27333D01*
X816617Y26917D01*
G01X777167Y196000D02*
Y201000D01*
X778833D01*
X779500Y200750D01*
X780000Y200417D01*
X780417Y199917D01*
X780750Y199333D01*
X780833Y198500D01*
X780750Y197667D01*
X780417Y197083D01*
X780000Y196583D01*
X779500Y196250D01*
X778833Y196000D01*
X777167D01*
G01X783433D02*
Y199333D01*
G01Y198667D02*
X783850Y199000D01*
X784267Y199250D01*
X784850Y199333D01*
X785267Y199250D01*
X785767Y199000D01*
G01X790200Y199333D02*
Y196000D01*
G01Y200667D02*
X790033Y200750D01*
Y200917D01*
X790200Y201000D01*
X790367Y200917D01*
Y200750D01*
X790200Y200667D01*
G01X795800Y196000D02*
Y201000D01*
G01X801400Y196000D02*
Y201000D01*
G01X811017Y196000D02*
Y201000D01*
X814183D01*
G01X813017Y198583D02*
X811017D01*
G01X817033Y196000D02*
Y199333D01*
G01Y198667D02*
X817450Y199000D01*
X817867Y199250D01*
X818450Y199333D01*
X818867Y199250D01*
X819367Y199000D01*
G01X823800Y196000D02*
X823300Y196083D01*
X822800Y196417D01*
X822467Y197000D01*
X822300Y197667D01*
X822467Y198333D01*
X822800Y198917D01*
X823300Y199250D01*
X823800Y199333D01*
X824300Y199250D01*
X824800Y198917D01*
X825133Y198333D01*
X825217Y197667D01*
X825133Y197000D01*
X824800Y196417D01*
X824300Y196083D01*
X823800Y196000D01*
G01X826900D02*
Y199333D01*
G01Y198417D02*
X827150Y198833D01*
X827567Y199167D01*
X828150Y199333D01*
X828733Y199167D01*
X829150Y198833D01*
X829400Y198417D01*
Y196000D01*
G01Y198417D02*
X829650Y198833D01*
X830067Y199167D01*
X830650Y199333D01*
X831233Y199167D01*
X831650Y198833D01*
X831900Y198333D01*
Y196000D01*
G01X838933Y201000D02*
Y196000D01*
X842267D01*
G01X846200D02*
Y201000D01*
X845200Y200000D01*
G01Y196000D02*
X847200D01*
G01X856983Y194333D02*
X856150Y195167D01*
X855733Y196000D01*
Y199333D01*
X856150Y200167D01*
X856983Y201000D01*
G01X863000D02*
Y196000D01*
G01X861083Y201000D02*
X864917D01*
G01X868600Y196000D02*
X867933Y196083D01*
X867350Y196417D01*
X866850Y196917D01*
X866517Y197500D01*
X866350Y198167D01*
Y198833D01*
X866517Y199500D01*
X866850Y200083D01*
X867350Y200583D01*
X867933Y200917D01*
X868600Y201000D01*
X869267Y200917D01*
X869850Y200583D01*
X870350Y200083D01*
X870683Y199500D01*
X870850Y198833D01*
Y198167D01*
X870683Y197500D01*
X870350Y196917D01*
X869850Y196417D01*
X869267Y196083D01*
X868600Y196000D01*
G01X872533D02*
Y201000D01*
X874533D01*
X875200Y200750D01*
X875700Y200167D01*
X875867Y199500D01*
X875700Y198833D01*
X875283Y198333D01*
X874533Y198083D01*
X872533D01*
G01X880217Y194333D02*
X881050Y195167D01*
X881467Y196000D01*
Y199333D01*
X881050Y200167D01*
X880217Y201000D01*
G01X891000D02*
Y196000D01*
G01X889833Y199333D02*
X892167D01*
G01X896600Y196000D02*
X896100Y196083D01*
X895600Y196417D01*
X895267Y197000D01*
X895100Y197667D01*
X895267Y198333D01*
X895600Y198917D01*
X896100Y199250D01*
X896600Y199333D01*
X897100Y199250D01*
X897600Y198917D01*
X897933Y198333D01*
X898017Y197667D01*
X897933Y197000D01*
X897600Y196417D01*
X897100Y196083D01*
X896600Y196000D01*
G01X906133Y201000D02*
Y196000D01*
X909467D01*
G01X912150Y199333D02*
X914650Y196000D01*
G01Y199333D02*
X912150Y196000D01*
G01X827667Y223500D02*
Y228500D01*
X829333D01*
X830000Y228250D01*
X830500Y227917D01*
X830917Y227417D01*
X831250Y226833D01*
X831333Y226000D01*
X831250Y225167D01*
X830917Y224583D01*
X830500Y224083D01*
X830000Y223750D01*
X829333Y223500D01*
X827667D01*
G01X835100D02*
Y228500D01*
X834100Y227500D01*
G01Y223500D02*
X836100D01*
G01X775333Y165000D02*
Y160000D01*
X778667D01*
G01X781350Y163333D02*
X783850Y160000D01*
G01Y163333D02*
X781350Y160000D01*
G01X788200Y159833D02*
X788033Y159917D01*
Y160083D01*
X788200Y160167D01*
X788367Y160083D01*
Y159917D01*
X788200Y159833D01*
G01Y162083D02*
X788033Y162167D01*
Y162333D01*
X788200Y162417D01*
X788367Y162333D01*
Y162167D01*
X788200Y162083D01*
G01X796900Y160000D02*
Y163333D01*
G01Y162417D02*
X797150Y162833D01*
X797567Y163167D01*
X798150Y163333D01*
X798733Y163167D01*
X799150Y162833D01*
X799400Y162417D01*
Y160000D01*
G01Y162417D02*
X799650Y162833D01*
X800067Y163167D01*
X800650Y163333D01*
X801233Y163167D01*
X801650Y162833D01*
X801900Y162333D01*
Y160000D01*
G01X803583Y163333D02*
Y161000D01*
X803917Y160417D01*
X804417Y160083D01*
X805000Y160000D01*
X805583Y160083D01*
X806083Y160417D01*
X806417Y161000D01*
G01Y160000D02*
Y163333D01*
G01X809350Y160583D02*
X809767Y160250D01*
X810350Y160000D01*
X810850D01*
X811350Y160167D01*
X811683Y160417D01*
X811850Y160750D01*
X811767Y161250D01*
X811433Y161500D01*
X809933Y162000D01*
X809600Y162583D01*
X809767Y163000D01*
X810100Y163250D01*
X810600Y163333D01*
X811100Y163250D01*
X811600Y163000D01*
G01X816200Y165000D02*
Y160000D01*
G01X815033Y163333D02*
X817367D01*
G01X825900Y160000D02*
Y165000D01*
G01Y162500D02*
X826317Y163000D01*
X826817Y163250D01*
X827317Y163333D01*
X828067Y163167D01*
X828567Y162833D01*
X828900Y162250D01*
Y161583D01*
X828733Y160917D01*
X828400Y160417D01*
X827817Y160083D01*
X827317Y160000D01*
X826817Y160083D01*
X826317Y160333D01*
X825900Y160750D01*
G01X831750Y162250D02*
X834417D01*
X834167Y162833D01*
X833750Y163167D01*
X833167Y163333D01*
X832583Y163250D01*
X832083Y163000D01*
X831750Y162417D01*
X831583Y161917D01*
Y161417D01*
X831750Y160917D01*
X832167Y160417D01*
X832667Y160083D01*
X833250Y160000D01*
X833833Y160167D01*
X834417Y160667D01*
G01X842700Y160000D02*
Y165000D01*
G01Y162500D02*
X843117Y163000D01*
X843617Y163250D01*
X844117Y163333D01*
X844867Y163167D01*
X845367Y162833D01*
X845700Y162250D01*
Y161583D01*
X845533Y160917D01*
X845200Y160417D01*
X844617Y160083D01*
X844117Y160000D01*
X843617Y160083D01*
X843117Y160333D01*
X842700Y160750D01*
G01X848633Y160000D02*
Y163333D01*
G01Y162667D02*
X849050Y163000D01*
X849467Y163250D01*
X850050Y163333D01*
X850467Y163250D01*
X850967Y163000D01*
G01X855400Y160000D02*
X854900Y160083D01*
X854400Y160417D01*
X854067Y161000D01*
X853900Y161667D01*
X854067Y162333D01*
X854400Y162917D01*
X854900Y163250D01*
X855400Y163333D01*
X855900Y163250D01*
X856400Y162917D01*
X856733Y162333D01*
X856817Y161667D01*
X856733Y161000D01*
X856400Y160417D01*
X855900Y160083D01*
X855400Y160000D01*
G01X859583D02*
Y165000D01*
G01X862250Y163333D02*
X859583Y161417D01*
G01X860667Y162167D02*
X862417Y160000D01*
G01X865350Y162250D02*
X868017D01*
X867767Y162833D01*
X867350Y163167D01*
X866767Y163333D01*
X866183Y163250D01*
X865683Y163000D01*
X865350Y162417D01*
X865183Y161917D01*
Y161417D01*
X865350Y160917D01*
X865767Y160417D01*
X866267Y160083D01*
X866850Y160000D01*
X867433Y160167D01*
X868017Y160667D01*
G01X870783Y160000D02*
Y163333D01*
G01Y162500D02*
X871117Y162917D01*
X871617Y163250D01*
X872283Y163333D01*
X872867Y163250D01*
X873367Y162917D01*
X873617Y162333D01*
Y160000D01*
G01X883400D02*
Y165000D01*
G01X890500Y160000D02*
Y163333D01*
G01Y162750D02*
X890167Y163083D01*
X889667Y163250D01*
X889083Y163333D01*
X888500Y163167D01*
X888000Y162833D01*
X887667Y162333D01*
X887500Y161667D01*
X887667Y161000D01*
X888000Y160500D01*
X888500Y160167D01*
X889083Y160000D01*
X889667Y160083D01*
X890167Y160333D01*
X890500Y160667D01*
G01X892850Y158500D02*
X893350Y158333D01*
X894017Y158500D01*
X894433Y158833D01*
X894767Y159250D01*
X895267Y160583D01*
X896350Y163333D01*
G01X893683D02*
X895267Y160583D01*
G01X898950Y162250D02*
X901617D01*
X901367Y162833D01*
X900950Y163167D01*
X900367Y163333D01*
X899783Y163250D01*
X899283Y163000D01*
X898950Y162417D01*
X898783Y161917D01*
Y161417D01*
X898950Y160917D01*
X899367Y160417D01*
X899867Y160083D01*
X900450Y160000D01*
X901033Y160167D01*
X901617Y160667D01*
G01X904633Y160000D02*
Y163333D01*
G01Y162667D02*
X905050Y163000D01*
X905467Y163250D01*
X906050Y163333D01*
X906467Y163250D01*
X906967Y163000D01*
G01X775333Y183000D02*
Y178000D01*
X778667D01*
G01X781183D02*
Y181333D01*
G01Y180500D02*
X781517Y180917D01*
X782017Y181250D01*
X782683Y181333D01*
X783267Y181250D01*
X783767Y180917D01*
X784017Y180333D01*
Y178000D01*
G01X788200Y177833D02*
X788033Y177917D01*
Y178083D01*
X788200Y178167D01*
X788367Y178083D01*
Y177917D01*
X788200Y177833D01*
G01Y180083D02*
X788033Y180167D01*
Y180333D01*
X788200Y180417D01*
X788367Y180333D01*
Y180167D01*
X788200Y180083D01*
G01X800733Y180917D02*
X800150Y181250D01*
X799650Y181333D01*
X798983Y181167D01*
X798483Y180833D01*
X798150Y180250D01*
X798067Y179667D01*
X798150Y179083D01*
X798483Y178583D01*
X798983Y178167D01*
X799650Y178000D01*
X800233Y178167D01*
X800733Y178500D01*
G01X806500Y178000D02*
Y181333D01*
G01Y180750D02*
X806167Y181083D01*
X805667Y181250D01*
X805083Y181333D01*
X804500Y181167D01*
X804000Y180833D01*
X803667Y180333D01*
X803500Y179667D01*
X803667Y179000D01*
X804000Y178500D01*
X804500Y178167D01*
X805083Y178000D01*
X805667Y178083D01*
X806167Y178333D01*
X806500Y178667D01*
G01X809183Y178000D02*
Y181333D01*
G01Y180500D02*
X809517Y180917D01*
X810017Y181250D01*
X810683Y181333D01*
X811267Y181250D01*
X811767Y180917D01*
X812017Y180333D01*
Y178000D01*
G01X816200Y181333D02*
X817033Y182375D01*
Y183000D01*
X816408D01*
Y182375D01*
X817033D01*
G01X821800Y183000D02*
Y178000D01*
G01X820633Y181333D02*
X822967D01*
G01X831500Y178000D02*
Y183000D01*
G01Y180500D02*
X831917Y181000D01*
X832417Y181250D01*
X832917Y181333D01*
X833667Y181167D01*
X834167Y180833D01*
X834500Y180250D01*
Y179583D01*
X834333Y178917D01*
X834000Y178417D01*
X833417Y178083D01*
X832917Y178000D01*
X832417Y178083D01*
X831917Y178333D01*
X831500Y178750D01*
G01X837350Y180250D02*
X840017D01*
X839767Y180833D01*
X839350Y181167D01*
X838767Y181333D01*
X838183Y181250D01*
X837683Y181000D01*
X837350Y180417D01*
X837183Y179917D01*
Y179417D01*
X837350Y178917D01*
X837767Y178417D01*
X838267Y178083D01*
X838850Y178000D01*
X839433Y178167D01*
X840017Y178667D01*
G01X848300Y178000D02*
Y183000D01*
G01Y180500D02*
X848717Y181000D01*
X849217Y181250D01*
X849717Y181333D01*
X850467Y181167D01*
X850967Y180833D01*
X851300Y180250D01*
Y179583D01*
X851133Y178917D01*
X850800Y178417D01*
X850217Y178083D01*
X849717Y178000D01*
X849217Y178083D01*
X848717Y178333D01*
X848300Y178750D01*
G01X854233Y178000D02*
Y181333D01*
G01Y180667D02*
X854650Y181000D01*
X855067Y181250D01*
X855650Y181333D01*
X856067Y181250D01*
X856567Y181000D01*
G01X861000Y178000D02*
X860500Y178083D01*
X860000Y178417D01*
X859667Y179000D01*
X859500Y179667D01*
X859667Y180333D01*
X860000Y180917D01*
X860500Y181250D01*
X861000Y181333D01*
X861500Y181250D01*
X862000Y180917D01*
X862333Y180333D01*
X862417Y179667D01*
X862333Y179000D01*
X862000Y178417D01*
X861500Y178083D01*
X861000Y178000D01*
G01X865183D02*
Y183000D01*
G01X867850Y181333D02*
X865183Y179417D01*
G01X866267Y180167D02*
X868017Y178000D01*
G01X870950Y180250D02*
X873617D01*
X873367Y180833D01*
X872950Y181167D01*
X872367Y181333D01*
X871783Y181250D01*
X871283Y181000D01*
X870950Y180417D01*
X870783Y179917D01*
Y179417D01*
X870950Y178917D01*
X871367Y178417D01*
X871867Y178083D01*
X872450Y178000D01*
X873033Y178167D01*
X873617Y178667D01*
G01X876383Y178000D02*
Y181333D01*
G01Y180500D02*
X876717Y180917D01*
X877217Y181250D01*
X877883Y181333D01*
X878467Y181250D01*
X878967Y180917D01*
X879217Y180333D01*
Y178000D01*
G01X889000D02*
Y183000D01*
G01X896100Y178000D02*
Y181333D01*
G01Y180750D02*
X895767Y181083D01*
X895267Y181250D01*
X894683Y181333D01*
X894100Y181167D01*
X893600Y180833D01*
X893267Y180333D01*
X893100Y179667D01*
X893267Y179000D01*
X893600Y178500D01*
X894100Y178167D01*
X894683Y178000D01*
X895267Y178083D01*
X895767Y178333D01*
X896100Y178667D01*
G01X898450Y176500D02*
X898950Y176333D01*
X899617Y176500D01*
X900033Y176833D01*
X900367Y177250D01*
X900867Y178583D01*
X901950Y181333D01*
G01X899283D02*
X900867Y178583D01*
G01X904550Y180250D02*
X907217D01*
X906967Y180833D01*
X906550Y181167D01*
X905967Y181333D01*
X905383Y181250D01*
X904883Y181000D01*
X904550Y180417D01*
X904383Y179917D01*
Y179417D01*
X904550Y178917D01*
X904967Y178417D01*
X905467Y178083D01*
X906050Y178000D01*
X906633Y178167D01*
X907217Y178667D01*
G01X910233Y178000D02*
Y181333D01*
G01Y180667D02*
X910650Y181000D01*
X911067Y181250D01*
X911650Y181333D01*
X912067Y181250D01*
X912567Y181000D01*
G01X825667Y397500D02*
Y402500D01*
X827333D01*
X828000Y402250D01*
X828500Y401917D01*
X828917Y401417D01*
X829250Y400833D01*
X829333Y400000D01*
X829250Y399167D01*
X828917Y398583D01*
X828500Y398083D01*
X828000Y397750D01*
X827333Y397500D01*
X825667D01*
G01X831517Y401667D02*
X832017Y402167D01*
X832600Y402417D01*
X833267Y402500D01*
X834100Y402333D01*
X834683Y401917D01*
X834850Y401417D01*
X834767Y400917D01*
X834433Y400500D01*
X832767Y399667D01*
X832017Y399083D01*
X831517Y398250D01*
X831350Y397500D01*
X834850D01*
G01X821500Y474000D02*
Y478250D01*
X821667Y478667D01*
X822000Y478917D01*
X822500Y479000D01*
X823000Y478833D01*
X823250Y478417D01*
G01X822250Y477000D02*
X820583D01*
G01X827600Y474000D02*
X827100Y474083D01*
X826600Y474417D01*
X826267Y475000D01*
X826100Y475667D01*
X826267Y476333D01*
X826600Y476917D01*
X827100Y477250D01*
X827600Y477333D01*
X828100Y477250D01*
X828600Y476917D01*
X828933Y476333D01*
X829017Y475667D01*
X828933Y475000D01*
X828600Y474417D01*
X828100Y474083D01*
X827600Y474000D01*
G01X833200D02*
Y479000D01*
G01X838800Y474000D02*
Y479000D01*
G01X844400Y474000D02*
X843900Y474083D01*
X843400Y474417D01*
X843067Y475000D01*
X842900Y475667D01*
X843067Y476333D01*
X843400Y476917D01*
X843900Y477250D01*
X844400Y477333D01*
X844900Y477250D01*
X845400Y476917D01*
X845733Y476333D01*
X845817Y475667D01*
X845733Y475000D01*
X845400Y474417D01*
X844900Y474083D01*
X844400Y474000D01*
G01X847917Y477333D02*
X848917Y474000D01*
X850000Y477333D01*
X851083Y474000D01*
X852083Y477333D01*
G01X861700Y476500D02*
X863367D01*
Y475000D01*
X862867Y474500D01*
X862283Y474167D01*
X861450Y474000D01*
X860617Y474167D01*
X860033Y474500D01*
X859533Y475000D01*
X859200Y475583D01*
X859033Y476250D01*
Y476833D01*
X859200Y477333D01*
X859533Y477917D01*
X860033Y478417D01*
X860533Y478750D01*
X861200Y479000D01*
X861783D01*
X862450Y478833D01*
X862950Y478500D01*
G01X865550Y476250D02*
X868217D01*
X867967Y476833D01*
X867550Y477167D01*
X866967Y477333D01*
X866383Y477250D01*
X865883Y477000D01*
X865550Y476417D01*
X865383Y475917D01*
Y475417D01*
X865550Y474917D01*
X865967Y474417D01*
X866467Y474083D01*
X867050Y474000D01*
X867633Y474167D01*
X868217Y474667D01*
G01X871233Y474000D02*
Y477333D01*
G01Y476667D02*
X871650Y477000D01*
X872067Y477250D01*
X872650Y477333D01*
X873067Y477250D01*
X873567Y477000D01*
G01X876500Y474000D02*
Y479000D01*
G01Y476500D02*
X876917Y477000D01*
X877417Y477250D01*
X877917Y477333D01*
X878667Y477167D01*
X879167Y476833D01*
X879500Y476250D01*
Y475583D01*
X879333Y474917D01*
X879000Y474417D01*
X878417Y474083D01*
X877917Y474000D01*
X877417Y474083D01*
X876917Y474333D01*
X876500Y474750D01*
G01X882350Y476250D02*
X885017D01*
X884767Y476833D01*
X884350Y477167D01*
X883767Y477333D01*
X883183Y477250D01*
X882683Y477000D01*
X882350Y476417D01*
X882183Y475917D01*
Y475417D01*
X882350Y474917D01*
X882767Y474417D01*
X883267Y474083D01*
X883850Y474000D01*
X884433Y474167D01*
X885017Y474667D01*
G01X888033Y474000D02*
Y477333D01*
G01Y476667D02*
X888450Y477000D01*
X888867Y477250D01*
X889450Y477333D01*
X889867Y477250D01*
X890367Y477000D01*
G01X901900Y474000D02*
Y477333D01*
G01Y476750D02*
X901567Y477083D01*
X901067Y477250D01*
X900483Y477333D01*
X899900Y477167D01*
X899400Y476833D01*
X899067Y476333D01*
X898900Y475667D01*
X899067Y475000D01*
X899400Y474500D01*
X899900Y474167D01*
X900483Y474000D01*
X901067Y474083D01*
X901567Y474333D01*
X901900Y474667D01*
G01X904583Y474000D02*
Y477333D01*
G01Y476500D02*
X904917Y476917D01*
X905417Y477250D01*
X906083Y477333D01*
X906667Y477250D01*
X907167Y476917D01*
X907417Y476333D01*
Y474000D01*
G01X913100Y479000D02*
Y474000D01*
G01Y474750D02*
X912767Y474333D01*
X912267Y474083D01*
X911683Y474000D01*
X911017Y474167D01*
X910517Y474583D01*
X910183Y475083D01*
X910100Y475667D01*
X910183Y476250D01*
X910517Y476750D01*
X911017Y477167D01*
X911683Y477333D01*
X912267Y477250D01*
X912683Y477083D01*
X913100Y476750D01*
G01X921300Y472333D02*
Y477333D01*
G01Y476583D02*
X921717Y477000D01*
X922133Y477250D01*
X922800Y477333D01*
X923383Y477250D01*
X923967Y476833D01*
X924217Y476250D01*
X924300Y475667D01*
X924217Y475083D01*
X923967Y474500D01*
X923467Y474167D01*
X922800Y474000D01*
X922217Y474083D01*
X921633Y474333D01*
X921300Y474667D01*
G01X928400Y474000D02*
Y479000D01*
G01X932583Y477333D02*
Y475000D01*
X932917Y474417D01*
X933417Y474083D01*
X934000Y474000D01*
X934583Y474083D01*
X935083Y474417D01*
X935417Y475000D01*
G01Y474000D02*
Y477333D01*
G01X938433Y472750D02*
X939017Y472417D01*
X939683Y472333D01*
X940267Y472417D01*
X940767Y472833D01*
X941100Y473417D01*
Y477333D01*
G01Y476667D02*
X940767Y477000D01*
X940267Y477250D01*
X939683Y477333D01*
X939017Y477167D01*
X938600Y476833D01*
X938267Y476250D01*
X938100Y475667D01*
X938183Y475167D01*
X938517Y474583D01*
X939017Y474167D01*
X939683Y474000D01*
X940183Y474083D01*
X940767Y474417D01*
X941100Y474750D01*
G01X948717Y477333D02*
X949717Y474000D01*
X950800Y477333D01*
X951883Y474000D01*
X952883Y477333D01*
G01X956400D02*
Y474000D01*
G01Y478667D02*
X956233Y478750D01*
Y478917D01*
X956400Y479000D01*
X956567Y478917D01*
Y478750D01*
X956400Y478667D01*
G01X962000Y479000D02*
Y474000D01*
G01X960833Y477333D02*
X963167D01*
G01X966183Y474000D02*
Y479000D01*
G01Y476583D02*
X966600Y477000D01*
X967017Y477250D01*
X967683Y477333D01*
X968183Y477250D01*
X968767Y476917D01*
X969017Y476417D01*
Y474000D01*
G01X977633D02*
Y477333D01*
G01Y476667D02*
X978050Y477000D01*
X978467Y477250D01*
X979050Y477333D01*
X979467Y477250D01*
X979967Y477000D01*
G01X983150Y476250D02*
X985817D01*
X985567Y476833D01*
X985150Y477167D01*
X984567Y477333D01*
X983983Y477250D01*
X983483Y477000D01*
X983150Y476417D01*
X982983Y475917D01*
Y475417D01*
X983150Y474917D01*
X983567Y474417D01*
X984067Y474083D01*
X984650Y474000D01*
X985233Y474167D01*
X985817Y474667D01*
G01X988750Y474583D02*
X989167Y474250D01*
X989750Y474000D01*
X990250D01*
X990750Y474167D01*
X991083Y474417D01*
X991250Y474750D01*
X991167Y475250D01*
X990833Y475500D01*
X989333Y476000D01*
X989000Y476583D01*
X989167Y477000D01*
X989500Y477250D01*
X990000Y477333D01*
X990500Y477250D01*
X991000Y477000D01*
G01X995600Y477333D02*
Y474000D01*
G01Y478667D02*
X995433Y478750D01*
Y478917D01*
X995600Y479000D01*
X995767Y478917D01*
Y478750D01*
X995600Y478667D01*
G01X999783Y474000D02*
Y477333D01*
G01Y476500D02*
X1000117Y476917D01*
X1000617Y477250D01*
X1001283Y477333D01*
X1001867Y477250D01*
X1002367Y476917D01*
X1002617Y476333D01*
Y474000D01*
G01X812000Y679500D02*
Y459000D01*
G01X823500Y540500D02*
Y543833D01*
G01Y543250D02*
X823167Y543583D01*
X822667Y543750D01*
X822083Y543833D01*
X821500Y543667D01*
X821000Y543333D01*
X820667Y542833D01*
X820500Y542167D01*
X820667Y541500D01*
X821000Y541000D01*
X821500Y540667D01*
X822083Y540500D01*
X822667Y540583D01*
X823167Y540833D01*
X823500Y541167D01*
G01X826183Y540500D02*
Y543833D01*
G01Y543000D02*
X826517Y543417D01*
X827017Y543750D01*
X827683Y543833D01*
X828267Y543750D01*
X828767Y543417D01*
X829017Y542833D01*
Y540500D01*
G01X834700Y545500D02*
Y540500D01*
G01Y541250D02*
X834367Y540833D01*
X833867Y540583D01*
X833283Y540500D01*
X832617Y540667D01*
X832117Y541083D01*
X831783Y541583D01*
X831700Y542167D01*
X831783Y542750D01*
X832117Y543250D01*
X832617Y543667D01*
X833283Y543833D01*
X833867Y543750D01*
X834283Y543583D01*
X834700Y543250D01*
G01X842900Y540500D02*
Y545500D01*
G01Y543000D02*
X843317Y543500D01*
X843817Y543750D01*
X844317Y543833D01*
X845067Y543667D01*
X845567Y543333D01*
X845900Y542750D01*
Y542083D01*
X845733Y541417D01*
X845400Y540917D01*
X844817Y540583D01*
X844317Y540500D01*
X843817Y540583D01*
X843317Y540833D01*
X842900Y541250D01*
G01X850000Y540500D02*
X849500Y540583D01*
X849000Y540917D01*
X848667Y541500D01*
X848500Y542167D01*
X848667Y542833D01*
X849000Y543417D01*
X849500Y543750D01*
X850000Y543833D01*
X850500Y543750D01*
X851000Y543417D01*
X851333Y542833D01*
X851417Y542167D01*
X851333Y541500D01*
X851000Y540917D01*
X850500Y540583D01*
X850000Y540500D01*
G01X855600Y545500D02*
Y540500D01*
G01X854433Y543833D02*
X856767D01*
G01X861200Y545500D02*
Y540500D01*
G01X860033Y543833D02*
X862367D01*
G01X866800Y540500D02*
X866300Y540583D01*
X865800Y540917D01*
X865467Y541500D01*
X865300Y542167D01*
X865467Y542833D01*
X865800Y543417D01*
X866300Y543750D01*
X866800Y543833D01*
X867300Y543750D01*
X867800Y543417D01*
X868133Y542833D01*
X868217Y542167D01*
X868133Y541500D01*
X867800Y540917D01*
X867300Y540583D01*
X866800Y540500D01*
G01X869900D02*
Y543833D01*
G01Y542917D02*
X870150Y543333D01*
X870567Y543667D01*
X871150Y543833D01*
X871733Y543667D01*
X872150Y543333D01*
X872400Y542917D01*
Y540500D01*
G01Y542917D02*
X872650Y543333D01*
X873067Y543667D01*
X873650Y543833D01*
X874233Y543667D01*
X874650Y543333D01*
X874900Y542833D01*
Y540500D01*
G01X882350Y541083D02*
X882767Y540750D01*
X883350Y540500D01*
X883850D01*
X884350Y540667D01*
X884683Y540917D01*
X884850Y541250D01*
X884767Y541750D01*
X884433Y542000D01*
X882933Y542500D01*
X882600Y543083D01*
X882767Y543500D01*
X883100Y543750D01*
X883600Y543833D01*
X884100Y543750D01*
X884600Y543500D01*
G01X889200Y543833D02*
Y540500D01*
G01Y545167D02*
X889033Y545250D01*
Y545417D01*
X889200Y545500D01*
X889367Y545417D01*
Y545250D01*
X889200Y545167D01*
G01X896300Y545500D02*
Y540500D01*
G01Y541250D02*
X895967Y540833D01*
X895467Y540583D01*
X894883Y540500D01*
X894217Y540667D01*
X893717Y541083D01*
X893383Y541583D01*
X893300Y542167D01*
X893383Y542750D01*
X893717Y543250D01*
X894217Y543667D01*
X894883Y543833D01*
X895467Y543750D01*
X895883Y543583D01*
X896300Y543250D01*
G01X899150Y542750D02*
X901817D01*
X901567Y543333D01*
X901150Y543667D01*
X900567Y543833D01*
X899983Y543750D01*
X899483Y543500D01*
X899150Y542917D01*
X898983Y542417D01*
Y541917D01*
X899150Y541417D01*
X899567Y540917D01*
X900067Y540583D01*
X900650Y540500D01*
X901233Y540667D01*
X901817Y541167D01*
G01X819917Y555833D02*
X820917Y552500D01*
X822000Y555833D01*
X823083Y552500D01*
X824083Y555833D01*
G01X827600D02*
Y552500D01*
G01Y557167D02*
X827433Y557250D01*
Y557417D01*
X827600Y557500D01*
X827767Y557417D01*
Y557250D01*
X827600Y557167D01*
G01X833200Y557500D02*
Y552500D01*
G01X832033Y555833D02*
X834367D01*
G01X837383Y552500D02*
Y557500D01*
G01Y555083D02*
X837800Y555500D01*
X838217Y555750D01*
X838883Y555833D01*
X839383Y555750D01*
X839967Y555417D01*
X840217Y554917D01*
Y552500D01*
G01X844400D02*
X843900Y552583D01*
X843400Y552917D01*
X843067Y553500D01*
X842900Y554167D01*
X843067Y554833D01*
X843400Y555417D01*
X843900Y555750D01*
X844400Y555833D01*
X844900Y555750D01*
X845400Y555417D01*
X845733Y554833D01*
X845817Y554167D01*
X845733Y553500D01*
X845400Y552917D01*
X844900Y552583D01*
X844400Y552500D01*
G01X848583Y555833D02*
Y553500D01*
X848917Y552917D01*
X849417Y552583D01*
X850000Y552500D01*
X850583Y552583D01*
X851083Y552917D01*
X851417Y553500D01*
G01Y552500D02*
Y555833D01*
G01X855600Y557500D02*
Y552500D01*
G01X854433Y555833D02*
X856767D01*
G01X865550Y553083D02*
X865967Y552750D01*
X866550Y552500D01*
X867050D01*
X867550Y552667D01*
X867883Y552917D01*
X868050Y553250D01*
X867967Y553750D01*
X867633Y554000D01*
X866133Y554500D01*
X865800Y555083D01*
X865967Y555500D01*
X866300Y555750D01*
X866800Y555833D01*
X867300Y555750D01*
X867800Y555500D01*
G01X872400Y552500D02*
X871900Y552583D01*
X871400Y552917D01*
X871067Y553500D01*
X870900Y554167D01*
X871067Y554833D01*
X871400Y555417D01*
X871900Y555750D01*
X872400Y555833D01*
X872900Y555750D01*
X873400Y555417D01*
X873733Y554833D01*
X873817Y554167D01*
X873733Y553500D01*
X873400Y552917D01*
X872900Y552583D01*
X872400Y552500D01*
G01X878000D02*
Y557500D01*
G01X885100D02*
Y552500D01*
G01Y553250D02*
X884767Y552833D01*
X884267Y552583D01*
X883683Y552500D01*
X883017Y552667D01*
X882517Y553083D01*
X882183Y553583D01*
X882100Y554167D01*
X882183Y554750D01*
X882517Y555250D01*
X883017Y555667D01*
X883683Y555833D01*
X884267Y555750D01*
X884683Y555583D01*
X885100Y555250D01*
G01X887950Y554750D02*
X890617D01*
X890367Y555333D01*
X889950Y555667D01*
X889367Y555833D01*
X888783Y555750D01*
X888283Y555500D01*
X887950Y554917D01*
X887783Y554417D01*
Y553917D01*
X887950Y553417D01*
X888367Y552917D01*
X888867Y552583D01*
X889450Y552500D01*
X890033Y552667D01*
X890617Y553167D01*
G01X893633Y552500D02*
Y555833D01*
G01Y555167D02*
X894050Y555500D01*
X894467Y555750D01*
X895050Y555833D01*
X895467Y555750D01*
X895967Y555500D01*
G01X903500Y552500D02*
Y555833D01*
G01Y554917D02*
X903750Y555333D01*
X904167Y555667D01*
X904750Y555833D01*
X905333Y555667D01*
X905750Y555333D01*
X906000Y554917D01*
Y552500D01*
G01Y554917D02*
X906250Y555333D01*
X906667Y555667D01*
X907250Y555833D01*
X907833Y555667D01*
X908250Y555333D01*
X908500Y554833D01*
Y552500D01*
G01X913100D02*
Y555833D01*
G01Y555250D02*
X912767Y555583D01*
X912267Y555750D01*
X911683Y555833D01*
X911100Y555667D01*
X910600Y555333D01*
X910267Y554833D01*
X910100Y554167D01*
X910267Y553500D01*
X910600Y553000D01*
X911100Y552667D01*
X911683Y552500D01*
X912267Y552583D01*
X912767Y552833D01*
X913100Y553167D01*
G01X915950Y553083D02*
X916367Y552750D01*
X916950Y552500D01*
X917450D01*
X917950Y552667D01*
X918283Y552917D01*
X918450Y553250D01*
X918367Y553750D01*
X918033Y554000D01*
X916533Y554500D01*
X916200Y555083D01*
X916367Y555500D01*
X916700Y555750D01*
X917200Y555833D01*
X917700Y555750D01*
X918200Y555500D01*
G01X921383Y552500D02*
Y557500D01*
G01X924050Y555833D02*
X921383Y553917D01*
G01X922467Y554667D02*
X924217Y552500D01*
G01X932500Y550833D02*
Y555833D01*
G01Y555083D02*
X932917Y555500D01*
X933333Y555750D01*
X934000Y555833D01*
X934583Y555750D01*
X935167Y555333D01*
X935417Y554750D01*
X935500Y554167D01*
X935417Y553583D01*
X935167Y553000D01*
X934667Y552667D01*
X934000Y552500D01*
X933417Y552583D01*
X932833Y552833D01*
X932500Y553167D01*
G01X941100Y552500D02*
Y555833D01*
G01Y555250D02*
X940767Y555583D01*
X940267Y555750D01*
X939683Y555833D01*
X939100Y555667D01*
X938600Y555333D01*
X938267Y554833D01*
X938100Y554167D01*
X938267Y553500D01*
X938600Y553000D01*
X939100Y552667D01*
X939683Y552500D01*
X940267Y552583D01*
X940767Y552833D01*
X941100Y553167D01*
G01X946700Y557500D02*
Y552500D01*
G01Y553250D02*
X946367Y552833D01*
X945867Y552583D01*
X945283Y552500D01*
X944617Y552667D01*
X944117Y553083D01*
X943783Y553583D01*
X943700Y554167D01*
X943783Y554750D01*
X944117Y555250D01*
X944617Y555667D01*
X945283Y555833D01*
X945867Y555750D01*
X946283Y555583D01*
X946700Y555250D01*
G01X956400Y552500D02*
X955900Y552583D01*
X955400Y552917D01*
X955067Y553500D01*
X954900Y554167D01*
X955067Y554833D01*
X955400Y555417D01*
X955900Y555750D01*
X956400Y555833D01*
X956900Y555750D01*
X957400Y555417D01*
X957733Y554833D01*
X957817Y554167D01*
X957733Y553500D01*
X957400Y552917D01*
X956900Y552583D01*
X956400Y552500D01*
G01X960583D02*
Y555833D01*
G01Y555000D02*
X960917Y555417D01*
X961417Y555750D01*
X962083Y555833D01*
X962667Y555750D01*
X963167Y555417D01*
X963417Y554833D01*
Y552500D01*
G01X973200Y557500D02*
Y552500D01*
G01X972033Y555833D02*
X974367D01*
G01X978800Y552500D02*
X978300Y552583D01*
X977800Y552917D01*
X977467Y553500D01*
X977300Y554167D01*
X977467Y554833D01*
X977800Y555417D01*
X978300Y555750D01*
X978800Y555833D01*
X979300Y555750D01*
X979800Y555417D01*
X980133Y554833D01*
X980217Y554167D01*
X980133Y553500D01*
X979800Y552917D01*
X979300Y552583D01*
X978800Y552500D01*
G01X982900Y550833D02*
Y555833D01*
G01Y555083D02*
X983317Y555500D01*
X983733Y555750D01*
X984400Y555833D01*
X984983Y555750D01*
X985567Y555333D01*
X985817Y554750D01*
X985900Y554167D01*
X985817Y553583D01*
X985567Y553000D01*
X985067Y552667D01*
X984400Y552500D01*
X983817Y552583D01*
X983233Y552833D01*
X982900Y553167D01*
G01X821500Y525500D02*
Y529750D01*
X821667Y530167D01*
X822000Y530417D01*
X822500Y530500D01*
X823000Y530333D01*
X823250Y529917D01*
G01X822250Y528500D02*
X820583D01*
G01X827600Y525500D02*
X827100Y525583D01*
X826600Y525917D01*
X826267Y526500D01*
X826100Y527167D01*
X826267Y527833D01*
X826600Y528417D01*
X827100Y528750D01*
X827600Y528833D01*
X828100Y528750D01*
X828600Y528417D01*
X828933Y527833D01*
X829017Y527167D01*
X828933Y526500D01*
X828600Y525917D01*
X828100Y525583D01*
X827600Y525500D01*
G01X833200D02*
Y530500D01*
G01X838800Y525500D02*
Y530500D01*
G01X844400Y525500D02*
X843900Y525583D01*
X843400Y525917D01*
X843067Y526500D01*
X842900Y527167D01*
X843067Y527833D01*
X843400Y528417D01*
X843900Y528750D01*
X844400Y528833D01*
X844900Y528750D01*
X845400Y528417D01*
X845733Y527833D01*
X845817Y527167D01*
X845733Y526500D01*
X845400Y525917D01*
X844900Y525583D01*
X844400Y525500D01*
G01X847917Y528833D02*
X848917Y525500D01*
X850000Y528833D01*
X851083Y525500D01*
X852083Y528833D01*
G01X861700Y528000D02*
X863367D01*
Y526500D01*
X862867Y526000D01*
X862283Y525667D01*
X861450Y525500D01*
X860617Y525667D01*
X860033Y526000D01*
X859533Y526500D01*
X859200Y527083D01*
X859033Y527750D01*
Y528333D01*
X859200Y528833D01*
X859533Y529417D01*
X860033Y529917D01*
X860533Y530250D01*
X861200Y530500D01*
X861783D01*
X862450Y530333D01*
X862950Y530000D01*
G01X865550Y527750D02*
X868217D01*
X867967Y528333D01*
X867550Y528667D01*
X866967Y528833D01*
X866383Y528750D01*
X865883Y528500D01*
X865550Y527917D01*
X865383Y527417D01*
Y526917D01*
X865550Y526417D01*
X865967Y525917D01*
X866467Y525583D01*
X867050Y525500D01*
X867633Y525667D01*
X868217Y526167D01*
G01X871233Y525500D02*
Y528833D01*
G01Y528167D02*
X871650Y528500D01*
X872067Y528750D01*
X872650Y528833D01*
X873067Y528750D01*
X873567Y528500D01*
G01X876500Y525500D02*
Y530500D01*
G01Y528000D02*
X876917Y528500D01*
X877417Y528750D01*
X877917Y528833D01*
X878667Y528667D01*
X879167Y528333D01*
X879500Y527750D01*
Y527083D01*
X879333Y526417D01*
X879000Y525917D01*
X878417Y525583D01*
X877917Y525500D01*
X877417Y525583D01*
X876917Y525833D01*
X876500Y526250D01*
G01X882350Y527750D02*
X885017D01*
X884767Y528333D01*
X884350Y528667D01*
X883767Y528833D01*
X883183Y528750D01*
X882683Y528500D01*
X882350Y527917D01*
X882183Y527417D01*
Y526917D01*
X882350Y526417D01*
X882767Y525917D01*
X883267Y525583D01*
X883850Y525500D01*
X884433Y525667D01*
X885017Y526167D01*
G01X888033Y525500D02*
Y528833D01*
G01Y528167D02*
X888450Y528500D01*
X888867Y528750D01*
X889450Y528833D01*
X889867Y528750D01*
X890367Y528500D01*
G01X821500Y504500D02*
Y508750D01*
X821667Y509167D01*
X822000Y509417D01*
X822500Y509500D01*
X823000Y509333D01*
X823250Y508917D01*
G01X822250Y507500D02*
X820583D01*
G01X827600Y504500D02*
X827100Y504583D01*
X826600Y504917D01*
X826267Y505500D01*
X826100Y506167D01*
X826267Y506833D01*
X826600Y507417D01*
X827100Y507750D01*
X827600Y507833D01*
X828100Y507750D01*
X828600Y507417D01*
X828933Y506833D01*
X829017Y506167D01*
X828933Y505500D01*
X828600Y504917D01*
X828100Y504583D01*
X827600Y504500D01*
G01X833200D02*
Y509500D01*
G01X838800Y504500D02*
Y509500D01*
G01X844400Y504500D02*
X843900Y504583D01*
X843400Y504917D01*
X843067Y505500D01*
X842900Y506167D01*
X843067Y506833D01*
X843400Y507417D01*
X843900Y507750D01*
X844400Y507833D01*
X844900Y507750D01*
X845400Y507417D01*
X845733Y506833D01*
X845817Y506167D01*
X845733Y505500D01*
X845400Y504917D01*
X844900Y504583D01*
X844400Y504500D01*
G01X847917Y507833D02*
X848917Y504500D01*
X850000Y507833D01*
X851083Y504500D01*
X852083Y507833D01*
G01X861700Y507000D02*
X863367D01*
Y505500D01*
X862867Y505000D01*
X862283Y504667D01*
X861450Y504500D01*
X860617Y504667D01*
X860033Y505000D01*
X859533Y505500D01*
X859200Y506083D01*
X859033Y506750D01*
Y507333D01*
X859200Y507833D01*
X859533Y508417D01*
X860033Y508917D01*
X860533Y509250D01*
X861200Y509500D01*
X861783D01*
X862450Y509333D01*
X862950Y509000D01*
G01X865550Y506750D02*
X868217D01*
X867967Y507333D01*
X867550Y507667D01*
X866967Y507833D01*
X866383Y507750D01*
X865883Y507500D01*
X865550Y506917D01*
X865383Y506417D01*
Y505917D01*
X865550Y505417D01*
X865967Y504917D01*
X866467Y504583D01*
X867050Y504500D01*
X867633Y504667D01*
X868217Y505167D01*
G01X871233Y504500D02*
Y507833D01*
G01Y507167D02*
X871650Y507500D01*
X872067Y507750D01*
X872650Y507833D01*
X873067Y507750D01*
X873567Y507500D01*
G01X876500Y504500D02*
Y509500D01*
G01Y507000D02*
X876917Y507500D01*
X877417Y507750D01*
X877917Y507833D01*
X878667Y507667D01*
X879167Y507333D01*
X879500Y506750D01*
Y506083D01*
X879333Y505417D01*
X879000Y504917D01*
X878417Y504583D01*
X877917Y504500D01*
X877417Y504583D01*
X876917Y504833D01*
X876500Y505250D01*
G01X882350Y506750D02*
X885017D01*
X884767Y507333D01*
X884350Y507667D01*
X883767Y507833D01*
X883183Y507750D01*
X882683Y507500D01*
X882350Y506917D01*
X882183Y506417D01*
Y505917D01*
X882350Y505417D01*
X882767Y504917D01*
X883267Y504583D01*
X883850Y504500D01*
X884433Y504667D01*
X885017Y505167D01*
G01X888033Y504500D02*
Y507833D01*
G01Y507167D02*
X888450Y507500D01*
X888867Y507750D01*
X889450Y507833D01*
X889867Y507750D01*
X890367Y507500D01*
G01X901900Y504500D02*
Y507833D01*
G01Y507250D02*
X901567Y507583D01*
X901067Y507750D01*
X900483Y507833D01*
X899900Y507667D01*
X899400Y507333D01*
X899067Y506833D01*
X898900Y506167D01*
X899067Y505500D01*
X899400Y505000D01*
X899900Y504667D01*
X900483Y504500D01*
X901067Y504583D01*
X901567Y504833D01*
X901900Y505167D01*
G01X904583Y504500D02*
Y507833D01*
G01Y507000D02*
X904917Y507417D01*
X905417Y507750D01*
X906083Y507833D01*
X906667Y507750D01*
X907167Y507417D01*
X907417Y506833D01*
Y504500D01*
G01X913100Y509500D02*
Y504500D01*
G01Y505250D02*
X912767Y504833D01*
X912267Y504583D01*
X911683Y504500D01*
X911017Y504667D01*
X910517Y505083D01*
X910183Y505583D01*
X910100Y506167D01*
X910183Y506750D01*
X910517Y507250D01*
X911017Y507667D01*
X911683Y507833D01*
X912267Y507750D01*
X912683Y507583D01*
X913100Y507250D01*
G01X921300Y502833D02*
Y507833D01*
G01Y507083D02*
X921717Y507500D01*
X922133Y507750D01*
X922800Y507833D01*
X923383Y507750D01*
X923967Y507333D01*
X924217Y506750D01*
X924300Y506167D01*
X924217Y505583D01*
X923967Y505000D01*
X923467Y504667D01*
X922800Y504500D01*
X922217Y504583D01*
X921633Y504833D01*
X921300Y505167D01*
G01X928400Y504500D02*
Y509500D01*
G01X932583Y507833D02*
Y505500D01*
X932917Y504917D01*
X933417Y504583D01*
X934000Y504500D01*
X934583Y504583D01*
X935083Y504917D01*
X935417Y505500D01*
G01Y504500D02*
Y507833D01*
G01X938433Y503250D02*
X939017Y502917D01*
X939683Y502833D01*
X940267Y502917D01*
X940767Y503333D01*
X941100Y503917D01*
Y507833D01*
G01Y507167D02*
X940767Y507500D01*
X940267Y507750D01*
X939683Y507833D01*
X939017Y507667D01*
X938600Y507333D01*
X938267Y506750D01*
X938100Y506167D01*
X938183Y505667D01*
X938517Y505083D01*
X939017Y504667D01*
X939683Y504500D01*
X940183Y504583D01*
X940767Y504917D01*
X941100Y505250D01*
G01X948717Y507833D02*
X949717Y504500D01*
X950800Y507833D01*
X951883Y504500D01*
X952883Y507833D01*
G01X956400D02*
Y504500D01*
G01Y509167D02*
X956233Y509250D01*
Y509417D01*
X956400Y509500D01*
X956567Y509417D01*
Y509250D01*
X956400Y509167D01*
G01X962000Y509500D02*
Y504500D01*
G01X960833Y507833D02*
X963167D01*
G01X966183Y504500D02*
Y509500D01*
G01Y507083D02*
X966600Y507500D01*
X967017Y507750D01*
X967683Y507833D01*
X968183Y507750D01*
X968767Y507417D01*
X969017Y506917D01*
Y504500D01*
G01X977633D02*
Y507833D01*
G01Y507167D02*
X978050Y507500D01*
X978467Y507750D01*
X979050Y507833D01*
X979467Y507750D01*
X979967Y507500D01*
G01X983150Y506750D02*
X985817D01*
X985567Y507333D01*
X985150Y507667D01*
X984567Y507833D01*
X983983Y507750D01*
X983483Y507500D01*
X983150Y506917D01*
X982983Y506417D01*
Y505917D01*
X983150Y505417D01*
X983567Y504917D01*
X984067Y504583D01*
X984650Y504500D01*
X985233Y504667D01*
X985817Y505167D01*
G01X988750Y505083D02*
X989167Y504750D01*
X989750Y504500D01*
X990250D01*
X990750Y504667D01*
X991083Y504917D01*
X991250Y505250D01*
X991167Y505750D01*
X990833Y506000D01*
X989333Y506500D01*
X989000Y507083D01*
X989167Y507500D01*
X989500Y507750D01*
X990000Y507833D01*
X990500Y507750D01*
X991000Y507500D01*
G01X995600Y507833D02*
Y504500D01*
G01Y509167D02*
X995433Y509250D01*
Y509417D01*
X995600Y509500D01*
X995767Y509417D01*
Y509250D01*
X995600Y509167D01*
G01X999783Y504500D02*
Y507833D01*
G01Y507000D02*
X1000117Y507417D01*
X1000617Y507750D01*
X1001283Y507833D01*
X1001867Y507750D01*
X1002367Y507417D01*
X1002617Y506833D01*
Y504500D01*
G01X829750Y627583D02*
X830167Y627250D01*
X830750Y627000D01*
X831250D01*
X831750Y627167D01*
X832083Y627417D01*
X832250Y627750D01*
X832167Y628250D01*
X831833Y628500D01*
X830333Y629000D01*
X830000Y629583D01*
X830167Y630000D01*
X830500Y630250D01*
X831000Y630333D01*
X831500Y630250D01*
X832000Y630000D01*
G01X836600Y627000D02*
X836100Y627083D01*
X835600Y627417D01*
X835267Y628000D01*
X835100Y628667D01*
X835267Y629333D01*
X835600Y629917D01*
X836100Y630250D01*
X836600Y630333D01*
X837100Y630250D01*
X837600Y629917D01*
X837933Y629333D01*
X838017Y628667D01*
X837933Y628000D01*
X837600Y627417D01*
X837100Y627083D01*
X836600Y627000D01*
G01X842200D02*
Y632000D01*
G01X849300D02*
Y627000D01*
G01Y627750D02*
X848967Y627333D01*
X848467Y627083D01*
X847883Y627000D01*
X847217Y627167D01*
X846717Y627583D01*
X846383Y628083D01*
X846300Y628667D01*
X846383Y629250D01*
X846717Y629750D01*
X847217Y630167D01*
X847883Y630333D01*
X848467Y630250D01*
X848883Y630083D01*
X849300Y629750D01*
G01X852150Y629250D02*
X854817D01*
X854567Y629833D01*
X854150Y630167D01*
X853567Y630333D01*
X852983Y630250D01*
X852483Y630000D01*
X852150Y629417D01*
X851983Y628917D01*
Y628417D01*
X852150Y627917D01*
X852567Y627417D01*
X853067Y627083D01*
X853650Y627000D01*
X854233Y627167D01*
X854817Y627667D01*
G01X857833Y627000D02*
Y630333D01*
G01Y629667D02*
X858250Y630000D01*
X858667Y630250D01*
X859250Y630333D01*
X859667Y630250D01*
X860167Y630000D01*
G01X867700Y627000D02*
Y630333D01*
G01Y629417D02*
X867950Y629833D01*
X868367Y630167D01*
X868950Y630333D01*
X869533Y630167D01*
X869950Y629833D01*
X870200Y629417D01*
Y627000D01*
G01Y629417D02*
X870450Y629833D01*
X870867Y630167D01*
X871450Y630333D01*
X872033Y630167D01*
X872450Y629833D01*
X872700Y629333D01*
Y627000D01*
G01X877300D02*
Y630333D01*
G01Y629750D02*
X876967Y630083D01*
X876467Y630250D01*
X875883Y630333D01*
X875300Y630167D01*
X874800Y629833D01*
X874467Y629333D01*
X874300Y628667D01*
X874467Y628000D01*
X874800Y627500D01*
X875300Y627167D01*
X875883Y627000D01*
X876467Y627083D01*
X876967Y627333D01*
X877300Y627667D01*
G01X880150Y627583D02*
X880567Y627250D01*
X881150Y627000D01*
X881650D01*
X882150Y627167D01*
X882483Y627417D01*
X882650Y627750D01*
X882567Y628250D01*
X882233Y628500D01*
X880733Y629000D01*
X880400Y629583D01*
X880567Y630000D01*
X880900Y630250D01*
X881400Y630333D01*
X881900Y630250D01*
X882400Y630000D01*
G01X885583Y627000D02*
Y632000D01*
G01X888250Y630333D02*
X885583Y628417D01*
G01X886667Y629167D02*
X888417Y627000D01*
G01X896700Y625333D02*
Y630333D01*
G01Y629583D02*
X897117Y630000D01*
X897533Y630250D01*
X898200Y630333D01*
X898783Y630250D01*
X899367Y629833D01*
X899617Y629250D01*
X899700Y628667D01*
X899617Y628083D01*
X899367Y627500D01*
X898867Y627167D01*
X898200Y627000D01*
X897617Y627083D01*
X897033Y627333D01*
X896700Y627667D01*
G01X905300Y627000D02*
Y630333D01*
G01Y629750D02*
X904967Y630083D01*
X904467Y630250D01*
X903883Y630333D01*
X903300Y630167D01*
X902800Y629833D01*
X902467Y629333D01*
X902300Y628667D01*
X902467Y628000D01*
X902800Y627500D01*
X903300Y627167D01*
X903883Y627000D01*
X904467Y627083D01*
X904967Y627333D01*
X905300Y627667D01*
G01X910900Y632000D02*
Y627000D01*
G01Y627750D02*
X910567Y627333D01*
X910067Y627083D01*
X909483Y627000D01*
X908817Y627167D01*
X908317Y627583D01*
X907983Y628083D01*
X907900Y628667D01*
X907983Y629250D01*
X908317Y629750D01*
X908817Y630167D01*
X909483Y630333D01*
X910067Y630250D01*
X910483Y630083D01*
X910900Y629750D01*
G01X829917Y648333D02*
X830917Y645000D01*
X832000Y648333D01*
X833083Y645000D01*
X834083Y648333D01*
G01X836183Y645000D02*
Y650000D01*
G01Y647583D02*
X836600Y648000D01*
X837017Y648250D01*
X837683Y648333D01*
X838183Y648250D01*
X838767Y647917D01*
X839017Y647417D01*
Y645000D01*
G01X843200Y648333D02*
Y645000D01*
G01Y649667D02*
X843033Y649750D01*
Y649917D01*
X843200Y650000D01*
X843367Y649917D01*
Y649750D01*
X843200Y649667D01*
G01X850133Y647917D02*
X849550Y648250D01*
X849050Y648333D01*
X848383Y648167D01*
X847883Y647833D01*
X847550Y647250D01*
X847467Y646667D01*
X847550Y646083D01*
X847883Y645583D01*
X848383Y645167D01*
X849050Y645000D01*
X849633Y645167D01*
X850133Y645500D01*
G01X852983Y645000D02*
Y650000D01*
G01Y647583D02*
X853400Y648000D01*
X853817Y648250D01*
X854483Y648333D01*
X854983Y648250D01*
X855567Y647917D01*
X855817Y647417D01*
Y645000D01*
G01X864350Y645583D02*
X864767Y645250D01*
X865350Y645000D01*
X865850D01*
X866350Y645167D01*
X866683Y645417D01*
X866850Y645750D01*
X866767Y646250D01*
X866433Y646500D01*
X864933Y647000D01*
X864600Y647583D01*
X864767Y648000D01*
X865100Y648250D01*
X865600Y648333D01*
X866100Y648250D01*
X866600Y648000D01*
G01X871200Y648333D02*
Y645000D01*
G01Y649667D02*
X871033Y649750D01*
Y649917D01*
X871200Y650000D01*
X871367Y649917D01*
Y649750D01*
X871200Y649667D01*
G01X875550Y648333D02*
X878050D01*
X875550Y645000D01*
X878050D01*
G01X881150Y647250D02*
X883817D01*
X883567Y647833D01*
X883150Y648167D01*
X882567Y648333D01*
X881983Y648250D01*
X881483Y648000D01*
X881150Y647417D01*
X880983Y646917D01*
Y646417D01*
X881150Y645917D01*
X881567Y645417D01*
X882067Y645083D01*
X882650Y645000D01*
X883233Y645167D01*
X883817Y645667D01*
G01X893600Y648333D02*
Y645000D01*
G01Y649667D02*
X893433Y649750D01*
Y649917D01*
X893600Y650000D01*
X893767Y649917D01*
Y649750D01*
X893600Y649667D01*
G01X897950Y645583D02*
X898367Y645250D01*
X898950Y645000D01*
X899450D01*
X899950Y645167D01*
X900283Y645417D01*
X900450Y645750D01*
X900367Y646250D01*
X900033Y646500D01*
X898533Y647000D01*
X898200Y647583D01*
X898367Y648000D01*
X898700Y648250D01*
X899200Y648333D01*
X899700Y648250D01*
X900200Y648000D01*
G01X908900Y645000D02*
Y650000D01*
G01Y647500D02*
X909317Y648000D01*
X909817Y648250D01*
X910317Y648333D01*
X911067Y648167D01*
X911567Y647833D01*
X911900Y647250D01*
Y646583D01*
X911733Y645917D01*
X911400Y645417D01*
X910817Y645083D01*
X910317Y645000D01*
X909817Y645083D01*
X909317Y645333D01*
X908900Y645750D01*
G01X916000Y648333D02*
Y645000D01*
G01Y649667D02*
X915833Y649750D01*
Y649917D01*
X916000Y650000D01*
X916167Y649917D01*
Y649750D01*
X916000Y649667D01*
G01X920433Y643750D02*
X921017Y643417D01*
X921683Y643333D01*
X922267Y643417D01*
X922767Y643833D01*
X923100Y644417D01*
Y648333D01*
G01Y647667D02*
X922767Y648000D01*
X922267Y648250D01*
X921683Y648333D01*
X921017Y648167D01*
X920600Y647833D01*
X920267Y647250D01*
X920100Y646667D01*
X920183Y646167D01*
X920517Y645583D01*
X921017Y645167D01*
X921683Y645000D01*
X922183Y645083D01*
X922767Y645417D01*
X923100Y645750D01*
G01X926033Y643750D02*
X926617Y643417D01*
X927283Y643333D01*
X927867Y643417D01*
X928367Y643833D01*
X928700Y644417D01*
Y648333D01*
G01Y647667D02*
X928367Y648000D01*
X927867Y648250D01*
X927283Y648333D01*
X926617Y648167D01*
X926200Y647833D01*
X925867Y647250D01*
X925700Y646667D01*
X925783Y646167D01*
X926117Y645583D01*
X926617Y645167D01*
X927283Y645000D01*
X927783Y645083D01*
X928367Y645417D01*
X928700Y645750D01*
G01X931550Y647250D02*
X934217D01*
X933967Y647833D01*
X933550Y648167D01*
X932967Y648333D01*
X932383Y648250D01*
X931883Y648000D01*
X931550Y647417D01*
X931383Y646917D01*
Y646417D01*
X931550Y645917D01*
X931967Y645417D01*
X932467Y645083D01*
X933050Y645000D01*
X933633Y645167D01*
X934217Y645667D01*
G01X937233Y645000D02*
Y648333D01*
G01Y647667D02*
X937650Y648000D01*
X938067Y648250D01*
X938650Y648333D01*
X939067Y648250D01*
X939567Y648000D01*
G01X949600Y650000D02*
Y645000D01*
G01X948433Y648333D02*
X950767D01*
G01X953783Y645000D02*
Y650000D01*
G01Y647583D02*
X954200Y648000D01*
X954617Y648250D01*
X955283Y648333D01*
X955783Y648250D01*
X956367Y647917D01*
X956617Y647417D01*
Y645000D01*
G01X962300D02*
Y648333D01*
G01Y647750D02*
X961967Y648083D01*
X961467Y648250D01*
X960883Y648333D01*
X960300Y648167D01*
X959800Y647833D01*
X959467Y647333D01*
X959300Y646667D01*
X959467Y646000D01*
X959800Y645500D01*
X960300Y645167D01*
X960883Y645000D01*
X961467Y645083D01*
X961967Y645333D01*
X962300Y645667D01*
G01X964983Y645000D02*
Y648333D01*
G01Y647500D02*
X965317Y647917D01*
X965817Y648250D01*
X966483Y648333D01*
X967067Y648250D01*
X967567Y647917D01*
X967817Y647333D01*
Y645000D01*
G01X979100D02*
Y648333D01*
G01Y647750D02*
X978767Y648083D01*
X978267Y648250D01*
X977683Y648333D01*
X977100Y648167D01*
X976600Y647833D01*
X976267Y647333D01*
X976100Y646667D01*
X976267Y646000D01*
X976600Y645500D01*
X977100Y645167D01*
X977683Y645000D01*
X978267Y645083D01*
X978767Y645333D01*
X979100Y645667D01*
G01X981783Y645000D02*
Y648333D01*
G01Y647500D02*
X982117Y647917D01*
X982617Y648250D01*
X983283Y648333D01*
X983867Y648250D01*
X984367Y647917D01*
X984617Y647333D01*
Y645000D01*
G01X987383D02*
Y648333D01*
G01Y647500D02*
X987717Y647917D01*
X988217Y648250D01*
X988883Y648333D01*
X989467Y648250D01*
X989967Y647917D01*
X990217Y647333D01*
Y645000D01*
G01X992983Y648333D02*
Y646000D01*
X993317Y645417D01*
X993817Y645083D01*
X994400Y645000D01*
X994983Y645083D01*
X995483Y645417D01*
X995817Y646000D01*
G01Y645000D02*
Y648333D01*
G01X1001500Y645000D02*
Y648333D01*
G01Y647750D02*
X1001167Y648083D01*
X1000667Y648250D01*
X1000083Y648333D01*
X999500Y648167D01*
X999000Y647833D01*
X998667Y647333D01*
X998500Y646667D01*
X998667Y646000D01*
X999000Y645500D01*
X999500Y645167D01*
X1000083Y645000D01*
X1000667Y645083D01*
X1001167Y645333D01*
X1001500Y645667D01*
G01X1005600Y645000D02*
Y650000D01*
G01X831333Y636000D02*
Y639333D01*
G01Y638667D02*
X831750Y639000D01*
X832167Y639250D01*
X832750Y639333D01*
X833167Y639250D01*
X833667Y639000D01*
G01X838100Y639333D02*
Y636000D01*
G01Y640667D02*
X837933Y640750D01*
Y640917D01*
X838100Y641000D01*
X838267Y640917D01*
Y640750D01*
X838100Y640667D01*
G01X842283Y636000D02*
Y639333D01*
G01Y638500D02*
X842617Y638917D01*
X843117Y639250D01*
X843783Y639333D01*
X844367Y639250D01*
X844867Y638917D01*
X845117Y638333D01*
Y636000D01*
G01X848133Y634750D02*
X848717Y634417D01*
X849383Y634333D01*
X849967Y634417D01*
X850467Y634833D01*
X850800Y635417D01*
Y639333D01*
G01Y638667D02*
X850467Y639000D01*
X849967Y639250D01*
X849383Y639333D01*
X848717Y639167D01*
X848300Y638833D01*
X847967Y638250D01*
X847800Y637667D01*
X847883Y637167D01*
X848217Y636583D01*
X848717Y636167D01*
X849383Y636000D01*
X849883Y636083D01*
X850467Y636417D01*
X850800Y636750D01*
G01X859250Y636583D02*
X859667Y636250D01*
X860250Y636000D01*
X860750D01*
X861250Y636167D01*
X861583Y636417D01*
X861750Y636750D01*
X861667Y637250D01*
X861333Y637500D01*
X859833Y638000D01*
X859500Y638583D01*
X859667Y639000D01*
X860000Y639250D01*
X860500Y639333D01*
X861000Y639250D01*
X861500Y639000D01*
G01X866100Y639333D02*
Y636000D01*
G01Y640667D02*
X865933Y640750D01*
Y640917D01*
X866100Y641000D01*
X866267Y640917D01*
Y640750D01*
X866100Y640667D01*
G01X870450Y639333D02*
X872950D01*
X870450Y636000D01*
X872950D01*
G01X876050Y638250D02*
X878717D01*
X878467Y638833D01*
X878050Y639167D01*
X877467Y639333D01*
X876883Y639250D01*
X876383Y639000D01*
X876050Y638417D01*
X875883Y637917D01*
Y637417D01*
X876050Y636917D01*
X876467Y636417D01*
X876967Y636083D01*
X877550Y636000D01*
X878133Y636167D01*
X878717Y636667D01*
G01X888333Y635083D02*
X888667Y636167D01*
G01X822000Y654000D02*
Y659000D01*
X821000Y658000D01*
G01Y654000D02*
X823000D01*
G01X827600Y653833D02*
X827433Y653917D01*
Y654083D01*
X827600Y654167D01*
X827767Y654083D01*
Y653917D01*
X827600Y653833D01*
G01X833200Y654000D02*
X832533Y654083D01*
X831950Y654417D01*
X831450Y654917D01*
X831117Y655500D01*
X830950Y656167D01*
Y656833D01*
X831117Y657500D01*
X831450Y658083D01*
X831950Y658583D01*
X832533Y658917D01*
X833200Y659000D01*
X833867Y658917D01*
X834450Y658583D01*
X834950Y658083D01*
X835283Y657500D01*
X835450Y656833D01*
Y656167D01*
X835283Y655500D01*
X834950Y654917D01*
X834450Y654417D01*
X833867Y654083D01*
X833200Y654000D01*
G01X837383D02*
Y657333D01*
G01Y656500D02*
X837717Y656917D01*
X838217Y657250D01*
X838883Y657333D01*
X839467Y657250D01*
X839967Y656917D01*
X840217Y656333D01*
Y654000D01*
G01X843150Y656250D02*
X845817D01*
X845567Y656833D01*
X845150Y657167D01*
X844567Y657333D01*
X843983Y657250D01*
X843483Y657000D01*
X843150Y656417D01*
X842983Y655917D01*
Y655417D01*
X843150Y654917D01*
X843567Y654417D01*
X844067Y654083D01*
X844650Y654000D01*
X845233Y654167D01*
X845817Y654667D01*
G01X854350Y654583D02*
X854767Y654250D01*
X855350Y654000D01*
X855850D01*
X856350Y654167D01*
X856683Y654417D01*
X856850Y654750D01*
X856767Y655250D01*
X856433Y655500D01*
X854933Y656000D01*
X854600Y656583D01*
X854767Y657000D01*
X855100Y657250D01*
X855600Y657333D01*
X856100Y657250D01*
X856600Y657000D01*
G01X861200Y657333D02*
Y654000D01*
G01Y658667D02*
X861033Y658750D01*
Y658917D01*
X861200Y659000D01*
X861367Y658917D01*
Y658750D01*
X861200Y658667D01*
G01X868300Y659000D02*
Y654000D01*
G01Y654750D02*
X867967Y654333D01*
X867467Y654083D01*
X866883Y654000D01*
X866217Y654167D01*
X865717Y654583D01*
X865383Y655083D01*
X865300Y655667D01*
X865383Y656250D01*
X865717Y656750D01*
X866217Y657167D01*
X866883Y657333D01*
X867467Y657250D01*
X867883Y657083D01*
X868300Y656750D01*
G01X871150Y656250D02*
X873817D01*
X873567Y656833D01*
X873150Y657167D01*
X872567Y657333D01*
X871983Y657250D01*
X871483Y657000D01*
X871150Y656417D01*
X870983Y655917D01*
Y655417D01*
X871150Y654917D01*
X871567Y654417D01*
X872067Y654083D01*
X872650Y654000D01*
X873233Y654167D01*
X873817Y654667D01*
G01X881517Y657333D02*
X882517Y654000D01*
X883600Y657333D01*
X884683Y654000D01*
X885683Y657333D01*
G01X889200D02*
Y654000D01*
G01Y658667D02*
X889033Y658750D01*
Y658917D01*
X889200Y659000D01*
X889367Y658917D01*
Y658750D01*
X889200Y658667D01*
G01X894800Y659000D02*
Y654000D01*
G01X893633Y657333D02*
X895967D01*
G01X898983Y654000D02*
Y659000D01*
G01Y656583D02*
X899400Y657000D01*
X899817Y657250D01*
X900483Y657333D01*
X900983Y657250D01*
X901567Y656917D01*
X901817Y656417D01*
Y654000D01*
G01X910350Y654583D02*
X910767Y654250D01*
X911350Y654000D01*
X911850D01*
X912350Y654167D01*
X912683Y654417D01*
X912850Y654750D01*
X912767Y655250D01*
X912433Y655500D01*
X910933Y656000D01*
X910600Y656583D01*
X910767Y657000D01*
X911100Y657250D01*
X911600Y657333D01*
X912100Y657250D01*
X912600Y657000D01*
G01X917200Y654000D02*
X916700Y654083D01*
X916200Y654417D01*
X915867Y655000D01*
X915700Y655667D01*
X915867Y656333D01*
X916200Y656917D01*
X916700Y657250D01*
X917200Y657333D01*
X917700Y657250D01*
X918200Y656917D01*
X918533Y656333D01*
X918617Y655667D01*
X918533Y655000D01*
X918200Y654417D01*
X917700Y654083D01*
X917200Y654000D01*
G01X922800D02*
Y659000D01*
G01X929900D02*
Y654000D01*
G01Y654750D02*
X929567Y654333D01*
X929067Y654083D01*
X928483Y654000D01*
X927817Y654167D01*
X927317Y654583D01*
X926983Y655083D01*
X926900Y655667D01*
X926983Y656250D01*
X927317Y656750D01*
X927817Y657167D01*
X928483Y657333D01*
X929067Y657250D01*
X929483Y657083D01*
X929900Y656750D01*
G01X932750Y656250D02*
X935417D01*
X935167Y656833D01*
X934750Y657167D01*
X934167Y657333D01*
X933583Y657250D01*
X933083Y657000D01*
X932750Y656417D01*
X932583Y655917D01*
Y655417D01*
X932750Y654917D01*
X933167Y654417D01*
X933667Y654083D01*
X934250Y654000D01*
X934833Y654167D01*
X935417Y654667D01*
G01X938433Y654000D02*
Y657333D01*
G01Y656667D02*
X938850Y657000D01*
X939267Y657250D01*
X939850Y657333D01*
X940267Y657250D01*
X940767Y657000D01*
G01X948300Y654000D02*
Y657333D01*
G01Y656417D02*
X948550Y656833D01*
X948967Y657167D01*
X949550Y657333D01*
X950133Y657167D01*
X950550Y656833D01*
X950800Y656417D01*
Y654000D01*
G01Y656417D02*
X951050Y656833D01*
X951467Y657167D01*
X952050Y657333D01*
X952633Y657167D01*
X953050Y656833D01*
X953300Y656333D01*
Y654000D01*
G01X957900D02*
Y657333D01*
G01Y656750D02*
X957567Y657083D01*
X957067Y657250D01*
X956483Y657333D01*
X955900Y657167D01*
X955400Y656833D01*
X955067Y656333D01*
X954900Y655667D01*
X955067Y655000D01*
X955400Y654500D01*
X955900Y654167D01*
X956483Y654000D01*
X957067Y654083D01*
X957567Y654333D01*
X957900Y654667D01*
G01X960750Y654583D02*
X961167Y654250D01*
X961750Y654000D01*
X962250D01*
X962750Y654167D01*
X963083Y654417D01*
X963250Y654750D01*
X963167Y655250D01*
X962833Y655500D01*
X961333Y656000D01*
X961000Y656583D01*
X961167Y657000D01*
X961500Y657250D01*
X962000Y657333D01*
X962500Y657250D01*
X963000Y657000D01*
G01X966183Y654000D02*
Y659000D01*
G01X968850Y657333D02*
X966183Y655417D01*
G01X967267Y656167D02*
X969017Y654000D01*
G01X977300Y652333D02*
Y657333D01*
G01Y656583D02*
X977717Y657000D01*
X978133Y657250D01*
X978800Y657333D01*
X979383Y657250D01*
X979967Y656833D01*
X980217Y656250D01*
X980300Y655667D01*
X980217Y655083D01*
X979967Y654500D01*
X979467Y654167D01*
X978800Y654000D01*
X978217Y654083D01*
X977633Y654333D01*
X977300Y654667D01*
G01X985900Y654000D02*
Y657333D01*
G01Y656750D02*
X985567Y657083D01*
X985067Y657250D01*
X984483Y657333D01*
X983900Y657167D01*
X983400Y656833D01*
X983067Y656333D01*
X982900Y655667D01*
X983067Y655000D01*
X983400Y654500D01*
X983900Y654167D01*
X984483Y654000D01*
X985067Y654083D01*
X985567Y654333D01*
X985900Y654667D01*
G01X991500Y659000D02*
Y654000D01*
G01Y654750D02*
X991167Y654333D01*
X990667Y654083D01*
X990083Y654000D01*
X989417Y654167D01*
X988917Y654583D01*
X988583Y655083D01*
X988500Y655667D01*
X988583Y656250D01*
X988917Y656750D01*
X989417Y657167D01*
X990083Y657333D01*
X990667Y657250D01*
X991083Y657083D01*
X991500Y656750D01*
G01X794500Y744500D02*
Y739500D01*
G01X793333Y742833D02*
X795667D01*
G01X798683Y739500D02*
Y744500D01*
G01Y742083D02*
X799100Y742500D01*
X799517Y742750D01*
X800183Y742833D01*
X800683Y742750D01*
X801267Y742417D01*
X801517Y741917D01*
Y739500D01*
G01X805700Y742833D02*
Y739500D01*
G01Y744167D02*
X805533Y744250D01*
Y744417D01*
X805700Y744500D01*
X805867Y744417D01*
Y744250D01*
X805700Y744167D01*
G01X812633Y742417D02*
X812050Y742750D01*
X811550Y742833D01*
X810883Y742667D01*
X810383Y742333D01*
X810050Y741750D01*
X809967Y741167D01*
X810050Y740583D01*
X810383Y740083D01*
X810883Y739667D01*
X811550Y739500D01*
X812133Y739667D01*
X812633Y740000D01*
G01X815483Y739500D02*
Y744500D01*
G01X818150Y742833D02*
X815483Y740917D01*
G01X816567Y741667D02*
X818317Y739500D01*
G01X821083D02*
Y742833D01*
G01Y742000D02*
X821417Y742417D01*
X821917Y742750D01*
X822583Y742833D01*
X823167Y742750D01*
X823667Y742417D01*
X823917Y741833D01*
Y739500D01*
G01X826850Y741750D02*
X829517D01*
X829267Y742333D01*
X828850Y742667D01*
X828267Y742833D01*
X827683Y742750D01*
X827183Y742500D01*
X826850Y741917D01*
X826683Y741417D01*
Y740917D01*
X826850Y740417D01*
X827267Y739917D01*
X827767Y739583D01*
X828350Y739500D01*
X828933Y739667D01*
X829517Y740167D01*
G01X832450Y740083D02*
X832867Y739750D01*
X833450Y739500D01*
X833950D01*
X834450Y739667D01*
X834783Y739917D01*
X834950Y740250D01*
X834867Y740750D01*
X834533Y741000D01*
X833033Y741500D01*
X832700Y742083D01*
X832867Y742500D01*
X833200Y742750D01*
X833700Y742833D01*
X834200Y742750D01*
X834700Y742500D01*
G01X838050Y740083D02*
X838467Y739750D01*
X839050Y739500D01*
X839550D01*
X840050Y739667D01*
X840383Y739917D01*
X840550Y740250D01*
X840467Y740750D01*
X840133Y741000D01*
X838633Y741500D01*
X838300Y742083D01*
X838467Y742500D01*
X838800Y742750D01*
X839300Y742833D01*
X839800Y742750D01*
X840300Y742500D01*
G01X809000Y756500D02*
Y761500D01*
G01Y759000D02*
X809417Y759500D01*
X809917Y759750D01*
X810417Y759833D01*
X811167Y759667D01*
X811667Y759333D01*
X812000Y758750D01*
Y758083D01*
X811833Y757417D01*
X811500Y756917D01*
X810917Y756583D01*
X810417Y756500D01*
X809917Y756583D01*
X809417Y756833D01*
X809000Y757250D01*
G01X816100Y756500D02*
X815600Y756583D01*
X815100Y756917D01*
X814767Y757500D01*
X814600Y758167D01*
X814767Y758833D01*
X815100Y759417D01*
X815600Y759750D01*
X816100Y759833D01*
X816600Y759750D01*
X817100Y759417D01*
X817433Y758833D01*
X817517Y758167D01*
X817433Y757500D01*
X817100Y756917D01*
X816600Y756583D01*
X816100Y756500D01*
G01X823200D02*
Y759833D01*
G01Y759250D02*
X822867Y759583D01*
X822367Y759750D01*
X821783Y759833D01*
X821200Y759667D01*
X820700Y759333D01*
X820367Y758833D01*
X820200Y758167D01*
X820367Y757500D01*
X820700Y757000D01*
X821200Y756667D01*
X821783Y756500D01*
X822367Y756583D01*
X822867Y756833D01*
X823200Y757167D01*
G01X826133Y756500D02*
Y759833D01*
G01Y759167D02*
X826550Y759500D01*
X826967Y759750D01*
X827550Y759833D01*
X827967Y759750D01*
X828467Y759500D01*
G01X834400Y761500D02*
Y756500D01*
G01Y757250D02*
X834067Y756833D01*
X833567Y756583D01*
X832983Y756500D01*
X832317Y756667D01*
X831817Y757083D01*
X831483Y757583D01*
X831400Y758167D01*
X831483Y758750D01*
X831817Y759250D01*
X832317Y759667D01*
X832983Y759833D01*
X833567Y759750D01*
X833983Y759583D01*
X834400Y759250D01*
G01X909000Y110500D02*
Y115500D01*
X905917Y111917D01*
X910083D01*
G01X911767Y111250D02*
X912267Y110833D01*
X912850Y110583D01*
X913600Y110500D01*
X914350Y110667D01*
X914933Y111000D01*
X915350Y111583D01*
X915433Y112250D01*
X915267Y112917D01*
X914850Y113333D01*
X914267Y113667D01*
X913683Y113750D01*
X913100Y113667D01*
X912350Y113333D01*
X912600Y115500D01*
X914850D01*
G01X868250Y225000D02*
Y230000D01*
G01X871750D02*
Y225000D01*
G01Y227500D02*
X868250D01*
G01X875600Y225000D02*
X874933Y225083D01*
X874350Y225417D01*
X873850Y225917D01*
X873517Y226500D01*
X873350Y227167D01*
Y227833D01*
X873517Y228500D01*
X873850Y229083D01*
X874350Y229583D01*
X874933Y229917D01*
X875600Y230000D01*
X876267Y229917D01*
X876850Y229583D01*
X877350Y229083D01*
X877683Y228500D01*
X877850Y227833D01*
Y227167D01*
X877683Y226500D01*
X877350Y225917D01*
X876850Y225417D01*
X876267Y225083D01*
X875600Y225000D01*
G01X879533Y230000D02*
Y225000D01*
X882867D01*
G01X888467D02*
X885133D01*
Y230000D01*
X888467D01*
G01X887133Y227583D02*
X885133D01*
G01X912300Y225000D02*
Y228333D01*
G01Y227417D02*
X912550Y227833D01*
X912967Y228167D01*
X913550Y228333D01*
X914133Y228167D01*
X914550Y227833D01*
X914800Y227417D01*
Y225000D01*
G01Y227417D02*
X915050Y227833D01*
X915467Y228167D01*
X916050Y228333D01*
X916633Y228167D01*
X917050Y227833D01*
X917300Y227333D01*
Y225000D01*
G01X920400Y228333D02*
Y225000D01*
G01Y229667D02*
X920233Y229750D01*
Y229917D01*
X920400Y230000D01*
X920567Y229917D01*
Y229750D01*
X920400Y229667D01*
G01X926000Y225000D02*
Y230000D01*
G01X930350Y225583D02*
X930767Y225250D01*
X931350Y225000D01*
X931850D01*
X932350Y225167D01*
X932683Y225417D01*
X932850Y225750D01*
X932767Y226250D01*
X932433Y226500D01*
X930933Y227000D01*
X930600Y227583D01*
X930767Y228000D01*
X931100Y228250D01*
X931600Y228333D01*
X932100Y228250D01*
X932600Y228000D01*
G01X936783Y223333D02*
X935950Y224167D01*
X935533Y225000D01*
Y228333D01*
X935950Y229167D01*
X936783Y230000D01*
G01X941133Y225000D02*
Y230000D01*
X943133D01*
X943800Y229750D01*
X944300Y229167D01*
X944467Y228500D01*
X944300Y227833D01*
X943883Y227333D01*
X943133Y227083D01*
X941133D01*
G01X948400Y230000D02*
Y225000D01*
G01X946483Y230000D02*
X950317D01*
G01X952250Y225000D02*
Y230000D01*
G01X955750D02*
Y225000D01*
G01Y227500D02*
X952250D01*
G01X960017Y223333D02*
X960850Y224167D01*
X961267Y225000D01*
Y228333D01*
X960850Y229167D01*
X960017Y230000D01*
G01X909250Y257083D02*
X909667Y256750D01*
X910250Y256500D01*
X910750D01*
X911250Y256667D01*
X911583Y256917D01*
X911750Y257250D01*
X911667Y257750D01*
X911333Y258000D01*
X909833Y258500D01*
X909500Y259083D01*
X909667Y259500D01*
X910000Y259750D01*
X910500Y259833D01*
X911000Y259750D01*
X911500Y259500D01*
G01X916100Y261500D02*
Y256500D01*
G01X914933Y259833D02*
X917267D01*
G01X920283D02*
Y257500D01*
X920617Y256917D01*
X921117Y256583D01*
X921700Y256500D01*
X922283Y256583D01*
X922783Y256917D01*
X923117Y257500D01*
G01Y256500D02*
Y259833D01*
G01X925800Y256500D02*
Y261500D01*
G01Y259000D02*
X926217Y259500D01*
X926717Y259750D01*
X927217Y259833D01*
X927967Y259667D01*
X928467Y259333D01*
X928800Y258750D01*
Y258083D01*
X928633Y257417D01*
X928300Y256917D01*
X927717Y256583D01*
X927217Y256500D01*
X926717Y256583D01*
X926217Y256833D01*
X925800Y257250D01*
G01X938500Y256500D02*
Y261500D01*
G01X942850Y258750D02*
X945517D01*
X945267Y259333D01*
X944850Y259667D01*
X944267Y259833D01*
X943683Y259750D01*
X943183Y259500D01*
X942850Y258917D01*
X942683Y258417D01*
Y257917D01*
X942850Y257417D01*
X943267Y256917D01*
X943767Y256583D01*
X944350Y256500D01*
X944933Y256667D01*
X945517Y257167D01*
G01X948283Y256500D02*
Y259833D01*
G01Y259000D02*
X948617Y259417D01*
X949117Y259750D01*
X949783Y259833D01*
X950367Y259750D01*
X950867Y259417D01*
X951117Y258833D01*
Y256500D01*
G01X954133Y255250D02*
X954717Y254917D01*
X955383Y254833D01*
X955967Y254917D01*
X956467Y255333D01*
X956800Y255917D01*
Y259833D01*
G01Y259167D02*
X956467Y259500D01*
X955967Y259750D01*
X955383Y259833D01*
X954717Y259667D01*
X954300Y259333D01*
X953967Y258750D01*
X953800Y258167D01*
X953883Y257667D01*
X954217Y257083D01*
X954717Y256667D01*
X955383Y256500D01*
X955883Y256583D01*
X956467Y256917D01*
X956800Y257250D01*
G01X960900Y261500D02*
Y256500D01*
G01X959733Y259833D02*
X962067D01*
G01X965083Y256500D02*
Y261500D01*
G01Y259083D02*
X965500Y259500D01*
X965917Y259750D01*
X966583Y259833D01*
X967083Y259750D01*
X967667Y259417D01*
X967917Y258917D01*
Y256500D01*
G01X971017Y257417D02*
X973183D01*
G01Y258917D02*
X971017D01*
G01X976117Y258583D02*
X976700Y259167D01*
X977200Y259500D01*
X977867Y259667D01*
X978450Y259500D01*
X978867Y259167D01*
X979200Y258667D01*
X979283Y258083D01*
X979200Y257583D01*
X978867Y257083D01*
X978367Y256667D01*
X977783Y256500D01*
X977117Y256667D01*
X976533Y257167D01*
X976200Y257917D01*
X976117Y258750D01*
X976283Y259833D01*
X976533Y260417D01*
X976950Y261000D01*
X977533Y261417D01*
X978117Y261500D01*
X978700Y261333D01*
X979117Y260917D01*
G01X982383Y258167D02*
X984383D01*
G01X983300Y259250D02*
Y257083D01*
G01X987400Y256333D02*
X990400Y261500D01*
G01X993417Y258167D02*
X995583D01*
G01X998267Y257250D02*
X998767Y256833D01*
X999350Y256583D01*
X1000100Y256500D01*
X1000850Y256667D01*
X1001433Y257000D01*
X1001850Y257583D01*
X1001933Y258250D01*
X1001767Y258917D01*
X1001350Y259333D01*
X1000767Y259667D01*
X1000183Y259750D01*
X999600Y259667D01*
X998850Y259333D01*
X999100Y261500D01*
X1001350D01*
G01X1003200Y256500D02*
Y259833D01*
G01Y258917D02*
X1003450Y259333D01*
X1003867Y259667D01*
X1004450Y259833D01*
X1005033Y259667D01*
X1005450Y259333D01*
X1005700Y258917D01*
Y256500D01*
G01Y258917D02*
X1005950Y259333D01*
X1006367Y259667D01*
X1006950Y259833D01*
X1007533Y259667D01*
X1007950Y259333D01*
X1008200Y258833D01*
Y256500D01*
G01X1011300Y259833D02*
Y256500D01*
G01Y261167D02*
X1011133Y261250D01*
Y261417D01*
X1011300Y261500D01*
X1011467Y261417D01*
Y261250D01*
X1011300Y261167D01*
G01X1016900Y256500D02*
Y261500D01*
G01X900833Y287500D02*
Y282500D01*
X904167D01*
G01X906683D02*
Y285833D01*
G01Y285000D02*
X907017Y285417D01*
X907517Y285750D01*
X908183Y285833D01*
X908767Y285750D01*
X909267Y285417D01*
X909517Y284833D01*
Y282500D01*
G01X902833Y328500D02*
Y323500D01*
X906167D01*
G01X908850Y326833D02*
X911350Y323500D01*
G01Y326833D02*
X908850Y323500D01*
G01X868167Y391167D02*
X868500Y391417D01*
X868750Y391833D01*
X868917Y392417D01*
X868750Y392917D01*
X868417Y393250D01*
X867833Y393500D01*
X865583D01*
Y388500D01*
X868333D01*
X868917Y388833D01*
X869250Y389333D01*
X869417Y389917D01*
X869250Y390500D01*
X868750Y391000D01*
X868167Y391167D01*
X865583D01*
G01X871017Y388500D02*
X873100Y393500D01*
X875183Y388500D01*
G01X874433Y390250D02*
X871767D01*
G01X880533Y393083D02*
X880033Y393333D01*
X879450Y393500D01*
X878783D01*
X878033Y393250D01*
X877450Y392833D01*
X877033Y392333D01*
X876700Y391500D01*
X876617Y390750D01*
X876783Y390000D01*
X877033Y389500D01*
X877533Y389000D01*
X878117Y388667D01*
X878700Y388500D01*
X879283D01*
X879867Y388667D01*
X880367Y388917D01*
X880783Y389250D01*
G01X882467Y388500D02*
Y393500D01*
G01X885633D02*
X882467Y390417D01*
G01X886133Y388500D02*
X883883Y391833D01*
G01X893667Y388500D02*
Y393500D01*
X895333D01*
X896000Y393250D01*
X896500Y392917D01*
X896917Y392417D01*
X897250Y391833D01*
X897333Y391000D01*
X897250Y390167D01*
X896917Y389583D01*
X896500Y389083D01*
X896000Y388750D01*
X895333Y388500D01*
X893667D01*
G01X899433D02*
Y393500D01*
X901517D01*
X902183Y393250D01*
X902600Y392917D01*
X902767Y392250D01*
X902600Y391583D01*
X902100Y391167D01*
X901517Y390917D01*
X899433D01*
G01X901517D02*
X902767Y388500D01*
G01X905700Y393500D02*
X907700D01*
G01X906700D02*
Y388500D01*
G01X905700D02*
X907700D01*
G01X910633Y393500D02*
Y388500D01*
X913967D01*
G01X916233Y393500D02*
Y388500D01*
X919567D01*
G01X943400D02*
Y391833D01*
G01Y390917D02*
X943650Y391333D01*
X944067Y391667D01*
X944650Y391833D01*
X945233Y391667D01*
X945650Y391333D01*
X945900Y390917D01*
Y388500D01*
G01Y390917D02*
X946150Y391333D01*
X946567Y391667D01*
X947150Y391833D01*
X947733Y391667D01*
X948150Y391333D01*
X948400Y390833D01*
Y388500D01*
G01X951500Y391833D02*
Y388500D01*
G01Y393167D02*
X951333Y393250D01*
Y393417D01*
X951500Y393500D01*
X951667Y393417D01*
Y393250D01*
X951500Y393167D01*
G01X957100Y388500D02*
Y393500D01*
G01X961450Y389083D02*
X961867Y388750D01*
X962450Y388500D01*
X962950D01*
X963450Y388667D01*
X963783Y388917D01*
X963950Y389250D01*
X963867Y389750D01*
X963533Y390000D01*
X962033Y390500D01*
X961700Y391083D01*
X961867Y391500D01*
X962200Y391750D01*
X962700Y391833D01*
X963200Y391750D01*
X963700Y391500D01*
G01X967883Y386833D02*
X967050Y387667D01*
X966633Y388500D01*
Y391833D01*
X967050Y392667D01*
X967883Y393500D01*
G01X971983Y388500D02*
Y393500D01*
X975817Y388500D01*
Y393500D01*
G01X977833Y388500D02*
Y393500D01*
X979833D01*
X980500Y393250D01*
X981000Y392667D01*
X981167Y392000D01*
X981000Y391333D01*
X980583Y390833D01*
X979833Y390583D01*
X977833D01*
G01X985100Y393500D02*
Y388500D01*
G01X983183Y393500D02*
X987017D01*
G01X988950Y388500D02*
Y393500D01*
G01X992450D02*
Y388500D01*
G01Y391000D02*
X988950D01*
G01X996717Y386833D02*
X997550Y387667D01*
X997967Y388500D01*
Y391833D01*
X997550Y392667D01*
X996717Y393500D01*
G01X894000Y641000D02*
Y636000D01*
G01X892833Y639333D02*
X895167D01*
G01X898183Y636000D02*
Y641000D01*
G01Y638583D02*
X898600Y639000D01*
X899017Y639250D01*
X899683Y639333D01*
X900183Y639250D01*
X900767Y638917D01*
X901017Y638417D01*
Y636000D01*
G01X903950Y638250D02*
X906617D01*
X906367Y638833D01*
X905950Y639167D01*
X905367Y639333D01*
X904783Y639250D01*
X904283Y639000D01*
X903950Y638417D01*
X903783Y637917D01*
Y637417D01*
X903950Y636917D01*
X904367Y636417D01*
X904867Y636083D01*
X905450Y636000D01*
X906033Y636167D01*
X906617Y636667D01*
G01X916400Y636000D02*
X915900Y636083D01*
X915400Y636417D01*
X915067Y637000D01*
X914900Y637667D01*
X915067Y638333D01*
X915400Y638917D01*
X915900Y639250D01*
X916400Y639333D01*
X916900Y639250D01*
X917400Y638917D01*
X917733Y638333D01*
X917817Y637667D01*
X917733Y637000D01*
X917400Y636417D01*
X916900Y636083D01*
X916400Y636000D01*
G01X922000Y641000D02*
Y636000D01*
G01X920833Y639333D02*
X923167D01*
G01X926183Y636000D02*
Y641000D01*
G01Y638583D02*
X926600Y639000D01*
X927017Y639250D01*
X927683Y639333D01*
X928183Y639250D01*
X928767Y638917D01*
X929017Y638417D01*
Y636000D01*
G01X931950Y638250D02*
X934617D01*
X934367Y638833D01*
X933950Y639167D01*
X933367Y639333D01*
X932783Y639250D01*
X932283Y639000D01*
X931950Y638417D01*
X931783Y637917D01*
Y637417D01*
X931950Y636917D01*
X932367Y636417D01*
X932867Y636083D01*
X933450Y636000D01*
X934033Y636167D01*
X934617Y636667D01*
G01X937633Y636000D02*
Y639333D01*
G01Y638667D02*
X938050Y639000D01*
X938467Y639250D01*
X939050Y639333D01*
X939467Y639250D01*
X939967Y639000D01*
G01X948750Y636583D02*
X949167Y636250D01*
X949750Y636000D01*
X950250D01*
X950750Y636167D01*
X951083Y636417D01*
X951250Y636750D01*
X951167Y637250D01*
X950833Y637500D01*
X949333Y638000D01*
X949000Y638583D01*
X949167Y639000D01*
X949500Y639250D01*
X950000Y639333D01*
X950500Y639250D01*
X951000Y639000D01*
G01X955600Y639333D02*
Y636000D01*
G01Y640667D02*
X955433Y640750D01*
Y640917D01*
X955600Y641000D01*
X955767Y640917D01*
Y640750D01*
X955600Y640667D01*
G01X962700Y641000D02*
Y636000D01*
G01Y636750D02*
X962367Y636333D01*
X961867Y636083D01*
X961283Y636000D01*
X960617Y636167D01*
X960117Y636583D01*
X959783Y637083D01*
X959700Y637667D01*
X959783Y638250D01*
X960117Y638750D01*
X960617Y639167D01*
X961283Y639333D01*
X961867Y639250D01*
X962283Y639083D01*
X962700Y638750D01*
G01X965550Y638250D02*
X968217D01*
X967967Y638833D01*
X967550Y639167D01*
X966967Y639333D01*
X966383Y639250D01*
X965883Y639000D01*
X965550Y638417D01*
X965383Y637917D01*
Y637417D01*
X965550Y636917D01*
X965967Y636417D01*
X966467Y636083D01*
X967050Y636000D01*
X967633Y636167D01*
X968217Y636667D01*
G01X975917Y639333D02*
X976917Y636000D01*
X978000Y639333D01*
X979083Y636000D01*
X980083Y639333D01*
G01X983600D02*
Y636000D01*
G01Y640667D02*
X983433Y640750D01*
Y640917D01*
X983600Y641000D01*
X983767Y640917D01*
Y640750D01*
X983600Y640667D01*
G01X989200Y641000D02*
Y636000D01*
G01X988033Y639333D02*
X990367D01*
G01X993383Y636000D02*
Y641000D01*
G01Y638583D02*
X993800Y639000D01*
X994217Y639250D01*
X994883Y639333D01*
X995383Y639250D01*
X995967Y638917D01*
X996217Y638417D01*
Y636000D01*
G01X1000400D02*
X999900Y636083D01*
X999400Y636417D01*
X999067Y637000D01*
X998900Y637667D01*
X999067Y638333D01*
X999400Y638917D01*
X999900Y639250D01*
X1000400Y639333D01*
X1000900Y639250D01*
X1001400Y638917D01*
X1001733Y638333D01*
X1001817Y637667D01*
X1001733Y637000D01*
X1001400Y636417D01*
X1000900Y636083D01*
X1000400Y636000D01*
G01X1004583Y639333D02*
Y637000D01*
X1004917Y636417D01*
X1005417Y636083D01*
X1006000Y636000D01*
X1006583Y636083D01*
X1007083Y636417D01*
X1007417Y637000D01*
G01Y636000D02*
Y639333D01*
G01X1011600Y641000D02*
Y636000D01*
G01X1010433Y639333D02*
X1012767D01*
G01X878000Y671500D02*
X879667D01*
Y670000D01*
X879167Y669500D01*
X878583Y669167D01*
X877750Y669000D01*
X876917Y669167D01*
X876333Y669500D01*
X875833Y670000D01*
X875500Y670583D01*
X875333Y671250D01*
Y671833D01*
X875500Y672333D01*
X875833Y672917D01*
X876333Y673417D01*
X876833Y673750D01*
X877500Y674000D01*
X878083D01*
X878750Y673833D01*
X879250Y673500D01*
G01X881850Y671250D02*
X884517D01*
X884267Y671833D01*
X883850Y672167D01*
X883267Y672333D01*
X882683Y672250D01*
X882183Y672000D01*
X881850Y671417D01*
X881683Y670917D01*
Y670417D01*
X881850Y669917D01*
X882267Y669417D01*
X882767Y669083D01*
X883350Y669000D01*
X883933Y669167D01*
X884517Y669667D01*
G01X887533Y669000D02*
Y672333D01*
G01Y671667D02*
X887950Y672000D01*
X888367Y672250D01*
X888950Y672333D01*
X889367Y672250D01*
X889867Y672000D01*
G01X892800Y669000D02*
Y674000D01*
G01Y671500D02*
X893217Y672000D01*
X893717Y672250D01*
X894217Y672333D01*
X894967Y672167D01*
X895467Y671833D01*
X895800Y671250D01*
Y670583D01*
X895633Y669917D01*
X895300Y669417D01*
X894717Y669083D01*
X894217Y669000D01*
X893717Y669083D01*
X893217Y669333D01*
X892800Y669750D01*
G01X898650Y671250D02*
X901317D01*
X901067Y671833D01*
X900650Y672167D01*
X900067Y672333D01*
X899483Y672250D01*
X898983Y672000D01*
X898650Y671417D01*
X898483Y670917D01*
Y670417D01*
X898650Y669917D01*
X899067Y669417D01*
X899567Y669083D01*
X900150Y669000D01*
X900733Y669167D01*
X901317Y669667D01*
G01X904333Y669000D02*
Y672333D01*
G01Y671667D02*
X904750Y672000D01*
X905167Y672250D01*
X905750Y672333D01*
X906167Y672250D01*
X906667Y672000D01*
G01X918200Y674000D02*
Y669000D01*
G01Y669750D02*
X917867Y669333D01*
X917367Y669083D01*
X916783Y669000D01*
X916117Y669167D01*
X915617Y669583D01*
X915283Y670083D01*
X915200Y670667D01*
X915283Y671250D01*
X915617Y671750D01*
X916117Y672167D01*
X916783Y672333D01*
X917367Y672250D01*
X917783Y672083D01*
X918200Y671750D01*
G01X921050Y671250D02*
X923717D01*
X923467Y671833D01*
X923050Y672167D01*
X922467Y672333D01*
X921883Y672250D01*
X921383Y672000D01*
X921050Y671417D01*
X920883Y670917D01*
Y670417D01*
X921050Y669917D01*
X921467Y669417D01*
X921967Y669083D01*
X922550Y669000D01*
X923133Y669167D01*
X923717Y669667D01*
G01X926650Y669583D02*
X927067Y669250D01*
X927650Y669000D01*
X928150D01*
X928650Y669167D01*
X928983Y669417D01*
X929150Y669750D01*
X929067Y670250D01*
X928733Y670500D01*
X927233Y671000D01*
X926900Y671583D01*
X927067Y672000D01*
X927400Y672250D01*
X927900Y672333D01*
X928400Y672250D01*
X928900Y672000D01*
G01X933500Y672333D02*
Y669000D01*
G01Y673667D02*
X933333Y673750D01*
Y673917D01*
X933500Y674000D01*
X933667Y673917D01*
Y673750D01*
X933500Y673667D01*
G01X937933Y667750D02*
X938517Y667417D01*
X939183Y667333D01*
X939767Y667417D01*
X940267Y667833D01*
X940600Y668417D01*
Y672333D01*
G01Y671667D02*
X940267Y672000D01*
X939767Y672250D01*
X939183Y672333D01*
X938517Y672167D01*
X938100Y671833D01*
X937767Y671250D01*
X937600Y670667D01*
X937683Y670167D01*
X938017Y669583D01*
X938517Y669167D01*
X939183Y669000D01*
X939683Y669083D01*
X940267Y669417D01*
X940600Y669750D01*
G01X943283Y669000D02*
Y672333D01*
G01Y671500D02*
X943617Y671917D01*
X944117Y672250D01*
X944783Y672333D01*
X945367Y672250D01*
X945867Y671917D01*
X946117Y671333D01*
Y669000D01*
G01X843083Y804500D02*
Y809500D01*
G01Y807083D02*
X843500Y807500D01*
X843917Y807750D01*
X844583Y807833D01*
X845083Y807750D01*
X845667Y807417D01*
X845917Y806917D01*
Y804500D01*
G01X851600D02*
Y807833D01*
G01Y807250D02*
X851267Y807583D01*
X850767Y807750D01*
X850183Y807833D01*
X849600Y807667D01*
X849100Y807333D01*
X848767Y806833D01*
X848600Y806167D01*
X848767Y805500D01*
X849100Y805000D01*
X849600Y804667D01*
X850183Y804500D01*
X850767Y804583D01*
X851267Y804833D01*
X851600Y805167D01*
G01X855700Y804500D02*
Y809500D01*
G01X860800Y804500D02*
Y808750D01*
X860967Y809167D01*
X861300Y809417D01*
X861800Y809500D01*
X862300Y809333D01*
X862550Y808917D01*
G01X861550Y807500D02*
X859883D01*
G01X871000Y802833D02*
Y807833D01*
G01Y807083D02*
X871417Y807500D01*
X871833Y807750D01*
X872500Y807833D01*
X873083Y807750D01*
X873667Y807333D01*
X873917Y806750D01*
X874000Y806167D01*
X873917Y805583D01*
X873667Y805000D01*
X873167Y804667D01*
X872500Y804500D01*
X871917Y804583D01*
X871333Y804833D01*
X871000Y805167D01*
G01X878100Y804500D02*
Y809500D01*
G01X882283Y807833D02*
Y805500D01*
X882617Y804917D01*
X883117Y804583D01*
X883700Y804500D01*
X884283Y804583D01*
X884783Y804917D01*
X885117Y805500D01*
G01Y804500D02*
Y807833D01*
G01X888133Y803250D02*
X888717Y802917D01*
X889383Y802833D01*
X889967Y802917D01*
X890467Y803333D01*
X890800Y803917D01*
Y807833D01*
G01Y807167D02*
X890467Y807500D01*
X889967Y807750D01*
X889383Y807833D01*
X888717Y807667D01*
X888300Y807333D01*
X887967Y806750D01*
X887800Y806167D01*
X887883Y805667D01*
X888217Y805083D01*
X888717Y804667D01*
X889383Y804500D01*
X889883Y804583D01*
X890467Y804917D01*
X890800Y805250D01*
G01X893733Y803250D02*
X894317Y802917D01*
X894983Y802833D01*
X895567Y802917D01*
X896067Y803333D01*
X896400Y803917D01*
Y807833D01*
G01Y807167D02*
X896067Y807500D01*
X895567Y807750D01*
X894983Y807833D01*
X894317Y807667D01*
X893900Y807333D01*
X893567Y806750D01*
X893400Y806167D01*
X893483Y805667D01*
X893817Y805083D01*
X894317Y804667D01*
X894983Y804500D01*
X895483Y804583D01*
X896067Y804917D01*
X896400Y805250D01*
G01X900500Y807833D02*
Y804500D01*
G01Y809167D02*
X900333Y809250D01*
Y809417D01*
X900500Y809500D01*
X900667Y809417D01*
Y809250D01*
X900500Y809167D01*
G01X904683Y804500D02*
Y807833D01*
G01Y807000D02*
X905017Y807417D01*
X905517Y807750D01*
X906183Y807833D01*
X906767Y807750D01*
X907267Y807417D01*
X907517Y806833D01*
Y804500D01*
G01X910533Y803250D02*
X911117Y802917D01*
X911783Y802833D01*
X912367Y802917D01*
X912867Y803333D01*
X913200Y803917D01*
Y807833D01*
G01Y807167D02*
X912867Y807500D01*
X912367Y807750D01*
X911783Y807833D01*
X911117Y807667D01*
X910700Y807333D01*
X910367Y806750D01*
X910200Y806167D01*
X910283Y805667D01*
X910617Y805083D01*
X911117Y804667D01*
X911783Y804500D01*
X912283Y804583D01*
X912867Y804917D01*
X913200Y805250D01*
G01X995667Y43500D02*
Y48500D01*
X997333D01*
X998000Y48250D01*
X998500Y47917D01*
X998917Y47417D01*
X999250Y46833D01*
X999333Y46000D01*
X999250Y45167D01*
X998917Y44583D01*
X998500Y44083D01*
X998000Y43750D01*
X997333Y43500D01*
X995667D01*
G01X1003100D02*
Y48500D01*
X1002100Y47500D01*
G01Y43500D02*
X1004100D01*
G01X1007117Y45583D02*
X1007700Y46167D01*
X1008200Y46500D01*
X1008867Y46667D01*
X1009450Y46500D01*
X1009867Y46167D01*
X1010200Y45667D01*
X1010283Y45083D01*
X1010200Y44583D01*
X1009867Y44083D01*
X1009367Y43667D01*
X1008783Y43500D01*
X1008117Y43667D01*
X1007533Y44167D01*
X1007200Y44917D01*
X1007117Y45750D01*
X1007283Y46833D01*
X1007533Y47417D01*
X1007950Y48000D01*
X1008533Y48417D01*
X1009117Y48500D01*
X1009700Y48333D01*
X1010117Y47917D01*
G01X1014300Y43333D02*
X1014133Y43417D01*
Y43583D01*
X1014300Y43667D01*
X1014467Y43583D01*
Y43417D01*
X1014300Y43333D01*
G01Y45583D02*
X1014133Y45667D01*
Y45833D01*
X1014300Y45917D01*
X1014467Y45833D01*
Y45667D01*
X1014300Y45583D01*
G01X1018067Y43500D02*
Y48500D01*
X1019733D01*
X1020400Y48250D01*
X1020900Y47917D01*
X1021317Y47417D01*
X1021650Y46833D01*
X1021733Y46000D01*
X1021650Y45167D01*
X1021317Y44583D01*
X1020900Y44083D01*
X1020400Y43750D01*
X1019733Y43500D01*
X1018067D01*
G01X1025500Y46833D02*
Y43500D01*
G01Y48167D02*
X1025333Y48250D01*
Y48417D01*
X1025500Y48500D01*
X1025667Y48417D01*
Y48250D01*
X1025500Y48167D01*
G01X1032600Y43500D02*
Y46833D01*
G01Y46250D02*
X1032267Y46583D01*
X1031767Y46750D01*
X1031183Y46833D01*
X1030600Y46667D01*
X1030100Y46333D01*
X1029767Y45833D01*
X1029600Y45167D01*
X1029767Y44500D01*
X1030100Y44000D01*
X1030600Y43667D01*
X1031183Y43500D01*
X1031767Y43583D01*
X1032267Y43833D01*
X1032600Y44167D01*
G01X1034200Y43500D02*
Y46833D01*
G01Y45917D02*
X1034450Y46333D01*
X1034867Y46667D01*
X1035450Y46833D01*
X1036033Y46667D01*
X1036450Y46333D01*
X1036700Y45917D01*
Y43500D01*
G01Y45917D02*
X1036950Y46333D01*
X1037367Y46667D01*
X1037950Y46833D01*
X1038533Y46667D01*
X1038950Y46333D01*
X1039200Y45833D01*
Y43500D01*
G01X1041050Y45750D02*
X1043717D01*
X1043467Y46333D01*
X1043050Y46667D01*
X1042467Y46833D01*
X1041883Y46750D01*
X1041383Y46500D01*
X1041050Y45917D01*
X1040883Y45417D01*
Y44917D01*
X1041050Y44417D01*
X1041467Y43917D01*
X1041967Y43583D01*
X1042550Y43500D01*
X1043133Y43667D01*
X1043717Y44167D01*
G01X1047900Y48500D02*
Y43500D01*
G01X1046733Y46833D02*
X1049067D01*
G01X1052250Y45750D02*
X1054917D01*
X1054667Y46333D01*
X1054250Y46667D01*
X1053667Y46833D01*
X1053083Y46750D01*
X1052583Y46500D01*
X1052250Y45917D01*
X1052083Y45417D01*
Y44917D01*
X1052250Y44417D01*
X1052667Y43917D01*
X1053167Y43583D01*
X1053750Y43500D01*
X1054333Y43667D01*
X1054917Y44167D01*
G01X1057933Y43500D02*
Y46833D01*
G01Y46167D02*
X1058350Y46500D01*
X1058767Y46750D01*
X1059350Y46833D01*
X1059767Y46750D01*
X1060267Y46500D01*
G01X1070300Y43500D02*
Y48500D01*
X1069300Y47500D01*
G01Y43500D02*
X1071300D01*
G01X1074317Y45583D02*
X1074900Y46167D01*
X1075400Y46500D01*
X1076067Y46667D01*
X1076650Y46500D01*
X1077067Y46167D01*
X1077400Y45667D01*
X1077483Y45083D01*
X1077400Y44583D01*
X1077067Y44083D01*
X1076567Y43667D01*
X1075983Y43500D01*
X1075317Y43667D01*
X1074733Y44167D01*
X1074400Y44917D01*
X1074317Y45750D01*
X1074483Y46833D01*
X1074733Y47417D01*
X1075150Y48000D01*
X1075733Y48417D01*
X1076317Y48500D01*
X1076900Y48333D01*
X1077317Y47917D01*
G01X1079000Y43500D02*
Y46833D01*
G01Y45917D02*
X1079250Y46333D01*
X1079667Y46667D01*
X1080250Y46833D01*
X1080833Y46667D01*
X1081250Y46333D01*
X1081500Y45917D01*
Y43500D01*
G01Y45917D02*
X1081750Y46333D01*
X1082167Y46667D01*
X1082750Y46833D01*
X1083333Y46667D01*
X1083750Y46333D01*
X1084000Y45833D01*
Y43500D01*
G01X1087100Y46833D02*
Y43500D01*
G01Y48167D02*
X1086933Y48250D01*
Y48417D01*
X1087100Y48500D01*
X1087267Y48417D01*
Y48250D01*
X1087100Y48167D01*
G01X1092700Y43500D02*
Y48500D01*
G01X980667Y54500D02*
X977333D01*
Y59500D01*
X980667D01*
G01X979333Y57083D02*
X977333D01*
G01X983350Y57833D02*
X985850Y54500D01*
G01Y57833D02*
X983350Y54500D01*
G01X990200Y54333D02*
X990033Y54417D01*
Y54583D01*
X990200Y54667D01*
X990367Y54583D01*
Y54417D01*
X990200Y54333D01*
G01X994050Y54500D02*
Y59500D01*
G01X997550D02*
Y54500D01*
G01Y57000D02*
X994050D01*
G01X999733Y54500D02*
Y59500D01*
X1001817D01*
X1002483Y59250D01*
X1002900Y58917D01*
X1003067Y58250D01*
X1002900Y57583D01*
X1002400Y57167D01*
X1001817Y56917D01*
X999733D01*
G01X1001817D02*
X1003067Y54500D01*
G01X1008667D02*
X1005333D01*
Y59500D01*
X1008667D01*
G01X1007333Y57083D02*
X1005333D01*
G01X1013600Y54500D02*
Y59500D01*
X1010517Y55917D01*
X1014683D01*
G01X1016367Y55250D02*
X1016867Y54833D01*
X1017450Y54583D01*
X1018200Y54500D01*
X1018950Y54667D01*
X1019533Y55000D01*
X1019950Y55583D01*
X1020033Y56250D01*
X1019867Y56917D01*
X1019450Y57333D01*
X1018867Y57667D01*
X1018283Y57750D01*
X1017700Y57667D01*
X1016950Y57333D01*
X1017200Y59500D01*
X1019450D01*
G01X1022050Y54500D02*
X1025550Y59500D01*
G01X1022050D02*
X1025550Y54500D01*
G01X1027983Y55083D02*
X1028567Y54667D01*
X1029233Y54500D01*
X1029900Y54667D01*
X1030483Y55167D01*
X1030900Y55917D01*
X1031067Y56667D01*
Y57583D01*
X1030900Y58333D01*
X1030483Y59000D01*
X1029983Y59333D01*
X1029400Y59500D01*
X1028733Y59333D01*
X1028233Y59000D01*
X1027900Y58500D01*
X1027733Y57833D01*
X1027900Y57250D01*
X1028317Y56667D01*
X1028817Y56333D01*
X1029400Y56250D01*
X1030067Y56417D01*
X1030567Y56833D01*
X1031067Y57583D01*
G01X1033417Y56583D02*
X1034000Y57167D01*
X1034500Y57500D01*
X1035167Y57667D01*
X1035750Y57500D01*
X1036167Y57167D01*
X1036500Y56667D01*
X1036583Y56083D01*
X1036500Y55583D01*
X1036167Y55083D01*
X1035667Y54667D01*
X1035083Y54500D01*
X1034417Y54667D01*
X1033833Y55167D01*
X1033500Y55917D01*
X1033417Y56750D01*
X1033583Y57833D01*
X1033833Y58417D01*
X1034250Y59000D01*
X1034833Y59417D01*
X1035417Y59500D01*
X1036000Y59333D01*
X1036417Y58917D01*
G01X1040183Y52833D02*
X1039350Y53667D01*
X1038933Y54500D01*
Y57833D01*
X1039350Y58667D01*
X1040183Y59500D01*
G01X1044367Y54500D02*
Y59500D01*
X1046033D01*
X1046700Y59250D01*
X1047200Y58917D01*
X1047617Y58417D01*
X1047950Y57833D01*
X1048033Y57000D01*
X1047950Y56167D01*
X1047617Y55583D01*
X1047200Y55083D01*
X1046700Y54750D01*
X1046033Y54500D01*
X1044367D01*
G01X1051800D02*
Y59500D01*
X1050800Y58500D01*
G01Y54500D02*
X1052800D01*
G01X1055817Y56583D02*
X1056400Y57167D01*
X1056900Y57500D01*
X1057567Y57667D01*
X1058150Y57500D01*
X1058567Y57167D01*
X1058900Y56667D01*
X1058983Y56083D01*
X1058900Y55583D01*
X1058567Y55083D01*
X1058067Y54667D01*
X1057483Y54500D01*
X1056817Y54667D01*
X1056233Y55167D01*
X1055900Y55917D01*
X1055817Y56750D01*
X1055983Y57833D01*
X1056233Y58417D01*
X1056650Y59000D01*
X1057233Y59417D01*
X1057817Y59500D01*
X1058400Y59333D01*
X1058817Y58917D01*
G01X1061250Y54500D02*
X1064750Y59500D01*
G01X1061250D02*
X1064750Y54500D01*
G01X1069600D02*
Y59500D01*
X1066517Y55917D01*
X1070683D01*
G01X1074617Y52833D02*
X1075450Y53667D01*
X1075867Y54500D01*
Y57833D01*
X1075450Y58667D01*
X1074617Y59500D01*
G01X928583Y61083D02*
X929167Y60667D01*
X929833Y60500D01*
X930500Y60667D01*
X931083Y61167D01*
X931500Y61917D01*
X931667Y62667D01*
Y63583D01*
X931500Y64333D01*
X931083Y65000D01*
X930583Y65333D01*
X930000Y65500D01*
X929333Y65333D01*
X928833Y65000D01*
X928500Y64500D01*
X928333Y63833D01*
X928500Y63250D01*
X928917Y62667D01*
X929417Y62333D01*
X930000Y62250D01*
X930667Y62417D01*
X931167Y62833D01*
X931667Y63583D01*
G01X934017Y62583D02*
X934600Y63167D01*
X935100Y63500D01*
X935767Y63667D01*
X936350Y63500D01*
X936767Y63167D01*
X937100Y62667D01*
X937183Y62083D01*
X937100Y61583D01*
X936767Y61083D01*
X936267Y60667D01*
X935683Y60500D01*
X935017Y60667D01*
X934433Y61167D01*
X934100Y61917D01*
X934017Y62750D01*
X934183Y63833D01*
X934433Y64417D01*
X934850Y65000D01*
X935433Y65417D01*
X936017Y65500D01*
X936600Y65333D01*
X937017Y64917D01*
G01X977333Y103500D02*
Y108500D01*
X979417D01*
X980083Y108250D01*
X980500Y107917D01*
X980667Y107250D01*
X980500Y106583D01*
X980000Y106167D01*
X979417Y105917D01*
X977333D01*
G01X979417D02*
X980667Y103500D01*
G01X986267D02*
X982933D01*
Y108500D01*
X986267D01*
G01X984933Y106083D02*
X982933D01*
G01X992033Y108083D02*
X991533Y108333D01*
X990950Y108500D01*
X990283D01*
X989533Y108250D01*
X988950Y107833D01*
X988533Y107333D01*
X988200Y106500D01*
X988117Y105750D01*
X988283Y105000D01*
X988533Y104500D01*
X989033Y104000D01*
X989617Y103667D01*
X990200Y103500D01*
X990783D01*
X991367Y103667D01*
X991867Y103917D01*
X992283Y104250D01*
G01X995800Y108500D02*
Y103500D01*
G01X993883Y108500D02*
X997717D01*
G01X999317Y103500D02*
X1001400Y108500D01*
X1003483Y103500D01*
G01X1002733Y105250D02*
X1000067D01*
G01X1005083Y103500D02*
Y108500D01*
X1008917Y103500D01*
Y108500D01*
G01X1013100Y106000D02*
X1014767D01*
Y104500D01*
X1014267Y104000D01*
X1013683Y103667D01*
X1012850Y103500D01*
X1012017Y103667D01*
X1011433Y104000D01*
X1010933Y104500D01*
X1010600Y105083D01*
X1010433Y105750D01*
Y106333D01*
X1010600Y106833D01*
X1010933Y107417D01*
X1011433Y107917D01*
X1011933Y108250D01*
X1012600Y108500D01*
X1013183D01*
X1013850Y108333D01*
X1014350Y108000D01*
G01X1016533Y108500D02*
Y103500D01*
X1019867D01*
G01X1025467D02*
X1022133D01*
Y108500D01*
X1025467D01*
G01X1024133Y106083D02*
X1022133D01*
G01X1033167Y103500D02*
Y108500D01*
X1034833D01*
X1035500Y108250D01*
X1036000Y107917D01*
X1036417Y107417D01*
X1036750Y106833D01*
X1036833Y106000D01*
X1036750Y105167D01*
X1036417Y104583D01*
X1036000Y104083D01*
X1035500Y103750D01*
X1034833Y103500D01*
X1033167D01*
G01X1038933D02*
Y108500D01*
X1041017D01*
X1041683Y108250D01*
X1042100Y107917D01*
X1042267Y107250D01*
X1042100Y106583D01*
X1041600Y106167D01*
X1041017Y105917D01*
X1038933D01*
G01X1041017D02*
X1042267Y103500D01*
G01X1045200Y108500D02*
X1047200D01*
G01X1046200D02*
Y103500D01*
G01X1045200D02*
X1047200D01*
G01X1050133Y108500D02*
Y103500D01*
X1053467D01*
G01X1055733Y108500D02*
Y103500D01*
X1059067D01*
G01X1066850D02*
Y108500D01*
G01X1070350D02*
Y103500D01*
G01Y106000D02*
X1066850D01*
G01X1074200Y103500D02*
X1073533Y103583D01*
X1072950Y103917D01*
X1072450Y104417D01*
X1072117Y105000D01*
X1071950Y105667D01*
Y106333D01*
X1072117Y107000D01*
X1072450Y107583D01*
X1072950Y108083D01*
X1073533Y108417D01*
X1074200Y108500D01*
X1074867Y108417D01*
X1075450Y108083D01*
X1075950Y107583D01*
X1076283Y107000D01*
X1076450Y106333D01*
Y105667D01*
X1076283Y105000D01*
X1075950Y104417D01*
X1075450Y103917D01*
X1074867Y103583D01*
X1074200Y103500D01*
G01X1078133Y108500D02*
Y103500D01*
X1081467D01*
G01X1087067D02*
X1083733D01*
Y108500D01*
X1087067D01*
G01X1085733Y106083D02*
X1083733D01*
G01X1094767Y103500D02*
Y108500D01*
X1096433D01*
X1097100Y108250D01*
X1097600Y107917D01*
X1098017Y107417D01*
X1098350Y106833D01*
X1098433Y106000D01*
X1098350Y105167D01*
X1098017Y104583D01*
X1097600Y104083D01*
X1097100Y103750D01*
X1096433Y103500D01*
X1094767D01*
G01X1103867D02*
X1100533D01*
Y108500D01*
X1103867D01*
G01X1102533Y106083D02*
X1100533D01*
G01X1106217Y103500D02*
Y108500D01*
X1109383D01*
G01X1108217Y106083D02*
X1106217D01*
G01X1112400Y108500D02*
X1114400D01*
G01X1113400D02*
Y103500D01*
G01X1112400D02*
X1114400D01*
G01X1117083D02*
Y108500D01*
X1120917Y103500D01*
Y108500D01*
G01X1126267Y103500D02*
X1122933D01*
Y108500D01*
X1126267D01*
G01X1124933Y106083D02*
X1122933D01*
G01X929000Y804500D02*
Y808750D01*
X929167Y809167D01*
X929500Y809417D01*
X930000Y809500D01*
X930500Y809333D01*
X930750Y808917D01*
G01X929750Y807500D02*
X928083D01*
G01X933683Y807833D02*
Y805500D01*
X934017Y804917D01*
X934517Y804583D01*
X935100Y804500D01*
X935683Y804583D01*
X936183Y804917D01*
X936517Y805500D01*
G01Y804500D02*
Y807833D01*
G01X940700Y804500D02*
Y809500D01*
G01X946300Y804500D02*
Y809500D01*
G01X956000Y802833D02*
Y807833D01*
G01Y807083D02*
X956417Y807500D01*
X956833Y807750D01*
X957500Y807833D01*
X958083Y807750D01*
X958667Y807333D01*
X958917Y806750D01*
X959000Y806167D01*
X958917Y805583D01*
X958667Y805000D01*
X958167Y804667D01*
X957500Y804500D01*
X956917Y804583D01*
X956333Y804833D01*
X956000Y805167D01*
G01X963100Y804500D02*
Y809500D01*
G01X967283Y807833D02*
Y805500D01*
X967617Y804917D01*
X968117Y804583D01*
X968700Y804500D01*
X969283Y804583D01*
X969783Y804917D01*
X970117Y805500D01*
G01Y804500D02*
Y807833D01*
G01X973133Y803250D02*
X973717Y802917D01*
X974383Y802833D01*
X974967Y802917D01*
X975467Y803333D01*
X975800Y803917D01*
Y807833D01*
G01Y807167D02*
X975467Y807500D01*
X974967Y807750D01*
X974383Y807833D01*
X973717Y807667D01*
X973300Y807333D01*
X972967Y806750D01*
X972800Y806167D01*
X972883Y805667D01*
X973217Y805083D01*
X973717Y804667D01*
X974383Y804500D01*
X974883Y804583D01*
X975467Y804917D01*
X975800Y805250D01*
G01X978733Y803250D02*
X979317Y802917D01*
X979983Y802833D01*
X980567Y802917D01*
X981067Y803333D01*
X981400Y803917D01*
Y807833D01*
G01Y807167D02*
X981067Y807500D01*
X980567Y807750D01*
X979983Y807833D01*
X979317Y807667D01*
X978900Y807333D01*
X978567Y806750D01*
X978400Y806167D01*
X978483Y805667D01*
X978817Y805083D01*
X979317Y804667D01*
X979983Y804500D01*
X980483Y804583D01*
X981067Y804917D01*
X981400Y805250D01*
G01X985500Y807833D02*
Y804500D01*
G01Y809167D02*
X985333Y809250D01*
Y809417D01*
X985500Y809500D01*
X985667Y809417D01*
Y809250D01*
X985500Y809167D01*
G01X989683Y804500D02*
Y807833D01*
G01Y807000D02*
X990017Y807417D01*
X990517Y807750D01*
X991183Y807833D01*
X991767Y807750D01*
X992267Y807417D01*
X992517Y806833D01*
Y804500D01*
G01X995533Y803250D02*
X996117Y802917D01*
X996783Y802833D01*
X997367Y802917D01*
X997867Y803333D01*
X998200Y803917D01*
Y807833D01*
G01Y807167D02*
X997867Y807500D01*
X997367Y807750D01*
X996783Y807833D01*
X996117Y807667D01*
X995700Y807333D01*
X995367Y806750D01*
X995200Y806167D01*
X995283Y805667D01*
X995617Y805083D01*
X996117Y804667D01*
X996783Y804500D01*
X997283Y804583D01*
X997867Y804917D01*
X998200Y805250D01*
G01X1026000Y429000D02*
Y139000D01*
G01X1087667Y197000D02*
Y202000D01*
X1089333D01*
X1090000Y201750D01*
X1090500Y201417D01*
X1090917Y200917D01*
X1091250Y200333D01*
X1091333Y199500D01*
X1091250Y198667D01*
X1090917Y198083D01*
X1090500Y197583D01*
X1090000Y197250D01*
X1089333Y197000D01*
X1087667D01*
G01X1093933D02*
Y200333D01*
G01Y199667D02*
X1094350Y200000D01*
X1094767Y200250D01*
X1095350Y200333D01*
X1095767Y200250D01*
X1096267Y200000D01*
G01X1100700Y200333D02*
Y197000D01*
G01Y201667D02*
X1100533Y201750D01*
Y201917D01*
X1100700Y202000D01*
X1100867Y201917D01*
Y201750D01*
X1100700Y201667D01*
G01X1106300Y197000D02*
Y202000D01*
G01X1111900Y197000D02*
Y202000D01*
G01X1121517Y197000D02*
Y202000D01*
X1124683D01*
G01X1123517Y199583D02*
X1121517D01*
G01X1127533Y197000D02*
Y200333D01*
G01Y199667D02*
X1127950Y200000D01*
X1128367Y200250D01*
X1128950Y200333D01*
X1129367Y200250D01*
X1129867Y200000D01*
G01X1134300Y197000D02*
X1133800Y197083D01*
X1133300Y197417D01*
X1132967Y198000D01*
X1132800Y198667D01*
X1132967Y199333D01*
X1133300Y199917D01*
X1133800Y200250D01*
X1134300Y200333D01*
X1134800Y200250D01*
X1135300Y199917D01*
X1135633Y199333D01*
X1135717Y198667D01*
X1135633Y198000D01*
X1135300Y197417D01*
X1134800Y197083D01*
X1134300Y197000D01*
G01X1137400D02*
Y200333D01*
G01Y199417D02*
X1137650Y199833D01*
X1138067Y200167D01*
X1138650Y200333D01*
X1139233Y200167D01*
X1139650Y199833D01*
X1139900Y199417D01*
Y197000D01*
G01Y199417D02*
X1140150Y199833D01*
X1140567Y200167D01*
X1141150Y200333D01*
X1141733Y200167D01*
X1142150Y199833D01*
X1142400Y199333D01*
Y197000D01*
G01X1167483Y195333D02*
X1166650Y196167D01*
X1166233Y197000D01*
Y200333D01*
X1166650Y201167D01*
X1167483Y202000D01*
G01X1174167Y199667D02*
X1174500Y199917D01*
X1174750Y200333D01*
X1174917Y200917D01*
X1174750Y201417D01*
X1174417Y201750D01*
X1173833Y202000D01*
X1171583D01*
Y197000D01*
X1174333D01*
X1174917Y197333D01*
X1175250Y197833D01*
X1175417Y198417D01*
X1175250Y199000D01*
X1174750Y199500D01*
X1174167Y199667D01*
X1171583D01*
G01X1179100Y197000D02*
X1178433Y197083D01*
X1177850Y197417D01*
X1177350Y197917D01*
X1177017Y198500D01*
X1176850Y199167D01*
Y199833D01*
X1177017Y200500D01*
X1177350Y201083D01*
X1177850Y201583D01*
X1178433Y201917D01*
X1179100Y202000D01*
X1179767Y201917D01*
X1180350Y201583D01*
X1180850Y201083D01*
X1181183Y200500D01*
X1181350Y199833D01*
Y199167D01*
X1181183Y198500D01*
X1180850Y197917D01*
X1180350Y197417D01*
X1179767Y197083D01*
X1179100Y197000D01*
G01X1184700Y202000D02*
Y197000D01*
G01X1182783Y202000D02*
X1186617D01*
G01X1190300D02*
Y197000D01*
G01X1188383Y202000D02*
X1192217D01*
G01X1195900Y197000D02*
X1195233Y197083D01*
X1194650Y197417D01*
X1194150Y197917D01*
X1193817Y198500D01*
X1193650Y199167D01*
Y199833D01*
X1193817Y200500D01*
X1194150Y201083D01*
X1194650Y201583D01*
X1195233Y201917D01*
X1195900Y202000D01*
X1196567Y201917D01*
X1197150Y201583D01*
X1197650Y201083D01*
X1197983Y200500D01*
X1198150Y199833D01*
Y199167D01*
X1197983Y198500D01*
X1197650Y197917D01*
X1197150Y197417D01*
X1196567Y197083D01*
X1195900Y197000D01*
G01X1199333D02*
Y202000D01*
X1201500Y197833D01*
X1203667Y202000D01*
Y197000D01*
G01X1207517Y195333D02*
X1208350Y196167D01*
X1208767Y197000D01*
Y200333D01*
X1208350Y201167D01*
X1207517Y202000D01*
G01X1218300D02*
Y197000D01*
G01X1217133Y200333D02*
X1219467D01*
G01X1223900Y197000D02*
X1223400Y197083D01*
X1222900Y197417D01*
X1222567Y198000D01*
X1222400Y198667D01*
X1222567Y199333D01*
X1222900Y199917D01*
X1223400Y200250D01*
X1223900Y200333D01*
X1224400Y200250D01*
X1224900Y199917D01*
X1225233Y199333D01*
X1225317Y198667D01*
X1225233Y198000D01*
X1224900Y197417D01*
X1224400Y197083D01*
X1223900Y197000D01*
G01X1233433Y202000D02*
Y197000D01*
X1236767D01*
G01X1239450Y200333D02*
X1241950Y197000D01*
G01Y200333D02*
X1239450Y197000D01*
G01X1033500Y463500D02*
Y468500D01*
G01Y466000D02*
X1033917Y466500D01*
X1034417Y466750D01*
X1034917Y466833D01*
X1035667Y466667D01*
X1036167Y466333D01*
X1036500Y465750D01*
Y465083D01*
X1036333Y464417D01*
X1036000Y463917D01*
X1035417Y463583D01*
X1034917Y463500D01*
X1034417Y463583D01*
X1033917Y463833D01*
X1033500Y464250D01*
G01X1039183Y466833D02*
Y464500D01*
X1039517Y463917D01*
X1040017Y463583D01*
X1040600Y463500D01*
X1041183Y463583D01*
X1041683Y463917D01*
X1042017Y464500D01*
G01Y463500D02*
Y466833D01*
G01X1044700Y463500D02*
Y468500D01*
G01Y466000D02*
X1045117Y466500D01*
X1045617Y466750D01*
X1046117Y466833D01*
X1046867Y466667D01*
X1047367Y466333D01*
X1047700Y465750D01*
Y465083D01*
X1047533Y464417D01*
X1047200Y463917D01*
X1046617Y463583D01*
X1046117Y463500D01*
X1045617Y463583D01*
X1045117Y463833D01*
X1044700Y464250D01*
G01X1050300Y463500D02*
Y468500D01*
G01Y466000D02*
X1050717Y466500D01*
X1051217Y466750D01*
X1051717Y466833D01*
X1052467Y466667D01*
X1052967Y466333D01*
X1053300Y465750D01*
Y465083D01*
X1053133Y464417D01*
X1052800Y463917D01*
X1052217Y463583D01*
X1051717Y463500D01*
X1051217Y463583D01*
X1050717Y463833D01*
X1050300Y464250D01*
G01X1057400Y463500D02*
Y468500D01*
G01X1061750Y465750D02*
X1064417D01*
X1064167Y466333D01*
X1063750Y466667D01*
X1063167Y466833D01*
X1062583Y466750D01*
X1062083Y466500D01*
X1061750Y465917D01*
X1061583Y465417D01*
Y464917D01*
X1061750Y464417D01*
X1062167Y463917D01*
X1062667Y463583D01*
X1063250Y463500D01*
X1063833Y463667D01*
X1064417Y464167D01*
G01X1074200Y466833D02*
Y463500D01*
G01Y468167D02*
X1074033Y468250D01*
Y468417D01*
X1074200Y468500D01*
X1074367Y468417D01*
Y468250D01*
X1074200Y468167D01*
G01X1078383Y463500D02*
Y466833D01*
G01Y466000D02*
X1078717Y466417D01*
X1079217Y466750D01*
X1079883Y466833D01*
X1080467Y466750D01*
X1080967Y466417D01*
X1081217Y465833D01*
Y463500D01*
G01X1084150Y464083D02*
X1084567Y463750D01*
X1085150Y463500D01*
X1085650D01*
X1086150Y463667D01*
X1086483Y463917D01*
X1086650Y464250D01*
X1086567Y464750D01*
X1086233Y465000D01*
X1084733Y465500D01*
X1084400Y466083D01*
X1084567Y466500D01*
X1084900Y466750D01*
X1085400Y466833D01*
X1085900Y466750D01*
X1086400Y466500D01*
G01X1091000Y466833D02*
Y463500D01*
G01Y468167D02*
X1090833Y468250D01*
Y468417D01*
X1091000Y468500D01*
X1091167Y468417D01*
Y468250D01*
X1091000Y468167D01*
G01X1098100Y468500D02*
Y463500D01*
G01Y464250D02*
X1097767Y463833D01*
X1097267Y463583D01*
X1096683Y463500D01*
X1096017Y463667D01*
X1095517Y464083D01*
X1095183Y464583D01*
X1095100Y465167D01*
X1095183Y465750D01*
X1095517Y466250D01*
X1096017Y466667D01*
X1096683Y466833D01*
X1097267Y466750D01*
X1097683Y466583D01*
X1098100Y466250D01*
G01X1100950Y465750D02*
X1103617D01*
X1103367Y466333D01*
X1102950Y466667D01*
X1102367Y466833D01*
X1101783Y466750D01*
X1101283Y466500D01*
X1100950Y465917D01*
X1100783Y465417D01*
Y464917D01*
X1100950Y464417D01*
X1101367Y463917D01*
X1101867Y463583D01*
X1102450Y463500D01*
X1103033Y463667D01*
X1103617Y464167D01*
G01X1113400Y468500D02*
Y463500D01*
G01X1112233Y466833D02*
X1114567D01*
G01X1117583Y463500D02*
Y468500D01*
G01Y466083D02*
X1118000Y466500D01*
X1118417Y466750D01*
X1119083Y466833D01*
X1119583Y466750D01*
X1120167Y466417D01*
X1120417Y465917D01*
Y463500D01*
G01X1123350Y465750D02*
X1126017D01*
X1125767Y466333D01*
X1125350Y466667D01*
X1124767Y466833D01*
X1124183Y466750D01*
X1123683Y466500D01*
X1123350Y465917D01*
X1123183Y465417D01*
Y464917D01*
X1123350Y464417D01*
X1123767Y463917D01*
X1124267Y463583D01*
X1124850Y463500D01*
X1125433Y463667D01*
X1126017Y464167D01*
G01X1134633Y463500D02*
Y466833D01*
G01Y466167D02*
X1135050Y466500D01*
X1135467Y466750D01*
X1136050Y466833D01*
X1136467Y466750D01*
X1136967Y466500D01*
G01X1140150Y465750D02*
X1142817D01*
X1142567Y466333D01*
X1142150Y466667D01*
X1141567Y466833D01*
X1140983Y466750D01*
X1140483Y466500D01*
X1140150Y465917D01*
X1139983Y465417D01*
Y464917D01*
X1140150Y464417D01*
X1140567Y463917D01*
X1141067Y463583D01*
X1141650Y463500D01*
X1142233Y463667D01*
X1142817Y464167D01*
G01X1145750Y464083D02*
X1146167Y463750D01*
X1146750Y463500D01*
X1147250D01*
X1147750Y463667D01*
X1148083Y463917D01*
X1148250Y464250D01*
X1148167Y464750D01*
X1147833Y465000D01*
X1146333Y465500D01*
X1146000Y466083D01*
X1146167Y466500D01*
X1146500Y466750D01*
X1147000Y466833D01*
X1147500Y466750D01*
X1148000Y466500D01*
G01X1152600Y466833D02*
Y463500D01*
G01Y468167D02*
X1152433Y468250D01*
Y468417D01*
X1152600Y468500D01*
X1152767Y468417D01*
Y468250D01*
X1152600Y468167D01*
G01X1156783Y463500D02*
Y466833D01*
G01Y466000D02*
X1157117Y466417D01*
X1157617Y466750D01*
X1158283Y466833D01*
X1158867Y466750D01*
X1159367Y466417D01*
X1159617Y465833D01*
Y463500D01*
G01X1163800Y463333D02*
X1163633Y463417D01*
Y463583D01*
X1163800Y463667D01*
X1163967Y463583D01*
Y463417D01*
X1163800Y463333D01*
G01X1021417Y476667D02*
X1021917Y477167D01*
X1022500Y477417D01*
X1023167Y477500D01*
X1024000Y477333D01*
X1024583Y476917D01*
X1024750Y476417D01*
X1024667Y475917D01*
X1024333Y475500D01*
X1022667Y474667D01*
X1021917Y474083D01*
X1021417Y473250D01*
X1021250Y472500D01*
X1024750D01*
G01X1028600Y472333D02*
X1028433Y472417D01*
Y472583D01*
X1028600Y472667D01*
X1028767Y472583D01*
Y472417D01*
X1028600Y472333D01*
G01X1032117Y477500D02*
X1034200Y472500D01*
X1036283Y477500D01*
G01X1039800Y475833D02*
Y472500D01*
G01Y477167D02*
X1039633Y477250D01*
Y477417D01*
X1039800Y477500D01*
X1039967Y477417D01*
Y477250D01*
X1039800Y477167D01*
G01X1046900Y472500D02*
Y475833D01*
G01Y475250D02*
X1046567Y475583D01*
X1046067Y475750D01*
X1045483Y475833D01*
X1044900Y475667D01*
X1044400Y475333D01*
X1044067Y474833D01*
X1043900Y474167D01*
X1044067Y473500D01*
X1044400Y473000D01*
X1044900Y472667D01*
X1045483Y472500D01*
X1046067Y472583D01*
X1046567Y472833D01*
X1046900Y473167D01*
G01X1055350Y473083D02*
X1055767Y472750D01*
X1056350Y472500D01*
X1056850D01*
X1057350Y472667D01*
X1057683Y472917D01*
X1057850Y473250D01*
X1057767Y473750D01*
X1057433Y474000D01*
X1055933Y474500D01*
X1055600Y475083D01*
X1055767Y475500D01*
X1056100Y475750D01*
X1056600Y475833D01*
X1057100Y475750D01*
X1057600Y475500D01*
G01X1060783Y472500D02*
Y477500D01*
G01Y475083D02*
X1061200Y475500D01*
X1061617Y475750D01*
X1062283Y475833D01*
X1062783Y475750D01*
X1063367Y475417D01*
X1063617Y474917D01*
Y472500D01*
G01X1067800D02*
X1067300Y472583D01*
X1066800Y472917D01*
X1066467Y473500D01*
X1066300Y474167D01*
X1066467Y474833D01*
X1066800Y475417D01*
X1067300Y475750D01*
X1067800Y475833D01*
X1068300Y475750D01*
X1068800Y475417D01*
X1069133Y474833D01*
X1069217Y474167D01*
X1069133Y473500D01*
X1068800Y472917D01*
X1068300Y472583D01*
X1067800Y472500D01*
G01X1071983Y475833D02*
Y473500D01*
X1072317Y472917D01*
X1072817Y472583D01*
X1073400Y472500D01*
X1073983Y472583D01*
X1074483Y472917D01*
X1074817Y473500D01*
G01Y472500D02*
Y475833D01*
G01X1079000Y472500D02*
Y477500D01*
G01X1086100D02*
Y472500D01*
G01Y473250D02*
X1085767Y472833D01*
X1085267Y472583D01*
X1084683Y472500D01*
X1084017Y472667D01*
X1083517Y473083D01*
X1083183Y473583D01*
X1083100Y474167D01*
X1083183Y474750D01*
X1083517Y475250D01*
X1084017Y475667D01*
X1084683Y475833D01*
X1085267Y475750D01*
X1085683Y475583D01*
X1086100Y475250D01*
G01X1094300Y472500D02*
Y477500D01*
G01Y475000D02*
X1094717Y475500D01*
X1095217Y475750D01*
X1095717Y475833D01*
X1096467Y475667D01*
X1096967Y475333D01*
X1097300Y474750D01*
Y474083D01*
X1097133Y473417D01*
X1096800Y472917D01*
X1096217Y472583D01*
X1095717Y472500D01*
X1095217Y472583D01*
X1094717Y472833D01*
X1094300Y473250D01*
G01X1100150Y474750D02*
X1102817D01*
X1102567Y475333D01*
X1102150Y475667D01*
X1101567Y475833D01*
X1100983Y475750D01*
X1100483Y475500D01*
X1100150Y474917D01*
X1099983Y474417D01*
Y473917D01*
X1100150Y473417D01*
X1100567Y472917D01*
X1101067Y472583D01*
X1101650Y472500D01*
X1102233Y472667D01*
X1102817Y473167D01*
G01X1111100Y470833D02*
Y475833D01*
G01Y475083D02*
X1111517Y475500D01*
X1111933Y475750D01*
X1112600Y475833D01*
X1113183Y475750D01*
X1113767Y475333D01*
X1114017Y474750D01*
X1114100Y474167D01*
X1114017Y473583D01*
X1113767Y473000D01*
X1113267Y472667D01*
X1112600Y472500D01*
X1112017Y472583D01*
X1111433Y472833D01*
X1111100Y473167D01*
G01X1118200Y472500D02*
Y477500D01*
G01X1122383Y475833D02*
Y473500D01*
X1122717Y472917D01*
X1123217Y472583D01*
X1123800Y472500D01*
X1124383Y472583D01*
X1124883Y472917D01*
X1125217Y473500D01*
G01Y472500D02*
Y475833D01*
G01X1128233Y471250D02*
X1128817Y470917D01*
X1129483Y470833D01*
X1130067Y470917D01*
X1130567Y471333D01*
X1130900Y471917D01*
Y475833D01*
G01Y475167D02*
X1130567Y475500D01*
X1130067Y475750D01*
X1129483Y475833D01*
X1128817Y475667D01*
X1128400Y475333D01*
X1128067Y474750D01*
X1127900Y474167D01*
X1127983Y473667D01*
X1128317Y473083D01*
X1128817Y472667D01*
X1129483Y472500D01*
X1129983Y472583D01*
X1130567Y472917D01*
X1130900Y473250D01*
G01X1133833Y471250D02*
X1134417Y470917D01*
X1135083Y470833D01*
X1135667Y470917D01*
X1136167Y471333D01*
X1136500Y471917D01*
Y475833D01*
G01Y475167D02*
X1136167Y475500D01*
X1135667Y475750D01*
X1135083Y475833D01*
X1134417Y475667D01*
X1134000Y475333D01*
X1133667Y474750D01*
X1133500Y474167D01*
X1133583Y473667D01*
X1133917Y473083D01*
X1134417Y472667D01*
X1135083Y472500D01*
X1135583Y472583D01*
X1136167Y472917D01*
X1136500Y473250D01*
G01X1139350Y474750D02*
X1142017D01*
X1141767Y475333D01*
X1141350Y475667D01*
X1140767Y475833D01*
X1140183Y475750D01*
X1139683Y475500D01*
X1139350Y474917D01*
X1139183Y474417D01*
Y473917D01*
X1139350Y473417D01*
X1139767Y472917D01*
X1140267Y472583D01*
X1140850Y472500D01*
X1141433Y472667D01*
X1142017Y473167D01*
G01X1147700Y477500D02*
Y472500D01*
G01Y473250D02*
X1147367Y472833D01*
X1146867Y472583D01*
X1146283Y472500D01*
X1145617Y472667D01*
X1145117Y473083D01*
X1144783Y473583D01*
X1144700Y474167D01*
X1144783Y474750D01*
X1145117Y475250D01*
X1145617Y475667D01*
X1146283Y475833D01*
X1146867Y475750D01*
X1147283Y475583D01*
X1147700Y475250D01*
G01X1155317Y475833D02*
X1156317Y472500D01*
X1157400Y475833D01*
X1158483Y472500D01*
X1159483Y475833D01*
G01X1163000D02*
Y472500D01*
G01Y477167D02*
X1162833Y477250D01*
Y477417D01*
X1163000Y477500D01*
X1163167Y477417D01*
Y477250D01*
X1163000Y477167D01*
G01X1168600Y477500D02*
Y472500D01*
G01X1167433Y475833D02*
X1169767D01*
G01X1172783Y472500D02*
Y477500D01*
G01Y475083D02*
X1173200Y475500D01*
X1173617Y475750D01*
X1174283Y475833D01*
X1174783Y475750D01*
X1175367Y475417D01*
X1175617Y474917D01*
Y472500D01*
G01X1183733D02*
X1187067Y474167D01*
X1183733Y475833D01*
G01X1189583Y473083D02*
X1190167Y472667D01*
X1190833Y472500D01*
X1191500Y472667D01*
X1192083Y473167D01*
X1192500Y473917D01*
X1192667Y474667D01*
Y475583D01*
X1192500Y476333D01*
X1192083Y477000D01*
X1191583Y477333D01*
X1191000Y477500D01*
X1190333Y477333D01*
X1189833Y477000D01*
X1189500Y476500D01*
X1189333Y475833D01*
X1189500Y475250D01*
X1189917Y474667D01*
X1190417Y474333D01*
X1191000Y474250D01*
X1191667Y474417D01*
X1192167Y474833D01*
X1192667Y475583D01*
G01X1196600Y477500D02*
X1195933Y477333D01*
X1195433Y476917D01*
X1195100Y476417D01*
X1194850Y475750D01*
X1194767Y475000D01*
X1194850Y474250D01*
X1195100Y473583D01*
X1195433Y473083D01*
X1195933Y472667D01*
X1196600Y472500D01*
X1197267Y472667D01*
X1197767Y473083D01*
X1198100Y473583D01*
X1198350Y474250D01*
X1198433Y475000D01*
X1198350Y475750D01*
X1198100Y476417D01*
X1197767Y476917D01*
X1197267Y477333D01*
X1196600Y477500D01*
G01X1200700Y472333D02*
X1203700Y477500D01*
G01X1200700D02*
X1200200Y477333D01*
X1199950Y477083D01*
X1199783Y476583D01*
X1199950Y476083D01*
X1200200Y475833D01*
X1200700Y475667D01*
X1201200Y475833D01*
X1201450Y476083D01*
X1201617Y476583D01*
X1201450Y477083D01*
X1201200Y477333D01*
X1200700Y477500D01*
G01X1203700Y474167D02*
X1203200Y474000D01*
X1202950Y473750D01*
X1202783Y473250D01*
X1202950Y472750D01*
X1203200Y472500D01*
X1203700Y472333D01*
X1204200Y472500D01*
X1204450Y472750D01*
X1204617Y473250D01*
X1204450Y473750D01*
X1204200Y474000D01*
X1203700Y474167D01*
G01X1212233Y472500D02*
Y475833D01*
G01Y475167D02*
X1212650Y475500D01*
X1213067Y475750D01*
X1213650Y475833D01*
X1214067Y475750D01*
X1214567Y475500D01*
G01X1217750Y474750D02*
X1220417D01*
X1220167Y475333D01*
X1219750Y475667D01*
X1219167Y475833D01*
X1218583Y475750D01*
X1218083Y475500D01*
X1217750Y474917D01*
X1217583Y474417D01*
Y473917D01*
X1217750Y473417D01*
X1218167Y472917D01*
X1218667Y472583D01*
X1219250Y472500D01*
X1219833Y472667D01*
X1220417Y473167D01*
G01X1223350Y473083D02*
X1223767Y472750D01*
X1224350Y472500D01*
X1224850D01*
X1225350Y472667D01*
X1225683Y472917D01*
X1225850Y473250D01*
X1225767Y473750D01*
X1225433Y474000D01*
X1223933Y474500D01*
X1223600Y475083D01*
X1223767Y475500D01*
X1224100Y475750D01*
X1224600Y475833D01*
X1225100Y475750D01*
X1225600Y475500D01*
G01X1230200Y475833D02*
Y472500D01*
G01Y477167D02*
X1230033Y477250D01*
Y477417D01*
X1230200Y477500D01*
X1230367Y477417D01*
Y477250D01*
X1230200Y477167D01*
G01X1234383Y472500D02*
Y475833D01*
G01Y475000D02*
X1234717Y475417D01*
X1235217Y475750D01*
X1235883Y475833D01*
X1236467Y475750D01*
X1236967Y475417D01*
X1237217Y474833D01*
Y472500D01*
G01X1246417Y471000D02*
X1247583Y472167D01*
Y473333D01*
X1246417D01*
Y472167D01*
X1247583D01*
G01Y474167D02*
Y475333D01*
X1246417D01*
Y474167D01*
X1247583D01*
G01X1250767Y472500D02*
Y477500D01*
X1252433D01*
X1253100Y477250D01*
X1253600Y476917D01*
X1254017Y476417D01*
X1254350Y475833D01*
X1254433Y475000D01*
X1254350Y474167D01*
X1254017Y473583D01*
X1253600Y473083D01*
X1253100Y472750D01*
X1252433Y472500D01*
X1250767D01*
G01X1258200D02*
X1257700Y472583D01*
X1257200Y472917D01*
X1256867Y473500D01*
X1256700Y474167D01*
X1256867Y474833D01*
X1257200Y475417D01*
X1257700Y475750D01*
X1258200Y475833D01*
X1258700Y475750D01*
X1259200Y475417D01*
X1259533Y474833D01*
X1259617Y474167D01*
X1259533Y473500D01*
X1259200Y472917D01*
X1258700Y472583D01*
X1258200Y472500D01*
G01X1267983D02*
Y475833D01*
G01Y475000D02*
X1268317Y475417D01*
X1268817Y475750D01*
X1269483Y475833D01*
X1270067Y475750D01*
X1270567Y475417D01*
X1270817Y474833D01*
Y472500D01*
G01X1275000D02*
X1274500Y472583D01*
X1274000Y472917D01*
X1273667Y473500D01*
X1273500Y474167D01*
X1273667Y474833D01*
X1274000Y475417D01*
X1274500Y475750D01*
X1275000Y475833D01*
X1275500Y475750D01*
X1276000Y475417D01*
X1276333Y474833D01*
X1276417Y474167D01*
X1276333Y473500D01*
X1276000Y472917D01*
X1275500Y472583D01*
X1275000Y472500D01*
G01X1280600Y477500D02*
Y472500D01*
G01X1279433Y475833D02*
X1281767D01*
G01X1293300Y472500D02*
Y475833D01*
G01Y475250D02*
X1292967Y475583D01*
X1292467Y475750D01*
X1291883Y475833D01*
X1291300Y475667D01*
X1290800Y475333D01*
X1290467Y474833D01*
X1290300Y474167D01*
X1290467Y473500D01*
X1290800Y473000D01*
X1291300Y472667D01*
X1291883Y472500D01*
X1292467Y472583D01*
X1292967Y472833D01*
X1293300Y473167D01*
G01X1297400Y472500D02*
Y477500D01*
G01X1303000Y472500D02*
Y477500D01*
G01X1308600Y472500D02*
X1308100Y472583D01*
X1307600Y472917D01*
X1307267Y473500D01*
X1307100Y474167D01*
X1307267Y474833D01*
X1307600Y475417D01*
X1308100Y475750D01*
X1308600Y475833D01*
X1309100Y475750D01*
X1309600Y475417D01*
X1309933Y474833D01*
X1310017Y474167D01*
X1309933Y473500D01*
X1309600Y472917D01*
X1309100Y472583D01*
X1308600Y472500D01*
G01X1312117Y475833D02*
X1313117Y472500D01*
X1314200Y475833D01*
X1315283Y472500D01*
X1316283Y475833D01*
G01X1326900Y472500D02*
Y475833D01*
G01Y475250D02*
X1326567Y475583D01*
X1326067Y475750D01*
X1325483Y475833D01*
X1324900Y475667D01*
X1324400Y475333D01*
X1324067Y474833D01*
X1323900Y474167D01*
X1324067Y473500D01*
X1324400Y473000D01*
X1324900Y472667D01*
X1325483Y472500D01*
X1326067Y472583D01*
X1326567Y472833D01*
X1326900Y473167D01*
G01X1331000Y475833D02*
Y472500D01*
G01Y477167D02*
X1330833Y477250D01*
Y477417D01*
X1331000Y477500D01*
X1331167Y477417D01*
Y477250D01*
X1331000Y477167D01*
G01X1335433Y472500D02*
Y475833D01*
G01Y475167D02*
X1335850Y475500D01*
X1336267Y475750D01*
X1336850Y475833D01*
X1337267Y475750D01*
X1337767Y475500D01*
G01X1016000Y679500D02*
Y459000D01*
G01X1033500Y498500D02*
Y503500D01*
G01Y501000D02*
X1033917Y501500D01*
X1034417Y501750D01*
X1034917Y501833D01*
X1035667Y501667D01*
X1036167Y501333D01*
X1036500Y500750D01*
Y500083D01*
X1036333Y499417D01*
X1036000Y498917D01*
X1035417Y498583D01*
X1034917Y498500D01*
X1034417Y498583D01*
X1033917Y498833D01*
X1033500Y499250D01*
G01X1039183Y501833D02*
Y499500D01*
X1039517Y498917D01*
X1040017Y498583D01*
X1040600Y498500D01*
X1041183Y498583D01*
X1041683Y498917D01*
X1042017Y499500D01*
G01Y498500D02*
Y501833D01*
G01X1044700Y498500D02*
Y503500D01*
G01Y501000D02*
X1045117Y501500D01*
X1045617Y501750D01*
X1046117Y501833D01*
X1046867Y501667D01*
X1047367Y501333D01*
X1047700Y500750D01*
Y500083D01*
X1047533Y499417D01*
X1047200Y498917D01*
X1046617Y498583D01*
X1046117Y498500D01*
X1045617Y498583D01*
X1045117Y498833D01*
X1044700Y499250D01*
G01X1050300Y498500D02*
Y503500D01*
G01Y501000D02*
X1050717Y501500D01*
X1051217Y501750D01*
X1051717Y501833D01*
X1052467Y501667D01*
X1052967Y501333D01*
X1053300Y500750D01*
Y500083D01*
X1053133Y499417D01*
X1052800Y498917D01*
X1052217Y498583D01*
X1051717Y498500D01*
X1051217Y498583D01*
X1050717Y498833D01*
X1050300Y499250D01*
G01X1057400Y498500D02*
Y503500D01*
G01X1061750Y500750D02*
X1064417D01*
X1064167Y501333D01*
X1063750Y501667D01*
X1063167Y501833D01*
X1062583Y501750D01*
X1062083Y501500D01*
X1061750Y500917D01*
X1061583Y500417D01*
Y499917D01*
X1061750Y499417D01*
X1062167Y498917D01*
X1062667Y498583D01*
X1063250Y498500D01*
X1063833Y498667D01*
X1064417Y499167D01*
G01X1074200Y501833D02*
Y498500D01*
G01Y503167D02*
X1074033Y503250D01*
Y503417D01*
X1074200Y503500D01*
X1074367Y503417D01*
Y503250D01*
X1074200Y503167D01*
G01X1078383Y498500D02*
Y501833D01*
G01Y501000D02*
X1078717Y501417D01*
X1079217Y501750D01*
X1079883Y501833D01*
X1080467Y501750D01*
X1080967Y501417D01*
X1081217Y500833D01*
Y498500D01*
G01X1084150Y499083D02*
X1084567Y498750D01*
X1085150Y498500D01*
X1085650D01*
X1086150Y498667D01*
X1086483Y498917D01*
X1086650Y499250D01*
X1086567Y499750D01*
X1086233Y500000D01*
X1084733Y500500D01*
X1084400Y501083D01*
X1084567Y501500D01*
X1084900Y501750D01*
X1085400Y501833D01*
X1085900Y501750D01*
X1086400Y501500D01*
G01X1091000Y501833D02*
Y498500D01*
G01Y503167D02*
X1090833Y503250D01*
Y503417D01*
X1091000Y503500D01*
X1091167Y503417D01*
Y503250D01*
X1091000Y503167D01*
G01X1098100Y503500D02*
Y498500D01*
G01Y499250D02*
X1097767Y498833D01*
X1097267Y498583D01*
X1096683Y498500D01*
X1096017Y498667D01*
X1095517Y499083D01*
X1095183Y499583D01*
X1095100Y500167D01*
X1095183Y500750D01*
X1095517Y501250D01*
X1096017Y501667D01*
X1096683Y501833D01*
X1097267Y501750D01*
X1097683Y501583D01*
X1098100Y501250D01*
G01X1100950Y500750D02*
X1103617D01*
X1103367Y501333D01*
X1102950Y501667D01*
X1102367Y501833D01*
X1101783Y501750D01*
X1101283Y501500D01*
X1100950Y500917D01*
X1100783Y500417D01*
Y499917D01*
X1100950Y499417D01*
X1101367Y498917D01*
X1101867Y498583D01*
X1102450Y498500D01*
X1103033Y498667D01*
X1103617Y499167D01*
G01X1113400Y503500D02*
Y498500D01*
G01X1112233Y501833D02*
X1114567D01*
G01X1117583Y498500D02*
Y503500D01*
G01Y501083D02*
X1118000Y501500D01*
X1118417Y501750D01*
X1119083Y501833D01*
X1119583Y501750D01*
X1120167Y501417D01*
X1120417Y500917D01*
Y498500D01*
G01X1123350Y500750D02*
X1126017D01*
X1125767Y501333D01*
X1125350Y501667D01*
X1124767Y501833D01*
X1124183Y501750D01*
X1123683Y501500D01*
X1123350Y500917D01*
X1123183Y500417D01*
Y499917D01*
X1123350Y499417D01*
X1123767Y498917D01*
X1124267Y498583D01*
X1124850Y498500D01*
X1125433Y498667D01*
X1126017Y499167D01*
G01X1134633Y498500D02*
Y501833D01*
G01Y501167D02*
X1135050Y501500D01*
X1135467Y501750D01*
X1136050Y501833D01*
X1136467Y501750D01*
X1136967Y501500D01*
G01X1140150Y500750D02*
X1142817D01*
X1142567Y501333D01*
X1142150Y501667D01*
X1141567Y501833D01*
X1140983Y501750D01*
X1140483Y501500D01*
X1140150Y500917D01*
X1139983Y500417D01*
Y499917D01*
X1140150Y499417D01*
X1140567Y498917D01*
X1141067Y498583D01*
X1141650Y498500D01*
X1142233Y498667D01*
X1142817Y499167D01*
G01X1145750Y499083D02*
X1146167Y498750D01*
X1146750Y498500D01*
X1147250D01*
X1147750Y498667D01*
X1148083Y498917D01*
X1148250Y499250D01*
X1148167Y499750D01*
X1147833Y500000D01*
X1146333Y500500D01*
X1146000Y501083D01*
X1146167Y501500D01*
X1146500Y501750D01*
X1147000Y501833D01*
X1147500Y501750D01*
X1148000Y501500D01*
G01X1152600Y501833D02*
Y498500D01*
G01Y503167D02*
X1152433Y503250D01*
Y503417D01*
X1152600Y503500D01*
X1152767Y503417D01*
Y503250D01*
X1152600Y503167D01*
G01X1156783Y498500D02*
Y501833D01*
G01Y501000D02*
X1157117Y501417D01*
X1157617Y501750D01*
X1158283Y501833D01*
X1158867Y501750D01*
X1159367Y501417D01*
X1159617Y500833D01*
Y498500D01*
G01X1163800Y498333D02*
X1163633Y498417D01*
Y498583D01*
X1163800Y498667D01*
X1163967Y498583D01*
Y498417D01*
X1163800Y498333D01*
G01X1023000Y483000D02*
Y488000D01*
X1022000Y487000D01*
G01Y483000D02*
X1024000D01*
G01X1028600Y482833D02*
X1028433Y482917D01*
Y483083D01*
X1028600Y483167D01*
X1028767Y483083D01*
Y482917D01*
X1028600Y482833D01*
G01X1032367Y483000D02*
Y488000D01*
X1034033D01*
X1034700Y487750D01*
X1035200Y487417D01*
X1035617Y486917D01*
X1035950Y486333D01*
X1036033Y485500D01*
X1035950Y484667D01*
X1035617Y484083D01*
X1035200Y483583D01*
X1034700Y483250D01*
X1034033Y483000D01*
X1032367D01*
G01X1039800Y486333D02*
Y483000D01*
G01Y487667D02*
X1039633Y487750D01*
Y487917D01*
X1039800Y488000D01*
X1039967Y487917D01*
Y487750D01*
X1039800Y487667D01*
G01X1042900Y483000D02*
Y486333D01*
G01Y485417D02*
X1043150Y485833D01*
X1043567Y486167D01*
X1044150Y486333D01*
X1044733Y486167D01*
X1045150Y485833D01*
X1045400Y485417D01*
Y483000D01*
G01Y485417D02*
X1045650Y485833D01*
X1046067Y486167D01*
X1046650Y486333D01*
X1047233Y486167D01*
X1047650Y485833D01*
X1047900Y485333D01*
Y483000D01*
G01X1049500Y481333D02*
Y486333D01*
G01Y485583D02*
X1049917Y486000D01*
X1050333Y486250D01*
X1051000Y486333D01*
X1051583Y486250D01*
X1052167Y485833D01*
X1052417Y485250D01*
X1052500Y484667D01*
X1052417Y484083D01*
X1052167Y483500D01*
X1051667Y483167D01*
X1051000Y483000D01*
X1050417Y483083D01*
X1049833Y483333D01*
X1049500Y483667D01*
G01X1056600Y483000D02*
Y488000D01*
G01X1060950Y485250D02*
X1063617D01*
X1063367Y485833D01*
X1062950Y486167D01*
X1062367Y486333D01*
X1061783Y486250D01*
X1061283Y486000D01*
X1060950Y485417D01*
X1060783Y484917D01*
Y484417D01*
X1060950Y483917D01*
X1061367Y483417D01*
X1061867Y483083D01*
X1062450Y483000D01*
X1063033Y483167D01*
X1063617Y483667D01*
G01X1075067Y483000D02*
X1071733Y484667D01*
X1075067Y486333D01*
G01X1084600Y483000D02*
Y488000D01*
X1083600Y487000D01*
G01Y483000D02*
X1085600D01*
G01X1093300D02*
Y486333D01*
G01Y485417D02*
X1093550Y485833D01*
X1093967Y486167D01*
X1094550Y486333D01*
X1095133Y486167D01*
X1095550Y485833D01*
X1095800Y485417D01*
Y483000D01*
G01Y485417D02*
X1096050Y485833D01*
X1096467Y486167D01*
X1097050Y486333D01*
X1097633Y486167D01*
X1098050Y485833D01*
X1098300Y485333D01*
Y483000D01*
G01X1101400Y486333D02*
Y483000D01*
G01Y487667D02*
X1101233Y487750D01*
Y487917D01*
X1101400Y488000D01*
X1101567Y487917D01*
Y487750D01*
X1101400Y487667D01*
G01X1107000Y483000D02*
Y488000D01*
G01X1117617Y481500D02*
X1118783Y482667D01*
Y483833D01*
X1117617D01*
Y482667D01*
X1118783D01*
G01Y484667D02*
Y485833D01*
X1117617D01*
Y484667D01*
X1118783D01*
G01X1023000Y509000D02*
Y514000D01*
X1022000Y513000D01*
G01Y509000D02*
X1024000D01*
G01X1028600Y508833D02*
X1028433Y508917D01*
Y509083D01*
X1028600Y509167D01*
X1028767Y509083D01*
Y508917D01*
X1028600Y508833D01*
G01X1032117Y514000D02*
X1034200Y509000D01*
X1036283Y514000D01*
G01X1039800Y512333D02*
Y509000D01*
G01Y513667D02*
X1039633Y513750D01*
Y513917D01*
X1039800Y514000D01*
X1039967Y513917D01*
Y513750D01*
X1039800Y513667D01*
G01X1046900Y509000D02*
Y512333D01*
G01Y511750D02*
X1046567Y512083D01*
X1046067Y512250D01*
X1045483Y512333D01*
X1044900Y512167D01*
X1044400Y511833D01*
X1044067Y511333D01*
X1043900Y510667D01*
X1044067Y510000D01*
X1044400Y509500D01*
X1044900Y509167D01*
X1045483Y509000D01*
X1046067Y509083D01*
X1046567Y509333D01*
X1046900Y509667D01*
G01X1055350Y509583D02*
X1055767Y509250D01*
X1056350Y509000D01*
X1056850D01*
X1057350Y509167D01*
X1057683Y509417D01*
X1057850Y509750D01*
X1057767Y510250D01*
X1057433Y510500D01*
X1055933Y511000D01*
X1055600Y511583D01*
X1055767Y512000D01*
X1056100Y512250D01*
X1056600Y512333D01*
X1057100Y512250D01*
X1057600Y512000D01*
G01X1060783Y509000D02*
Y514000D01*
G01Y511583D02*
X1061200Y512000D01*
X1061617Y512250D01*
X1062283Y512333D01*
X1062783Y512250D01*
X1063367Y511917D01*
X1063617Y511417D01*
Y509000D01*
G01X1067800D02*
X1067300Y509083D01*
X1066800Y509417D01*
X1066467Y510000D01*
X1066300Y510667D01*
X1066467Y511333D01*
X1066800Y511917D01*
X1067300Y512250D01*
X1067800Y512333D01*
X1068300Y512250D01*
X1068800Y511917D01*
X1069133Y511333D01*
X1069217Y510667D01*
X1069133Y510000D01*
X1068800Y509417D01*
X1068300Y509083D01*
X1067800Y509000D01*
G01X1071983Y512333D02*
Y510000D01*
X1072317Y509417D01*
X1072817Y509083D01*
X1073400Y509000D01*
X1073983Y509083D01*
X1074483Y509417D01*
X1074817Y510000D01*
G01Y509000D02*
Y512333D01*
G01X1079000Y509000D02*
Y514000D01*
G01X1086100D02*
Y509000D01*
G01Y509750D02*
X1085767Y509333D01*
X1085267Y509083D01*
X1084683Y509000D01*
X1084017Y509167D01*
X1083517Y509583D01*
X1083183Y510083D01*
X1083100Y510667D01*
X1083183Y511250D01*
X1083517Y511750D01*
X1084017Y512167D01*
X1084683Y512333D01*
X1085267Y512250D01*
X1085683Y512083D01*
X1086100Y511750D01*
G01X1094300Y509000D02*
Y514000D01*
G01Y511500D02*
X1094717Y512000D01*
X1095217Y512250D01*
X1095717Y512333D01*
X1096467Y512167D01*
X1096967Y511833D01*
X1097300Y511250D01*
Y510583D01*
X1097133Y509917D01*
X1096800Y509417D01*
X1096217Y509083D01*
X1095717Y509000D01*
X1095217Y509083D01*
X1094717Y509333D01*
X1094300Y509750D01*
G01X1100150Y511250D02*
X1102817D01*
X1102567Y511833D01*
X1102150Y512167D01*
X1101567Y512333D01*
X1100983Y512250D01*
X1100483Y512000D01*
X1100150Y511417D01*
X1099983Y510917D01*
Y510417D01*
X1100150Y509917D01*
X1100567Y509417D01*
X1101067Y509083D01*
X1101650Y509000D01*
X1102233Y509167D01*
X1102817Y509667D01*
G01X1111100Y507333D02*
Y512333D01*
G01Y511583D02*
X1111517Y512000D01*
X1111933Y512250D01*
X1112600Y512333D01*
X1113183Y512250D01*
X1113767Y511833D01*
X1114017Y511250D01*
X1114100Y510667D01*
X1114017Y510083D01*
X1113767Y509500D01*
X1113267Y509167D01*
X1112600Y509000D01*
X1112017Y509083D01*
X1111433Y509333D01*
X1111100Y509667D01*
G01X1118200Y509000D02*
Y514000D01*
G01X1122383Y512333D02*
Y510000D01*
X1122717Y509417D01*
X1123217Y509083D01*
X1123800Y509000D01*
X1124383Y509083D01*
X1124883Y509417D01*
X1125217Y510000D01*
G01Y509000D02*
Y512333D01*
G01X1128233Y507750D02*
X1128817Y507417D01*
X1129483Y507333D01*
X1130067Y507417D01*
X1130567Y507833D01*
X1130900Y508417D01*
Y512333D01*
G01Y511667D02*
X1130567Y512000D01*
X1130067Y512250D01*
X1129483Y512333D01*
X1128817Y512167D01*
X1128400Y511833D01*
X1128067Y511250D01*
X1127900Y510667D01*
X1127983Y510167D01*
X1128317Y509583D01*
X1128817Y509167D01*
X1129483Y509000D01*
X1129983Y509083D01*
X1130567Y509417D01*
X1130900Y509750D01*
G01X1133833Y507750D02*
X1134417Y507417D01*
X1135083Y507333D01*
X1135667Y507417D01*
X1136167Y507833D01*
X1136500Y508417D01*
Y512333D01*
G01Y511667D02*
X1136167Y512000D01*
X1135667Y512250D01*
X1135083Y512333D01*
X1134417Y512167D01*
X1134000Y511833D01*
X1133667Y511250D01*
X1133500Y510667D01*
X1133583Y510167D01*
X1133917Y509583D01*
X1134417Y509167D01*
X1135083Y509000D01*
X1135583Y509083D01*
X1136167Y509417D01*
X1136500Y509750D01*
G01X1139350Y511250D02*
X1142017D01*
X1141767Y511833D01*
X1141350Y512167D01*
X1140767Y512333D01*
X1140183Y512250D01*
X1139683Y512000D01*
X1139350Y511417D01*
X1139183Y510917D01*
Y510417D01*
X1139350Y509917D01*
X1139767Y509417D01*
X1140267Y509083D01*
X1140850Y509000D01*
X1141433Y509167D01*
X1142017Y509667D01*
G01X1147700Y514000D02*
Y509000D01*
G01Y509750D02*
X1147367Y509333D01*
X1146867Y509083D01*
X1146283Y509000D01*
X1145617Y509167D01*
X1145117Y509583D01*
X1144783Y510083D01*
X1144700Y510667D01*
X1144783Y511250D01*
X1145117Y511750D01*
X1145617Y512167D01*
X1146283Y512333D01*
X1146867Y512250D01*
X1147283Y512083D01*
X1147700Y511750D01*
G01X1155317Y512333D02*
X1156317Y509000D01*
X1157400Y512333D01*
X1158483Y509000D01*
X1159483Y512333D01*
G01X1163000D02*
Y509000D01*
G01Y513667D02*
X1162833Y513750D01*
Y513917D01*
X1163000Y514000D01*
X1163167Y513917D01*
Y513750D01*
X1163000Y513667D01*
G01X1168600Y514000D02*
Y509000D01*
G01X1167433Y512333D02*
X1169767D01*
G01X1172783Y509000D02*
Y514000D01*
G01Y511583D02*
X1173200Y512000D01*
X1173617Y512250D01*
X1174283Y512333D01*
X1174783Y512250D01*
X1175367Y511917D01*
X1175617Y511417D01*
Y509000D01*
G01X1183733D02*
X1187067Y510667D01*
X1183733Y512333D01*
G01X1189583Y509583D02*
X1190167Y509167D01*
X1190833Y509000D01*
X1191500Y509167D01*
X1192083Y509667D01*
X1192500Y510417D01*
X1192667Y511167D01*
Y512083D01*
X1192500Y512833D01*
X1192083Y513500D01*
X1191583Y513833D01*
X1191000Y514000D01*
X1190333Y513833D01*
X1189833Y513500D01*
X1189500Y513000D01*
X1189333Y512333D01*
X1189500Y511750D01*
X1189917Y511167D01*
X1190417Y510833D01*
X1191000Y510750D01*
X1191667Y510917D01*
X1192167Y511333D01*
X1192667Y512083D01*
G01X1196600Y514000D02*
X1195933Y513833D01*
X1195433Y513417D01*
X1195100Y512917D01*
X1194850Y512250D01*
X1194767Y511500D01*
X1194850Y510750D01*
X1195100Y510083D01*
X1195433Y509583D01*
X1195933Y509167D01*
X1196600Y509000D01*
X1197267Y509167D01*
X1197767Y509583D01*
X1198100Y510083D01*
X1198350Y510750D01*
X1198433Y511500D01*
X1198350Y512250D01*
X1198100Y512917D01*
X1197767Y513417D01*
X1197267Y513833D01*
X1196600Y514000D01*
G01X1200700Y508833D02*
X1203700Y514000D01*
G01X1200700D02*
X1200200Y513833D01*
X1199950Y513583D01*
X1199783Y513083D01*
X1199950Y512583D01*
X1200200Y512333D01*
X1200700Y512167D01*
X1201200Y512333D01*
X1201450Y512583D01*
X1201617Y513083D01*
X1201450Y513583D01*
X1201200Y513833D01*
X1200700Y514000D01*
G01X1203700Y510667D02*
X1203200Y510500D01*
X1202950Y510250D01*
X1202783Y509750D01*
X1202950Y509250D01*
X1203200Y509000D01*
X1203700Y508833D01*
X1204200Y509000D01*
X1204450Y509250D01*
X1204617Y509750D01*
X1204450Y510250D01*
X1204200Y510500D01*
X1203700Y510667D01*
G01X1212233Y509000D02*
Y512333D01*
G01Y511667D02*
X1212650Y512000D01*
X1213067Y512250D01*
X1213650Y512333D01*
X1214067Y512250D01*
X1214567Y512000D01*
G01X1217750Y511250D02*
X1220417D01*
X1220167Y511833D01*
X1219750Y512167D01*
X1219167Y512333D01*
X1218583Y512250D01*
X1218083Y512000D01*
X1217750Y511417D01*
X1217583Y510917D01*
Y510417D01*
X1217750Y509917D01*
X1218167Y509417D01*
X1218667Y509083D01*
X1219250Y509000D01*
X1219833Y509167D01*
X1220417Y509667D01*
G01X1223350Y509583D02*
X1223767Y509250D01*
X1224350Y509000D01*
X1224850D01*
X1225350Y509167D01*
X1225683Y509417D01*
X1225850Y509750D01*
X1225767Y510250D01*
X1225433Y510500D01*
X1223933Y511000D01*
X1223600Y511583D01*
X1223767Y512000D01*
X1224100Y512250D01*
X1224600Y512333D01*
X1225100Y512250D01*
X1225600Y512000D01*
G01X1230200Y512333D02*
Y509000D01*
G01Y513667D02*
X1230033Y513750D01*
Y513917D01*
X1230200Y514000D01*
X1230367Y513917D01*
Y513750D01*
X1230200Y513667D01*
G01X1234383Y509000D02*
Y512333D01*
G01Y511500D02*
X1234717Y511917D01*
X1235217Y512250D01*
X1235883Y512333D01*
X1236467Y512250D01*
X1236967Y511917D01*
X1237217Y511333D01*
Y509000D01*
G01X1246417Y507500D02*
X1247583Y508667D01*
Y509833D01*
X1246417D01*
Y508667D01*
X1247583D01*
G01Y510667D02*
Y511833D01*
X1246417D01*
Y510667D01*
X1247583D01*
G01X1250767Y509000D02*
Y514000D01*
X1252433D01*
X1253100Y513750D01*
X1253600Y513417D01*
X1254017Y512917D01*
X1254350Y512333D01*
X1254433Y511500D01*
X1254350Y510667D01*
X1254017Y510083D01*
X1253600Y509583D01*
X1253100Y509250D01*
X1252433Y509000D01*
X1250767D01*
G01X1258200D02*
X1257700Y509083D01*
X1257200Y509417D01*
X1256867Y510000D01*
X1256700Y510667D01*
X1256867Y511333D01*
X1257200Y511917D01*
X1257700Y512250D01*
X1258200Y512333D01*
X1258700Y512250D01*
X1259200Y511917D01*
X1259533Y511333D01*
X1259617Y510667D01*
X1259533Y510000D01*
X1259200Y509417D01*
X1258700Y509083D01*
X1258200Y509000D01*
G01X1267983D02*
Y512333D01*
G01Y511500D02*
X1268317Y511917D01*
X1268817Y512250D01*
X1269483Y512333D01*
X1270067Y512250D01*
X1270567Y511917D01*
X1270817Y511333D01*
Y509000D01*
G01X1275000D02*
X1274500Y509083D01*
X1274000Y509417D01*
X1273667Y510000D01*
X1273500Y510667D01*
X1273667Y511333D01*
X1274000Y511917D01*
X1274500Y512250D01*
X1275000Y512333D01*
X1275500Y512250D01*
X1276000Y511917D01*
X1276333Y511333D01*
X1276417Y510667D01*
X1276333Y510000D01*
X1276000Y509417D01*
X1275500Y509083D01*
X1275000Y509000D01*
G01X1280600Y514000D02*
Y509000D01*
G01X1279433Y512333D02*
X1281767D01*
G01X1293300Y509000D02*
Y512333D01*
G01Y511750D02*
X1292967Y512083D01*
X1292467Y512250D01*
X1291883Y512333D01*
X1291300Y512167D01*
X1290800Y511833D01*
X1290467Y511333D01*
X1290300Y510667D01*
X1290467Y510000D01*
X1290800Y509500D01*
X1291300Y509167D01*
X1291883Y509000D01*
X1292467Y509083D01*
X1292967Y509333D01*
X1293300Y509667D01*
G01X1297400Y509000D02*
Y514000D01*
G01X1303000Y509000D02*
Y514000D01*
G01X1308600Y509000D02*
X1308100Y509083D01*
X1307600Y509417D01*
X1307267Y510000D01*
X1307100Y510667D01*
X1307267Y511333D01*
X1307600Y511917D01*
X1308100Y512250D01*
X1308600Y512333D01*
X1309100Y512250D01*
X1309600Y511917D01*
X1309933Y511333D01*
X1310017Y510667D01*
X1309933Y510000D01*
X1309600Y509417D01*
X1309100Y509083D01*
X1308600Y509000D01*
G01X1312117Y512333D02*
X1313117Y509000D01*
X1314200Y512333D01*
X1315283Y509000D01*
X1316283Y512333D01*
G01X1326900Y509000D02*
Y512333D01*
G01Y511750D02*
X1326567Y512083D01*
X1326067Y512250D01*
X1325483Y512333D01*
X1324900Y512167D01*
X1324400Y511833D01*
X1324067Y511333D01*
X1323900Y510667D01*
X1324067Y510000D01*
X1324400Y509500D01*
X1324900Y509167D01*
X1325483Y509000D01*
X1326067Y509083D01*
X1326567Y509333D01*
X1326900Y509667D01*
G01X1331000Y512333D02*
Y509000D01*
G01Y513667D02*
X1330833Y513750D01*
Y513917D01*
X1331000Y514000D01*
X1331167Y513917D01*
Y513750D01*
X1331000Y513667D01*
G01X1335433Y509000D02*
Y512333D01*
G01Y511667D02*
X1335850Y512000D01*
X1336267Y512250D01*
X1336850Y512333D01*
X1337267Y512250D01*
X1337767Y512000D01*
G01X1025417Y530500D02*
X1027500Y525500D01*
X1029583Y530500D01*
G01X1033100Y528833D02*
Y525500D01*
G01Y530167D02*
X1032933Y530250D01*
Y530417D01*
X1033100Y530500D01*
X1033267Y530417D01*
Y530250D01*
X1033100Y530167D01*
G01X1040200Y525500D02*
Y528833D01*
G01Y528250D02*
X1039867Y528583D01*
X1039367Y528750D01*
X1038783Y528833D01*
X1038200Y528667D01*
X1037700Y528333D01*
X1037367Y527833D01*
X1037200Y527167D01*
X1037367Y526500D01*
X1037700Y526000D01*
X1038200Y525667D01*
X1038783Y525500D01*
X1039367Y525583D01*
X1039867Y525833D01*
X1040200Y526167D01*
G01X1048650Y526083D02*
X1049067Y525750D01*
X1049650Y525500D01*
X1050150D01*
X1050650Y525667D01*
X1050983Y525917D01*
X1051150Y526250D01*
X1051067Y526750D01*
X1050733Y527000D01*
X1049233Y527500D01*
X1048900Y528083D01*
X1049067Y528500D01*
X1049400Y528750D01*
X1049900Y528833D01*
X1050400Y528750D01*
X1050900Y528500D01*
G01X1054083Y525500D02*
Y530500D01*
G01Y528083D02*
X1054500Y528500D01*
X1054917Y528750D01*
X1055583Y528833D01*
X1056083Y528750D01*
X1056667Y528417D01*
X1056917Y527917D01*
Y525500D01*
G01X1061100D02*
X1060600Y525583D01*
X1060100Y525917D01*
X1059767Y526500D01*
X1059600Y527167D01*
X1059767Y527833D01*
X1060100Y528417D01*
X1060600Y528750D01*
X1061100Y528833D01*
X1061600Y528750D01*
X1062100Y528417D01*
X1062433Y527833D01*
X1062517Y527167D01*
X1062433Y526500D01*
X1062100Y525917D01*
X1061600Y525583D01*
X1061100Y525500D01*
G01X1065283Y528833D02*
Y526500D01*
X1065617Y525917D01*
X1066117Y525583D01*
X1066700Y525500D01*
X1067283Y525583D01*
X1067783Y525917D01*
X1068117Y526500D01*
G01Y525500D02*
Y528833D01*
G01X1072300Y525500D02*
Y530500D01*
G01X1079400D02*
Y525500D01*
G01Y526250D02*
X1079067Y525833D01*
X1078567Y525583D01*
X1077983Y525500D01*
X1077317Y525667D01*
X1076817Y526083D01*
X1076483Y526583D01*
X1076400Y527167D01*
X1076483Y527750D01*
X1076817Y528250D01*
X1077317Y528667D01*
X1077983Y528833D01*
X1078567Y528750D01*
X1078983Y528583D01*
X1079400Y528250D01*
G01X1087600Y525500D02*
Y530500D01*
G01Y528000D02*
X1088017Y528500D01*
X1088517Y528750D01*
X1089017Y528833D01*
X1089767Y528667D01*
X1090267Y528333D01*
X1090600Y527750D01*
Y527083D01*
X1090433Y526417D01*
X1090100Y525917D01*
X1089517Y525583D01*
X1089017Y525500D01*
X1088517Y525583D01*
X1088017Y525833D01*
X1087600Y526250D01*
G01X1093450Y527750D02*
X1096117D01*
X1095867Y528333D01*
X1095450Y528667D01*
X1094867Y528833D01*
X1094283Y528750D01*
X1093783Y528500D01*
X1093450Y527917D01*
X1093283Y527417D01*
Y526917D01*
X1093450Y526417D01*
X1093867Y525917D01*
X1094367Y525583D01*
X1094950Y525500D01*
X1095533Y525667D01*
X1096117Y526167D01*
G01X1104400Y523833D02*
Y528833D01*
G01Y528083D02*
X1104817Y528500D01*
X1105233Y528750D01*
X1105900Y528833D01*
X1106483Y528750D01*
X1107067Y528333D01*
X1107317Y527750D01*
X1107400Y527167D01*
X1107317Y526583D01*
X1107067Y526000D01*
X1106567Y525667D01*
X1105900Y525500D01*
X1105317Y525583D01*
X1104733Y525833D01*
X1104400Y526167D01*
G01X1111500Y525500D02*
Y530500D01*
G01X1115683Y528833D02*
Y526500D01*
X1116017Y525917D01*
X1116517Y525583D01*
X1117100Y525500D01*
X1117683Y525583D01*
X1118183Y525917D01*
X1118517Y526500D01*
G01Y525500D02*
Y528833D01*
G01X1121533Y524250D02*
X1122117Y523917D01*
X1122783Y523833D01*
X1123367Y523917D01*
X1123867Y524333D01*
X1124200Y524917D01*
Y528833D01*
G01Y528167D02*
X1123867Y528500D01*
X1123367Y528750D01*
X1122783Y528833D01*
X1122117Y528667D01*
X1121700Y528333D01*
X1121367Y527750D01*
X1121200Y527167D01*
X1121283Y526667D01*
X1121617Y526083D01*
X1122117Y525667D01*
X1122783Y525500D01*
X1123283Y525583D01*
X1123867Y525917D01*
X1124200Y526250D01*
G01X1127133Y524250D02*
X1127717Y523917D01*
X1128383Y523833D01*
X1128967Y523917D01*
X1129467Y524333D01*
X1129800Y524917D01*
Y528833D01*
G01Y528167D02*
X1129467Y528500D01*
X1128967Y528750D01*
X1128383Y528833D01*
X1127717Y528667D01*
X1127300Y528333D01*
X1126967Y527750D01*
X1126800Y527167D01*
X1126883Y526667D01*
X1127217Y526083D01*
X1127717Y525667D01*
X1128383Y525500D01*
X1128883Y525583D01*
X1129467Y525917D01*
X1129800Y526250D01*
G01X1132650Y527750D02*
X1135317D01*
X1135067Y528333D01*
X1134650Y528667D01*
X1134067Y528833D01*
X1133483Y528750D01*
X1132983Y528500D01*
X1132650Y527917D01*
X1132483Y527417D01*
Y526917D01*
X1132650Y526417D01*
X1133067Y525917D01*
X1133567Y525583D01*
X1134150Y525500D01*
X1134733Y525667D01*
X1135317Y526167D01*
G01X1141000Y530500D02*
Y525500D01*
G01Y526250D02*
X1140667Y525833D01*
X1140167Y525583D01*
X1139583Y525500D01*
X1138917Y525667D01*
X1138417Y526083D01*
X1138083Y526583D01*
X1138000Y527167D01*
X1138083Y527750D01*
X1138417Y528250D01*
X1138917Y528667D01*
X1139583Y528833D01*
X1140167Y528750D01*
X1140583Y528583D01*
X1141000Y528250D01*
G01X1148617Y528833D02*
X1149617Y525500D01*
X1150700Y528833D01*
X1151783Y525500D01*
X1152783Y528833D01*
G01X1156300D02*
Y525500D01*
G01Y530167D02*
X1156133Y530250D01*
Y530417D01*
X1156300Y530500D01*
X1156467Y530417D01*
Y530250D01*
X1156300Y530167D01*
G01X1161900Y530500D02*
Y525500D01*
G01X1160733Y528833D02*
X1163067D01*
G01X1166083Y525500D02*
Y530500D01*
G01Y528083D02*
X1166500Y528500D01*
X1166917Y528750D01*
X1167583Y528833D01*
X1168083Y528750D01*
X1168667Y528417D01*
X1168917Y527917D01*
Y525500D01*
G01X1177033D02*
X1180367Y527167D01*
X1177033Y528833D01*
G01X1182883Y526083D02*
X1183467Y525667D01*
X1184133Y525500D01*
X1184800Y525667D01*
X1185383Y526167D01*
X1185800Y526917D01*
X1185967Y527667D01*
Y528583D01*
X1185800Y529333D01*
X1185383Y530000D01*
X1184883Y530333D01*
X1184300Y530500D01*
X1183633Y530333D01*
X1183133Y530000D01*
X1182800Y529500D01*
X1182633Y528833D01*
X1182800Y528250D01*
X1183217Y527667D01*
X1183717Y527333D01*
X1184300Y527250D01*
X1184967Y527417D01*
X1185467Y527833D01*
X1185967Y528583D01*
G01X1189900Y530500D02*
X1189233Y530333D01*
X1188733Y529917D01*
X1188400Y529417D01*
X1188150Y528750D01*
X1188067Y528000D01*
X1188150Y527250D01*
X1188400Y526583D01*
X1188733Y526083D01*
X1189233Y525667D01*
X1189900Y525500D01*
X1190567Y525667D01*
X1191067Y526083D01*
X1191400Y526583D01*
X1191650Y527250D01*
X1191733Y528000D01*
X1191650Y528750D01*
X1191400Y529417D01*
X1191067Y529917D01*
X1190567Y530333D01*
X1189900Y530500D01*
G01X1194000Y525333D02*
X1197000Y530500D01*
G01X1194000D02*
X1193500Y530333D01*
X1193250Y530083D01*
X1193083Y529583D01*
X1193250Y529083D01*
X1193500Y528833D01*
X1194000Y528667D01*
X1194500Y528833D01*
X1194750Y529083D01*
X1194917Y529583D01*
X1194750Y530083D01*
X1194500Y530333D01*
X1194000Y530500D01*
G01X1197000Y527167D02*
X1196500Y527000D01*
X1196250Y526750D01*
X1196083Y526250D01*
X1196250Y525750D01*
X1196500Y525500D01*
X1197000Y525333D01*
X1197500Y525500D01*
X1197750Y525750D01*
X1197917Y526250D01*
X1197750Y526750D01*
X1197500Y527000D01*
X1197000Y527167D01*
G01X1205533Y525500D02*
Y528833D01*
G01Y528167D02*
X1205950Y528500D01*
X1206367Y528750D01*
X1206950Y528833D01*
X1207367Y528750D01*
X1207867Y528500D01*
G01X1211050Y527750D02*
X1213717D01*
X1213467Y528333D01*
X1213050Y528667D01*
X1212467Y528833D01*
X1211883Y528750D01*
X1211383Y528500D01*
X1211050Y527917D01*
X1210883Y527417D01*
Y526917D01*
X1211050Y526417D01*
X1211467Y525917D01*
X1211967Y525583D01*
X1212550Y525500D01*
X1213133Y525667D01*
X1213717Y526167D01*
G01X1216650Y526083D02*
X1217067Y525750D01*
X1217650Y525500D01*
X1218150D01*
X1218650Y525667D01*
X1218983Y525917D01*
X1219150Y526250D01*
X1219067Y526750D01*
X1218733Y527000D01*
X1217233Y527500D01*
X1216900Y528083D01*
X1217067Y528500D01*
X1217400Y528750D01*
X1217900Y528833D01*
X1218400Y528750D01*
X1218900Y528500D01*
G01X1223500Y528833D02*
Y525500D01*
G01Y530167D02*
X1223333Y530250D01*
Y530417D01*
X1223500Y530500D01*
X1223667Y530417D01*
Y530250D01*
X1223500Y530167D01*
G01X1227683Y525500D02*
Y528833D01*
G01Y528000D02*
X1228017Y528417D01*
X1228517Y528750D01*
X1229183Y528833D01*
X1229767Y528750D01*
X1230267Y528417D01*
X1230517Y527833D01*
Y525500D01*
G01X1023917Y551500D02*
X1026000Y546500D01*
X1028083Y551500D01*
G01X1031600Y549833D02*
Y546500D01*
G01Y551167D02*
X1031433Y551250D01*
Y551417D01*
X1031600Y551500D01*
X1031767Y551417D01*
Y551250D01*
X1031600Y551167D01*
G01X1038700Y546500D02*
Y549833D01*
G01Y549250D02*
X1038367Y549583D01*
X1037867Y549750D01*
X1037283Y549833D01*
X1036700Y549667D01*
X1036200Y549333D01*
X1035867Y548833D01*
X1035700Y548167D01*
X1035867Y547500D01*
X1036200Y547000D01*
X1036700Y546667D01*
X1037283Y546500D01*
X1037867Y546583D01*
X1038367Y546833D01*
X1038700Y547167D01*
G01X1047150Y547083D02*
X1047567Y546750D01*
X1048150Y546500D01*
X1048650D01*
X1049150Y546667D01*
X1049483Y546917D01*
X1049650Y547250D01*
X1049567Y547750D01*
X1049233Y548000D01*
X1047733Y548500D01*
X1047400Y549083D01*
X1047567Y549500D01*
X1047900Y549750D01*
X1048400Y549833D01*
X1048900Y549750D01*
X1049400Y549500D01*
G01X1052583Y546500D02*
Y551500D01*
G01Y549083D02*
X1053000Y549500D01*
X1053417Y549750D01*
X1054083Y549833D01*
X1054583Y549750D01*
X1055167Y549417D01*
X1055417Y548917D01*
Y546500D01*
G01X1059600D02*
X1059100Y546583D01*
X1058600Y546917D01*
X1058267Y547500D01*
X1058100Y548167D01*
X1058267Y548833D01*
X1058600Y549417D01*
X1059100Y549750D01*
X1059600Y549833D01*
X1060100Y549750D01*
X1060600Y549417D01*
X1060933Y548833D01*
X1061017Y548167D01*
X1060933Y547500D01*
X1060600Y546917D01*
X1060100Y546583D01*
X1059600Y546500D01*
G01X1063783Y549833D02*
Y547500D01*
X1064117Y546917D01*
X1064617Y546583D01*
X1065200Y546500D01*
X1065783Y546583D01*
X1066283Y546917D01*
X1066617Y547500D01*
G01Y546500D02*
Y549833D01*
G01X1070800Y546500D02*
Y551500D01*
G01X1077900D02*
Y546500D01*
G01Y547250D02*
X1077567Y546833D01*
X1077067Y546583D01*
X1076483Y546500D01*
X1075817Y546667D01*
X1075317Y547083D01*
X1074983Y547583D01*
X1074900Y548167D01*
X1074983Y548750D01*
X1075317Y549250D01*
X1075817Y549667D01*
X1076483Y549833D01*
X1077067Y549750D01*
X1077483Y549583D01*
X1077900Y549250D01*
G01X1086100Y546500D02*
Y551500D01*
G01Y549000D02*
X1086517Y549500D01*
X1087017Y549750D01*
X1087517Y549833D01*
X1088267Y549667D01*
X1088767Y549333D01*
X1089100Y548750D01*
Y548083D01*
X1088933Y547417D01*
X1088600Y546917D01*
X1088017Y546583D01*
X1087517Y546500D01*
X1087017Y546583D01*
X1086517Y546833D01*
X1086100Y547250D01*
G01X1091950Y548750D02*
X1094617D01*
X1094367Y549333D01*
X1093950Y549667D01*
X1093367Y549833D01*
X1092783Y549750D01*
X1092283Y549500D01*
X1091950Y548917D01*
X1091783Y548417D01*
Y547917D01*
X1091950Y547417D01*
X1092367Y546917D01*
X1092867Y546583D01*
X1093450Y546500D01*
X1094033Y546667D01*
X1094617Y547167D01*
G01X1102900Y544833D02*
Y549833D01*
G01Y549083D02*
X1103317Y549500D01*
X1103733Y549750D01*
X1104400Y549833D01*
X1104983Y549750D01*
X1105567Y549333D01*
X1105817Y548750D01*
X1105900Y548167D01*
X1105817Y547583D01*
X1105567Y547000D01*
X1105067Y546667D01*
X1104400Y546500D01*
X1103817Y546583D01*
X1103233Y546833D01*
X1102900Y547167D01*
G01X1110000Y546500D02*
Y551500D01*
G01X1114183Y549833D02*
Y547500D01*
X1114517Y546917D01*
X1115017Y546583D01*
X1115600Y546500D01*
X1116183Y546583D01*
X1116683Y546917D01*
X1117017Y547500D01*
G01Y546500D02*
Y549833D01*
G01X1120033Y545250D02*
X1120617Y544917D01*
X1121283Y544833D01*
X1121867Y544917D01*
X1122367Y545333D01*
X1122700Y545917D01*
Y549833D01*
G01Y549167D02*
X1122367Y549500D01*
X1121867Y549750D01*
X1121283Y549833D01*
X1120617Y549667D01*
X1120200Y549333D01*
X1119867Y548750D01*
X1119700Y548167D01*
X1119783Y547667D01*
X1120117Y547083D01*
X1120617Y546667D01*
X1121283Y546500D01*
X1121783Y546583D01*
X1122367Y546917D01*
X1122700Y547250D01*
G01X1125633Y545250D02*
X1126217Y544917D01*
X1126883Y544833D01*
X1127467Y544917D01*
X1127967Y545333D01*
X1128300Y545917D01*
Y549833D01*
G01Y549167D02*
X1127967Y549500D01*
X1127467Y549750D01*
X1126883Y549833D01*
X1126217Y549667D01*
X1125800Y549333D01*
X1125467Y548750D01*
X1125300Y548167D01*
X1125383Y547667D01*
X1125717Y547083D01*
X1126217Y546667D01*
X1126883Y546500D01*
X1127383Y546583D01*
X1127967Y546917D01*
X1128300Y547250D01*
G01X1131150Y548750D02*
X1133817D01*
X1133567Y549333D01*
X1133150Y549667D01*
X1132567Y549833D01*
X1131983Y549750D01*
X1131483Y549500D01*
X1131150Y548917D01*
X1130983Y548417D01*
Y547917D01*
X1131150Y547417D01*
X1131567Y546917D01*
X1132067Y546583D01*
X1132650Y546500D01*
X1133233Y546667D01*
X1133817Y547167D01*
G01X1139500Y551500D02*
Y546500D01*
G01Y547250D02*
X1139167Y546833D01*
X1138667Y546583D01*
X1138083Y546500D01*
X1137417Y546667D01*
X1136917Y547083D01*
X1136583Y547583D01*
X1136500Y548167D01*
X1136583Y548750D01*
X1136917Y549250D01*
X1137417Y549667D01*
X1138083Y549833D01*
X1138667Y549750D01*
X1139083Y549583D01*
X1139500Y549250D01*
G01X1150200Y546500D02*
Y551500D01*
X1147117Y547917D01*
X1151283D01*
G01X1154800Y551500D02*
X1154133Y551333D01*
X1153633Y550917D01*
X1153300Y550417D01*
X1153050Y549750D01*
X1152967Y549000D01*
X1153050Y548250D01*
X1153300Y547583D01*
X1153633Y547083D01*
X1154133Y546667D01*
X1154800Y546500D01*
X1155467Y546667D01*
X1155967Y547083D01*
X1156300Y547583D01*
X1156550Y548250D01*
X1156633Y549000D01*
X1156550Y549750D01*
X1156300Y550417D01*
X1155967Y550917D01*
X1155467Y551333D01*
X1154800Y551500D01*
G01X1158900Y546333D02*
X1161900Y551500D01*
G01X1158900D02*
X1158400Y551333D01*
X1158150Y551083D01*
X1157983Y550583D01*
X1158150Y550083D01*
X1158400Y549833D01*
X1158900Y549667D01*
X1159400Y549833D01*
X1159650Y550083D01*
X1159817Y550583D01*
X1159650Y551083D01*
X1159400Y551333D01*
X1158900Y551500D01*
G01X1161900Y548167D02*
X1161400Y548000D01*
X1161150Y547750D01*
X1160983Y547250D01*
X1161150Y546750D01*
X1161400Y546500D01*
X1161900Y546333D01*
X1162400Y546500D01*
X1162650Y546750D01*
X1162817Y547250D01*
X1162650Y547750D01*
X1162400Y548000D01*
X1161900Y548167D01*
G01X1169100D02*
X1169933Y549833D01*
X1170767D01*
X1172433Y546500D01*
X1173267D01*
X1174100Y548167D01*
G01X1182800Y546500D02*
Y551500D01*
X1181800Y550500D01*
G01Y546500D02*
X1183800D01*
G01X1188400Y551500D02*
X1187733Y551333D01*
X1187233Y550917D01*
X1186900Y550417D01*
X1186650Y549750D01*
X1186567Y549000D01*
X1186650Y548250D01*
X1186900Y547583D01*
X1187233Y547083D01*
X1187733Y546667D01*
X1188400Y546500D01*
X1189067Y546667D01*
X1189567Y547083D01*
X1189900Y547583D01*
X1190150Y548250D01*
X1190233Y549000D01*
X1190150Y549750D01*
X1189900Y550417D01*
X1189567Y550917D01*
X1189067Y551333D01*
X1188400Y551500D01*
G01X1194000D02*
X1193333Y551333D01*
X1192833Y550917D01*
X1192500Y550417D01*
X1192250Y549750D01*
X1192167Y549000D01*
X1192250Y548250D01*
X1192500Y547583D01*
X1192833Y547083D01*
X1193333Y546667D01*
X1194000Y546500D01*
X1194667Y546667D01*
X1195167Y547083D01*
X1195500Y547583D01*
X1195750Y548250D01*
X1195833Y549000D01*
X1195750Y549750D01*
X1195500Y550417D01*
X1195167Y550917D01*
X1194667Y551333D01*
X1194000Y551500D01*
G01X1198100Y546333D02*
X1201100Y551500D01*
G01X1198100D02*
X1197600Y551333D01*
X1197350Y551083D01*
X1197183Y550583D01*
X1197350Y550083D01*
X1197600Y549833D01*
X1198100Y549667D01*
X1198600Y549833D01*
X1198850Y550083D01*
X1199017Y550583D01*
X1198850Y551083D01*
X1198600Y551333D01*
X1198100Y551500D01*
G01X1201100Y548167D02*
X1200600Y548000D01*
X1200350Y547750D01*
X1200183Y547250D01*
X1200350Y546750D01*
X1200600Y546500D01*
X1201100Y546333D01*
X1201600Y546500D01*
X1201850Y546750D01*
X1202017Y547250D01*
X1201850Y547750D01*
X1201600Y548000D01*
X1201100Y548167D01*
G01X1209550Y547083D02*
X1209967Y546750D01*
X1210550Y546500D01*
X1211050D01*
X1211550Y546667D01*
X1211883Y546917D01*
X1212050Y547250D01*
X1211967Y547750D01*
X1211633Y548000D01*
X1210133Y548500D01*
X1209800Y549083D01*
X1209967Y549500D01*
X1210300Y549750D01*
X1210800Y549833D01*
X1211300Y549750D01*
X1211800Y549500D01*
G01X1216400Y546500D02*
X1215900Y546583D01*
X1215400Y546917D01*
X1215067Y547500D01*
X1214900Y548167D01*
X1215067Y548833D01*
X1215400Y549417D01*
X1215900Y549750D01*
X1216400Y549833D01*
X1216900Y549750D01*
X1217400Y549417D01*
X1217733Y548833D01*
X1217817Y548167D01*
X1217733Y547500D01*
X1217400Y546917D01*
X1216900Y546583D01*
X1216400Y546500D01*
G01X1222000D02*
Y551500D01*
G01X1229100D02*
Y546500D01*
G01Y547250D02*
X1228767Y546833D01*
X1228267Y546583D01*
X1227683Y546500D01*
X1227017Y546667D01*
X1226517Y547083D01*
X1226183Y547583D01*
X1226100Y548167D01*
X1226183Y548750D01*
X1226517Y549250D01*
X1227017Y549667D01*
X1227683Y549833D01*
X1228267Y549750D01*
X1228683Y549583D01*
X1229100Y549250D01*
G01X1231950Y548750D02*
X1234617D01*
X1234367Y549333D01*
X1233950Y549667D01*
X1233367Y549833D01*
X1232783Y549750D01*
X1232283Y549500D01*
X1231950Y548917D01*
X1231783Y548417D01*
Y547917D01*
X1231950Y547417D01*
X1232367Y546917D01*
X1232867Y546583D01*
X1233450Y546500D01*
X1234033Y546667D01*
X1234617Y547167D01*
G01X1237633Y546500D02*
Y549833D01*
G01Y549167D02*
X1238050Y549500D01*
X1238467Y549750D01*
X1239050Y549833D01*
X1239467Y549750D01*
X1239967Y549500D01*
G01X1247500Y546500D02*
Y549833D01*
G01Y548917D02*
X1247750Y549333D01*
X1248167Y549667D01*
X1248750Y549833D01*
X1249333Y549667D01*
X1249750Y549333D01*
X1250000Y548917D01*
Y546500D01*
G01Y548917D02*
X1250250Y549333D01*
X1250667Y549667D01*
X1251250Y549833D01*
X1251833Y549667D01*
X1252250Y549333D01*
X1252500Y548833D01*
Y546500D01*
G01X1257100D02*
Y549833D01*
G01Y549250D02*
X1256767Y549583D01*
X1256267Y549750D01*
X1255683Y549833D01*
X1255100Y549667D01*
X1254600Y549333D01*
X1254267Y548833D01*
X1254100Y548167D01*
X1254267Y547500D01*
X1254600Y547000D01*
X1255100Y546667D01*
X1255683Y546500D01*
X1256267Y546583D01*
X1256767Y546833D01*
X1257100Y547167D01*
G01X1259950Y547083D02*
X1260367Y546750D01*
X1260950Y546500D01*
X1261450D01*
X1261950Y546667D01*
X1262283Y546917D01*
X1262450Y547250D01*
X1262367Y547750D01*
X1262033Y548000D01*
X1260533Y548500D01*
X1260200Y549083D01*
X1260367Y549500D01*
X1260700Y549750D01*
X1261200Y549833D01*
X1261700Y549750D01*
X1262200Y549500D01*
G01X1265383Y546500D02*
Y551500D01*
G01X1268050Y549833D02*
X1265383Y547917D01*
G01X1266467Y548667D02*
X1268217Y546500D01*
G01X1046500Y570833D02*
X1048000Y567500D01*
X1049500Y570833D01*
G01X1053600D02*
Y567500D01*
G01Y572167D02*
X1053433Y572250D01*
Y572417D01*
X1053600Y572500D01*
X1053767Y572417D01*
Y572250D01*
X1053600Y572167D01*
G01X1060700Y567500D02*
Y570833D01*
G01Y570250D02*
X1060367Y570583D01*
X1059867Y570750D01*
X1059283Y570833D01*
X1058700Y570667D01*
X1058200Y570333D01*
X1057867Y569833D01*
X1057700Y569167D01*
X1057867Y568500D01*
X1058200Y568000D01*
X1058700Y567667D01*
X1059283Y567500D01*
X1059867Y567583D01*
X1060367Y567833D01*
X1060700Y568167D01*
G01X1069150Y568083D02*
X1069567Y567750D01*
X1070150Y567500D01*
X1070650D01*
X1071150Y567667D01*
X1071483Y567917D01*
X1071650Y568250D01*
X1071567Y568750D01*
X1071233Y569000D01*
X1069733Y569500D01*
X1069400Y570083D01*
X1069567Y570500D01*
X1069900Y570750D01*
X1070400Y570833D01*
X1070900Y570750D01*
X1071400Y570500D01*
G01X1074583Y567500D02*
Y572500D01*
G01Y570083D02*
X1075000Y570500D01*
X1075417Y570750D01*
X1076083Y570833D01*
X1076583Y570750D01*
X1077167Y570417D01*
X1077417Y569917D01*
Y567500D01*
G01X1083100D02*
Y570833D01*
G01Y570250D02*
X1082767Y570583D01*
X1082267Y570750D01*
X1081683Y570833D01*
X1081100Y570667D01*
X1080600Y570333D01*
X1080267Y569833D01*
X1080100Y569167D01*
X1080267Y568500D01*
X1080600Y568000D01*
X1081100Y567667D01*
X1081683Y567500D01*
X1082267Y567583D01*
X1082767Y567833D01*
X1083100Y568167D01*
G01X1087200Y567500D02*
Y572500D01*
G01X1092800Y567500D02*
Y572500D01*
G01X1102500Y567500D02*
Y572500D01*
G01Y570000D02*
X1102917Y570500D01*
X1103417Y570750D01*
X1103917Y570833D01*
X1104667Y570667D01*
X1105167Y570333D01*
X1105500Y569750D01*
Y569083D01*
X1105333Y568417D01*
X1105000Y567917D01*
X1104417Y567583D01*
X1103917Y567500D01*
X1103417Y567583D01*
X1102917Y567833D01*
X1102500Y568250D01*
G01X1108350Y569750D02*
X1111017D01*
X1110767Y570333D01*
X1110350Y570667D01*
X1109767Y570833D01*
X1109183Y570750D01*
X1108683Y570500D01*
X1108350Y569917D01*
X1108183Y569417D01*
Y568917D01*
X1108350Y568417D01*
X1108767Y567917D01*
X1109267Y567583D01*
X1109850Y567500D01*
X1110433Y567667D01*
X1111017Y568167D01*
G01X1118717Y570833D02*
X1119717Y567500D01*
X1120800Y570833D01*
X1121883Y567500D01*
X1122883Y570833D01*
G01X1126400D02*
Y567500D01*
G01Y572167D02*
X1126233Y572250D01*
Y572417D01*
X1126400Y572500D01*
X1126567Y572417D01*
Y572250D01*
X1126400Y572167D01*
G01X1132000Y572500D02*
Y567500D01*
G01X1130833Y570833D02*
X1133167D01*
G01X1136183Y567500D02*
Y572500D01*
G01Y570083D02*
X1136600Y570500D01*
X1137017Y570750D01*
X1137683Y570833D01*
X1138183Y570750D01*
X1138767Y570417D01*
X1139017Y569917D01*
Y567500D01*
G01X1150467D02*
X1147133Y569167D01*
X1150467Y570833D01*
G01X1160000Y567500D02*
X1160583Y567583D01*
X1161250Y567833D01*
X1161667Y568250D01*
X1161833Y568833D01*
X1161667Y569417D01*
X1161167Y569917D01*
X1160417Y570167D01*
X1159583D01*
X1159083Y570333D01*
X1158667Y570750D01*
X1158500Y571333D01*
X1158750Y571917D01*
X1159333Y572333D01*
X1160000Y572500D01*
X1160667Y572333D01*
X1161250Y571917D01*
X1161500Y571333D01*
X1161333Y570750D01*
X1160917Y570333D01*
X1160417Y570167D01*
X1159583D01*
X1158833Y569917D01*
X1158333Y569417D01*
X1158167Y568833D01*
X1158333Y568250D01*
X1158750Y567833D01*
X1159417Y567583D01*
X1160000Y567500D01*
G01X1165600Y572500D02*
X1164933Y572333D01*
X1164433Y571917D01*
X1164100Y571417D01*
X1163850Y570750D01*
X1163767Y570000D01*
X1163850Y569250D01*
X1164100Y568583D01*
X1164433Y568083D01*
X1164933Y567667D01*
X1165600Y567500D01*
X1166267Y567667D01*
X1166767Y568083D01*
X1167100Y568583D01*
X1167350Y569250D01*
X1167433Y570000D01*
X1167350Y570750D01*
X1167100Y571417D01*
X1166767Y571917D01*
X1166267Y572333D01*
X1165600Y572500D01*
G01X1175300Y567333D02*
X1178300Y572500D01*
G01X1175300D02*
X1174800Y572333D01*
X1174550Y572083D01*
X1174383Y571583D01*
X1174550Y571083D01*
X1174800Y570833D01*
X1175300Y570667D01*
X1175800Y570833D01*
X1176050Y571083D01*
X1176217Y571583D01*
X1176050Y572083D01*
X1175800Y572333D01*
X1175300Y572500D01*
G01X1178300Y569167D02*
X1177800Y569000D01*
X1177550Y568750D01*
X1177383Y568250D01*
X1177550Y567750D01*
X1177800Y567500D01*
X1178300Y567333D01*
X1178800Y567500D01*
X1179050Y567750D01*
X1179217Y568250D01*
X1179050Y568750D01*
X1178800Y569000D01*
X1178300Y569167D01*
G01X1186750Y568083D02*
X1187167Y567750D01*
X1187750Y567500D01*
X1188250D01*
X1188750Y567667D01*
X1189083Y567917D01*
X1189250Y568250D01*
X1189167Y568750D01*
X1188833Y569000D01*
X1187333Y569500D01*
X1187000Y570083D01*
X1187167Y570500D01*
X1187500Y570750D01*
X1188000Y570833D01*
X1188500Y570750D01*
X1189000Y570500D01*
G01X1193600Y567500D02*
X1193100Y567583D01*
X1192600Y567917D01*
X1192267Y568500D01*
X1192100Y569167D01*
X1192267Y569833D01*
X1192600Y570417D01*
X1193100Y570750D01*
X1193600Y570833D01*
X1194100Y570750D01*
X1194600Y570417D01*
X1194933Y569833D01*
X1195017Y569167D01*
X1194933Y568500D01*
X1194600Y567917D01*
X1194100Y567583D01*
X1193600Y567500D01*
G01X1199200D02*
Y572500D01*
G01X1206300D02*
Y567500D01*
G01Y568250D02*
X1205967Y567833D01*
X1205467Y567583D01*
X1204883Y567500D01*
X1204217Y567667D01*
X1203717Y568083D01*
X1203383Y568583D01*
X1203300Y569167D01*
X1203383Y569750D01*
X1203717Y570250D01*
X1204217Y570667D01*
X1204883Y570833D01*
X1205467Y570750D01*
X1205883Y570583D01*
X1206300Y570250D01*
G01X1209150Y569750D02*
X1211817D01*
X1211567Y570333D01*
X1211150Y570667D01*
X1210567Y570833D01*
X1209983Y570750D01*
X1209483Y570500D01*
X1209150Y569917D01*
X1208983Y569417D01*
Y568917D01*
X1209150Y568417D01*
X1209567Y567917D01*
X1210067Y567583D01*
X1210650Y567500D01*
X1211233Y567667D01*
X1211817Y568167D01*
G01X1214833Y567500D02*
Y570833D01*
G01Y570167D02*
X1215250Y570500D01*
X1215667Y570750D01*
X1216250Y570833D01*
X1216667Y570750D01*
X1217167Y570500D01*
G01X1224700Y567500D02*
Y570833D01*
G01Y569917D02*
X1224950Y570333D01*
X1225367Y570667D01*
X1225950Y570833D01*
X1226533Y570667D01*
X1226950Y570333D01*
X1227200Y569917D01*
Y567500D01*
G01Y569917D02*
X1227450Y570333D01*
X1227867Y570667D01*
X1228450Y570833D01*
X1229033Y570667D01*
X1229450Y570333D01*
X1229700Y569833D01*
Y567500D01*
G01X1234300D02*
Y570833D01*
G01Y570250D02*
X1233967Y570583D01*
X1233467Y570750D01*
X1232883Y570833D01*
X1232300Y570667D01*
X1231800Y570333D01*
X1231467Y569833D01*
X1231300Y569167D01*
X1231467Y568500D01*
X1231800Y568000D01*
X1232300Y567667D01*
X1232883Y567500D01*
X1233467Y567583D01*
X1233967Y567833D01*
X1234300Y568167D01*
G01X1237150Y568083D02*
X1237567Y567750D01*
X1238150Y567500D01*
X1238650D01*
X1239150Y567667D01*
X1239483Y567917D01*
X1239650Y568250D01*
X1239567Y568750D01*
X1239233Y569000D01*
X1237733Y569500D01*
X1237400Y570083D01*
X1237567Y570500D01*
X1237900Y570750D01*
X1238400Y570833D01*
X1238900Y570750D01*
X1239400Y570500D01*
G01X1242583Y567500D02*
Y572500D01*
G01X1245250Y570833D02*
X1242583Y568917D01*
G01X1243667Y569667D02*
X1245417Y567500D01*
G01X1035500Y576500D02*
Y581500D01*
G01Y579000D02*
X1035917Y579500D01*
X1036417Y579750D01*
X1036917Y579833D01*
X1037667Y579667D01*
X1038167Y579333D01*
X1038500Y578750D01*
Y578083D01*
X1038333Y577417D01*
X1038000Y576917D01*
X1037417Y576583D01*
X1036917Y576500D01*
X1036417Y576583D01*
X1035917Y576833D01*
X1035500Y577250D01*
G01X1042600Y576333D02*
X1042433Y576417D01*
Y576583D01*
X1042600Y576667D01*
X1042767Y576583D01*
Y576417D01*
X1042600Y576333D01*
G01X1048867Y579167D02*
X1049200Y579417D01*
X1049450Y579833D01*
X1049617Y580417D01*
X1049450Y580917D01*
X1049117Y581250D01*
X1048533Y581500D01*
X1046283D01*
Y576500D01*
X1049033D01*
X1049617Y576833D01*
X1049950Y577333D01*
X1050117Y577917D01*
X1049950Y578500D01*
X1049450Y579000D01*
X1048867Y579167D01*
X1046283D01*
G01X1053800Y576500D02*
X1053300Y576583D01*
X1052800Y576917D01*
X1052467Y577500D01*
X1052300Y578167D01*
X1052467Y578833D01*
X1052800Y579417D01*
X1053300Y579750D01*
X1053800Y579833D01*
X1054300Y579750D01*
X1054800Y579417D01*
X1055133Y578833D01*
X1055217Y578167D01*
X1055133Y577500D01*
X1054800Y576917D01*
X1054300Y576583D01*
X1053800Y576500D01*
G01X1060900D02*
Y579833D01*
G01Y579250D02*
X1060567Y579583D01*
X1060067Y579750D01*
X1059483Y579833D01*
X1058900Y579667D01*
X1058400Y579333D01*
X1058067Y578833D01*
X1057900Y578167D01*
X1058067Y577500D01*
X1058400Y577000D01*
X1058900Y576667D01*
X1059483Y576500D01*
X1060067Y576583D01*
X1060567Y576833D01*
X1060900Y577167D01*
G01X1063833Y576500D02*
Y579833D01*
G01Y579167D02*
X1064250Y579500D01*
X1064667Y579750D01*
X1065250Y579833D01*
X1065667Y579750D01*
X1066167Y579500D01*
G01X1072100Y581500D02*
Y576500D01*
G01Y577250D02*
X1071767Y576833D01*
X1071267Y576583D01*
X1070683Y576500D01*
X1070017Y576667D01*
X1069517Y577083D01*
X1069183Y577583D01*
X1069100Y578167D01*
X1069183Y578750D01*
X1069517Y579250D01*
X1070017Y579667D01*
X1070683Y579833D01*
X1071267Y579750D01*
X1071683Y579583D01*
X1072100Y579250D01*
G01X1081800Y581500D02*
Y576500D01*
G01X1080633Y579833D02*
X1082967D01*
G01X1085983Y576500D02*
Y581500D01*
G01Y579083D02*
X1086400Y579500D01*
X1086817Y579750D01*
X1087483Y579833D01*
X1087983Y579750D01*
X1088567Y579417D01*
X1088817Y578917D01*
Y576500D01*
G01X1093000Y579833D02*
Y576500D01*
G01Y581167D02*
X1092833Y581250D01*
Y581417D01*
X1093000Y581500D01*
X1093167Y581417D01*
Y581250D01*
X1093000Y581167D01*
G01X1099933Y579417D02*
X1099350Y579750D01*
X1098850Y579833D01*
X1098183Y579667D01*
X1097683Y579333D01*
X1097350Y578750D01*
X1097267Y578167D01*
X1097350Y577583D01*
X1097683Y577083D01*
X1098183Y576667D01*
X1098850Y576500D01*
X1099433Y576667D01*
X1099933Y577000D01*
G01X1102783Y576500D02*
Y581500D01*
G01X1105450Y579833D02*
X1102783Y577917D01*
G01X1103867Y578667D02*
X1105617Y576500D01*
G01X1108383D02*
Y579833D01*
G01Y579000D02*
X1108717Y579417D01*
X1109217Y579750D01*
X1109883Y579833D01*
X1110467Y579750D01*
X1110967Y579417D01*
X1111217Y578833D01*
Y576500D01*
G01X1114150Y578750D02*
X1116817D01*
X1116567Y579333D01*
X1116150Y579667D01*
X1115567Y579833D01*
X1114983Y579750D01*
X1114483Y579500D01*
X1114150Y578917D01*
X1113983Y578417D01*
Y577917D01*
X1114150Y577417D01*
X1114567Y576917D01*
X1115067Y576583D01*
X1115650Y576500D01*
X1116233Y576667D01*
X1116817Y577167D01*
G01X1119750Y577083D02*
X1120167Y576750D01*
X1120750Y576500D01*
X1121250D01*
X1121750Y576667D01*
X1122083Y576917D01*
X1122250Y577250D01*
X1122167Y577750D01*
X1121833Y578000D01*
X1120333Y578500D01*
X1120000Y579083D01*
X1120167Y579500D01*
X1120500Y579750D01*
X1121000Y579833D01*
X1121500Y579750D01*
X1122000Y579500D01*
G01X1125350Y577083D02*
X1125767Y576750D01*
X1126350Y576500D01*
X1126850D01*
X1127350Y576667D01*
X1127683Y576917D01*
X1127850Y577250D01*
X1127767Y577750D01*
X1127433Y578000D01*
X1125933Y578500D01*
X1125600Y579083D01*
X1125767Y579500D01*
X1126100Y579750D01*
X1126600Y579833D01*
X1127100Y579750D01*
X1127600Y579500D01*
G01X1139467Y576500D02*
X1136133Y578167D01*
X1139467Y579833D01*
G01X1149000Y581500D02*
X1148333Y581333D01*
X1147833Y580917D01*
X1147500Y580417D01*
X1147250Y579750D01*
X1147167Y579000D01*
X1147250Y578250D01*
X1147500Y577583D01*
X1147833Y577083D01*
X1148333Y576667D01*
X1149000Y576500D01*
X1149667Y576667D01*
X1150167Y577083D01*
X1150500Y577583D01*
X1150750Y578250D01*
X1150833Y579000D01*
X1150750Y579750D01*
X1150500Y580417D01*
X1150167Y580917D01*
X1149667Y581333D01*
X1149000Y581500D01*
G01X1154600Y576333D02*
X1154433Y576417D01*
Y576583D01*
X1154600Y576667D01*
X1154767Y576583D01*
Y576417D01*
X1154600Y576333D01*
G01X1158783Y577083D02*
X1159367Y576667D01*
X1160033Y576500D01*
X1160700Y576667D01*
X1161283Y577167D01*
X1161700Y577917D01*
X1161867Y578667D01*
Y579583D01*
X1161700Y580333D01*
X1161283Y581000D01*
X1160783Y581333D01*
X1160200Y581500D01*
X1159533Y581333D01*
X1159033Y581000D01*
X1158700Y580500D01*
X1158533Y579833D01*
X1158700Y579250D01*
X1159117Y578667D01*
X1159617Y578333D01*
X1160200Y578250D01*
X1160867Y578417D01*
X1161367Y578833D01*
X1161867Y579583D01*
G01X1163300Y576500D02*
Y579833D01*
G01Y578917D02*
X1163550Y579333D01*
X1163967Y579667D01*
X1164550Y579833D01*
X1165133Y579667D01*
X1165550Y579333D01*
X1165800Y578917D01*
Y576500D01*
G01Y578917D02*
X1166050Y579333D01*
X1166467Y579667D01*
X1167050Y579833D01*
X1167633Y579667D01*
X1168050Y579333D01*
X1168300Y578833D01*
Y576500D01*
G01X1168900D02*
Y579833D01*
G01Y578917D02*
X1169150Y579333D01*
X1169567Y579667D01*
X1170150Y579833D01*
X1170733Y579667D01*
X1171150Y579333D01*
X1171400Y578917D01*
Y576500D01*
G01Y578917D02*
X1171650Y579333D01*
X1172067Y579667D01*
X1172650Y579833D01*
X1173233Y579667D01*
X1173650Y579333D01*
X1173900Y578833D01*
Y576500D01*
G01X1177000Y576333D02*
X1176833Y576417D01*
Y576583D01*
X1177000Y576667D01*
X1177167Y576583D01*
Y576417D01*
X1177000Y576333D01*
G01Y578583D02*
X1176833Y578667D01*
Y578833D01*
X1177000Y578917D01*
X1177167Y578833D01*
Y578667D01*
X1177000Y578583D01*
G01X1045500Y589833D02*
X1047000Y586500D01*
X1048500Y589833D01*
G01X1052600D02*
Y586500D01*
G01Y591167D02*
X1052433Y591250D01*
Y591417D01*
X1052600Y591500D01*
X1052767Y591417D01*
Y591250D01*
X1052600Y591167D01*
G01X1059700Y586500D02*
Y589833D01*
G01Y589250D02*
X1059367Y589583D01*
X1058867Y589750D01*
X1058283Y589833D01*
X1057700Y589667D01*
X1057200Y589333D01*
X1056867Y588833D01*
X1056700Y588167D01*
X1056867Y587500D01*
X1057200Y587000D01*
X1057700Y586667D01*
X1058283Y586500D01*
X1058867Y586583D01*
X1059367Y586833D01*
X1059700Y587167D01*
G01X1068150Y587083D02*
X1068567Y586750D01*
X1069150Y586500D01*
X1069650D01*
X1070150Y586667D01*
X1070483Y586917D01*
X1070650Y587250D01*
X1070567Y587750D01*
X1070233Y588000D01*
X1068733Y588500D01*
X1068400Y589083D01*
X1068567Y589500D01*
X1068900Y589750D01*
X1069400Y589833D01*
X1069900Y589750D01*
X1070400Y589500D01*
G01X1073583Y586500D02*
Y591500D01*
G01Y589083D02*
X1074000Y589500D01*
X1074417Y589750D01*
X1075083Y589833D01*
X1075583Y589750D01*
X1076167Y589417D01*
X1076417Y588917D01*
Y586500D01*
G01X1082100D02*
Y589833D01*
G01Y589250D02*
X1081767Y589583D01*
X1081267Y589750D01*
X1080683Y589833D01*
X1080100Y589667D01*
X1079600Y589333D01*
X1079267Y588833D01*
X1079100Y588167D01*
X1079267Y587500D01*
X1079600Y587000D01*
X1080100Y586667D01*
X1080683Y586500D01*
X1081267Y586583D01*
X1081767Y586833D01*
X1082100Y587167D01*
G01X1086200Y586500D02*
Y591500D01*
G01X1091800Y586500D02*
Y591500D01*
G01X1101500Y586500D02*
Y591500D01*
G01Y589000D02*
X1101917Y589500D01*
X1102417Y589750D01*
X1102917Y589833D01*
X1103667Y589667D01*
X1104167Y589333D01*
X1104500Y588750D01*
Y588083D01*
X1104333Y587417D01*
X1104000Y586917D01*
X1103417Y586583D01*
X1102917Y586500D01*
X1102417Y586583D01*
X1101917Y586833D01*
X1101500Y587250D01*
G01X1107350Y588750D02*
X1110017D01*
X1109767Y589333D01*
X1109350Y589667D01*
X1108767Y589833D01*
X1108183Y589750D01*
X1107683Y589500D01*
X1107350Y588917D01*
X1107183Y588417D01*
Y587917D01*
X1107350Y587417D01*
X1107767Y586917D01*
X1108267Y586583D01*
X1108850Y586500D01*
X1109433Y586667D01*
X1110017Y587167D01*
G01X1118300Y584833D02*
Y589833D01*
G01Y589083D02*
X1118717Y589500D01*
X1119133Y589750D01*
X1119800Y589833D01*
X1120383Y589750D01*
X1120967Y589333D01*
X1121217Y588750D01*
X1121300Y588167D01*
X1121217Y587583D01*
X1120967Y587000D01*
X1120467Y586667D01*
X1119800Y586500D01*
X1119217Y586583D01*
X1118633Y586833D01*
X1118300Y587167D01*
G01X1125400Y586500D02*
Y591500D01*
G01X1129583Y589833D02*
Y587500D01*
X1129917Y586917D01*
X1130417Y586583D01*
X1131000Y586500D01*
X1131583Y586583D01*
X1132083Y586917D01*
X1132417Y587500D01*
G01Y586500D02*
Y589833D01*
G01X1135433Y585250D02*
X1136017Y584917D01*
X1136683Y584833D01*
X1137267Y584917D01*
X1137767Y585333D01*
X1138100Y585917D01*
Y589833D01*
G01Y589167D02*
X1137767Y589500D01*
X1137267Y589750D01*
X1136683Y589833D01*
X1136017Y589667D01*
X1135600Y589333D01*
X1135267Y588750D01*
X1135100Y588167D01*
X1135183Y587667D01*
X1135517Y587083D01*
X1136017Y586667D01*
X1136683Y586500D01*
X1137183Y586583D01*
X1137767Y586917D01*
X1138100Y587250D01*
G01X1141033Y585250D02*
X1141617Y584917D01*
X1142283Y584833D01*
X1142867Y584917D01*
X1143367Y585333D01*
X1143700Y585917D01*
Y589833D01*
G01Y589167D02*
X1143367Y589500D01*
X1142867Y589750D01*
X1142283Y589833D01*
X1141617Y589667D01*
X1141200Y589333D01*
X1140867Y588750D01*
X1140700Y588167D01*
X1140783Y587667D01*
X1141117Y587083D01*
X1141617Y586667D01*
X1142283Y586500D01*
X1142783Y586583D01*
X1143367Y586917D01*
X1143700Y587250D01*
G01X1146550Y588750D02*
X1149217D01*
X1148967Y589333D01*
X1148550Y589667D01*
X1147967Y589833D01*
X1147383Y589750D01*
X1146883Y589500D01*
X1146550Y588917D01*
X1146383Y588417D01*
Y587917D01*
X1146550Y587417D01*
X1146967Y586917D01*
X1147467Y586583D01*
X1148050Y586500D01*
X1148633Y586667D01*
X1149217Y587167D01*
G01X1154900Y591500D02*
Y586500D01*
G01Y587250D02*
X1154567Y586833D01*
X1154067Y586583D01*
X1153483Y586500D01*
X1152817Y586667D01*
X1152317Y587083D01*
X1151983Y587583D01*
X1151900Y588167D01*
X1151983Y588750D01*
X1152317Y589250D01*
X1152817Y589667D01*
X1153483Y589833D01*
X1154067Y589750D01*
X1154483Y589583D01*
X1154900Y589250D01*
G01X1162517Y589833D02*
X1163517Y586500D01*
X1164600Y589833D01*
X1165683Y586500D01*
X1166683Y589833D01*
G01X1170200D02*
Y586500D01*
G01Y591167D02*
X1170033Y591250D01*
Y591417D01*
X1170200Y591500D01*
X1170367Y591417D01*
Y591250D01*
X1170200Y591167D01*
G01X1175800Y591500D02*
Y586500D01*
G01X1174633Y589833D02*
X1176967D01*
G01X1179983Y586500D02*
Y591500D01*
G01Y589083D02*
X1180400Y589500D01*
X1180817Y589750D01*
X1181483Y589833D01*
X1181983Y589750D01*
X1182567Y589417D01*
X1182817Y588917D01*
Y586500D01*
G01X1194267D02*
X1190933Y588167D01*
X1194267Y589833D01*
G01X1201967Y587250D02*
X1202467Y586833D01*
X1203050Y586583D01*
X1203800Y586500D01*
X1204550Y586667D01*
X1205133Y587000D01*
X1205550Y587583D01*
X1205633Y588250D01*
X1205467Y588917D01*
X1205050Y589333D01*
X1204467Y589667D01*
X1203883Y589750D01*
X1203300Y589667D01*
X1202550Y589333D01*
X1202800Y591500D01*
X1205050D01*
G01X1209400D02*
X1208733Y591333D01*
X1208233Y590917D01*
X1207900Y590417D01*
X1207650Y589750D01*
X1207567Y589000D01*
X1207650Y588250D01*
X1207900Y587583D01*
X1208233Y587083D01*
X1208733Y586667D01*
X1209400Y586500D01*
X1210067Y586667D01*
X1210567Y587083D01*
X1210900Y587583D01*
X1211150Y588250D01*
X1211233Y589000D01*
X1211150Y589750D01*
X1210900Y590417D01*
X1210567Y590917D01*
X1210067Y591333D01*
X1209400Y591500D01*
G01X1219100Y586333D02*
X1222100Y591500D01*
G01X1219100D02*
X1218600Y591333D01*
X1218350Y591083D01*
X1218183Y590583D01*
X1218350Y590083D01*
X1218600Y589833D01*
X1219100Y589667D01*
X1219600Y589833D01*
X1219850Y590083D01*
X1220017Y590583D01*
X1219850Y591083D01*
X1219600Y591333D01*
X1219100Y591500D01*
G01X1222100Y588167D02*
X1221600Y588000D01*
X1221350Y587750D01*
X1221183Y587250D01*
X1221350Y586750D01*
X1221600Y586500D01*
X1222100Y586333D01*
X1222600Y586500D01*
X1222850Y586750D01*
X1223017Y587250D01*
X1222850Y587750D01*
X1222600Y588000D01*
X1222100Y588167D01*
G01X1230550Y587083D02*
X1230967Y586750D01*
X1231550Y586500D01*
X1232050D01*
X1232550Y586667D01*
X1232883Y586917D01*
X1233050Y587250D01*
X1232967Y587750D01*
X1232633Y588000D01*
X1231133Y588500D01*
X1230800Y589083D01*
X1230967Y589500D01*
X1231300Y589750D01*
X1231800Y589833D01*
X1232300Y589750D01*
X1232800Y589500D01*
G01X1237400Y586500D02*
X1236900Y586583D01*
X1236400Y586917D01*
X1236067Y587500D01*
X1235900Y588167D01*
X1236067Y588833D01*
X1236400Y589417D01*
X1236900Y589750D01*
X1237400Y589833D01*
X1237900Y589750D01*
X1238400Y589417D01*
X1238733Y588833D01*
X1238817Y588167D01*
X1238733Y587500D01*
X1238400Y586917D01*
X1237900Y586583D01*
X1237400Y586500D01*
G01X1243000D02*
Y591500D01*
G01X1250100D02*
Y586500D01*
G01Y587250D02*
X1249767Y586833D01*
X1249267Y586583D01*
X1248683Y586500D01*
X1248017Y586667D01*
X1247517Y587083D01*
X1247183Y587583D01*
X1247100Y588167D01*
X1247183Y588750D01*
X1247517Y589250D01*
X1248017Y589667D01*
X1248683Y589833D01*
X1249267Y589750D01*
X1249683Y589583D01*
X1250100Y589250D01*
G01X1252950Y588750D02*
X1255617D01*
X1255367Y589333D01*
X1254950Y589667D01*
X1254367Y589833D01*
X1253783Y589750D01*
X1253283Y589500D01*
X1252950Y588917D01*
X1252783Y588417D01*
Y587917D01*
X1252950Y587417D01*
X1253367Y586917D01*
X1253867Y586583D01*
X1254450Y586500D01*
X1255033Y586667D01*
X1255617Y587167D01*
G01X1258633Y586500D02*
Y589833D01*
G01Y589167D02*
X1259050Y589500D01*
X1259467Y589750D01*
X1260050Y589833D01*
X1260467Y589750D01*
X1260967Y589500D01*
G01X1268500Y586500D02*
Y589833D01*
G01Y588917D02*
X1268750Y589333D01*
X1269167Y589667D01*
X1269750Y589833D01*
X1270333Y589667D01*
X1270750Y589333D01*
X1271000Y588917D01*
Y586500D01*
G01Y588917D02*
X1271250Y589333D01*
X1271667Y589667D01*
X1272250Y589833D01*
X1272833Y589667D01*
X1273250Y589333D01*
X1273500Y588833D01*
Y586500D01*
G01X1278100D02*
Y589833D01*
G01Y589250D02*
X1277767Y589583D01*
X1277267Y589750D01*
X1276683Y589833D01*
X1276100Y589667D01*
X1275600Y589333D01*
X1275267Y588833D01*
X1275100Y588167D01*
X1275267Y587500D01*
X1275600Y587000D01*
X1276100Y586667D01*
X1276683Y586500D01*
X1277267Y586583D01*
X1277767Y586833D01*
X1278100Y587167D01*
G01X1280950Y587083D02*
X1281367Y586750D01*
X1281950Y586500D01*
X1282450D01*
X1282950Y586667D01*
X1283283Y586917D01*
X1283450Y587250D01*
X1283367Y587750D01*
X1283033Y588000D01*
X1281533Y588500D01*
X1281200Y589083D01*
X1281367Y589500D01*
X1281700Y589750D01*
X1282200Y589833D01*
X1282700Y589750D01*
X1283200Y589500D01*
G01X1286383Y586500D02*
Y591500D01*
G01X1289050Y589833D02*
X1286383Y587917D01*
G01X1287467Y588667D02*
X1289217Y586500D01*
G01X1293233Y585583D02*
X1293567Y586667D01*
G01X1038500Y595500D02*
Y598833D01*
G01Y598250D02*
X1038167Y598583D01*
X1037667Y598750D01*
X1037083Y598833D01*
X1036500Y598667D01*
X1036000Y598333D01*
X1035667Y597833D01*
X1035500Y597167D01*
X1035667Y596500D01*
X1036000Y596000D01*
X1036500Y595667D01*
X1037083Y595500D01*
X1037667Y595583D01*
X1038167Y595833D01*
X1038500Y596167D01*
G01X1042600Y595333D02*
X1042433Y595417D01*
Y595583D01*
X1042600Y595667D01*
X1042767Y595583D01*
Y595417D01*
X1042600Y595333D01*
G01X1048867Y598167D02*
X1049200Y598417D01*
X1049450Y598833D01*
X1049617Y599417D01*
X1049450Y599917D01*
X1049117Y600250D01*
X1048533Y600500D01*
X1046283D01*
Y595500D01*
X1049033D01*
X1049617Y595833D01*
X1049950Y596333D01*
X1050117Y596917D01*
X1049950Y597500D01*
X1049450Y598000D01*
X1048867Y598167D01*
X1046283D01*
G01X1053800Y595500D02*
X1053300Y595583D01*
X1052800Y595917D01*
X1052467Y596500D01*
X1052300Y597167D01*
X1052467Y597833D01*
X1052800Y598417D01*
X1053300Y598750D01*
X1053800Y598833D01*
X1054300Y598750D01*
X1054800Y598417D01*
X1055133Y597833D01*
X1055217Y597167D01*
X1055133Y596500D01*
X1054800Y595917D01*
X1054300Y595583D01*
X1053800Y595500D01*
G01X1060900D02*
Y598833D01*
G01Y598250D02*
X1060567Y598583D01*
X1060067Y598750D01*
X1059483Y598833D01*
X1058900Y598667D01*
X1058400Y598333D01*
X1058067Y597833D01*
X1057900Y597167D01*
X1058067Y596500D01*
X1058400Y596000D01*
X1058900Y595667D01*
X1059483Y595500D01*
X1060067Y595583D01*
X1060567Y595833D01*
X1060900Y596167D01*
G01X1063833Y595500D02*
Y598833D01*
G01Y598167D02*
X1064250Y598500D01*
X1064667Y598750D01*
X1065250Y598833D01*
X1065667Y598750D01*
X1066167Y598500D01*
G01X1072100Y600500D02*
Y595500D01*
G01Y596250D02*
X1071767Y595833D01*
X1071267Y595583D01*
X1070683Y595500D01*
X1070017Y595667D01*
X1069517Y596083D01*
X1069183Y596583D01*
X1069100Y597167D01*
X1069183Y597750D01*
X1069517Y598250D01*
X1070017Y598667D01*
X1070683Y598833D01*
X1071267Y598750D01*
X1071683Y598583D01*
X1072100Y598250D01*
G01X1081800Y600500D02*
Y595500D01*
G01X1080633Y598833D02*
X1082967D01*
G01X1085983Y595500D02*
Y600500D01*
G01Y598083D02*
X1086400Y598500D01*
X1086817Y598750D01*
X1087483Y598833D01*
X1087983Y598750D01*
X1088567Y598417D01*
X1088817Y597917D01*
Y595500D01*
G01X1093000Y598833D02*
Y595500D01*
G01Y600167D02*
X1092833Y600250D01*
Y600417D01*
X1093000Y600500D01*
X1093167Y600417D01*
Y600250D01*
X1093000Y600167D01*
G01X1099933Y598417D02*
X1099350Y598750D01*
X1098850Y598833D01*
X1098183Y598667D01*
X1097683Y598333D01*
X1097350Y597750D01*
X1097267Y597167D01*
X1097350Y596583D01*
X1097683Y596083D01*
X1098183Y595667D01*
X1098850Y595500D01*
X1099433Y595667D01*
X1099933Y596000D01*
G01X1102783Y595500D02*
Y600500D01*
G01X1105450Y598833D02*
X1102783Y596917D01*
G01X1103867Y597667D02*
X1105617Y595500D01*
G01X1108383D02*
Y598833D01*
G01Y598000D02*
X1108717Y598417D01*
X1109217Y598750D01*
X1109883Y598833D01*
X1110467Y598750D01*
X1110967Y598417D01*
X1111217Y597833D01*
Y595500D01*
G01X1114150Y597750D02*
X1116817D01*
X1116567Y598333D01*
X1116150Y598667D01*
X1115567Y598833D01*
X1114983Y598750D01*
X1114483Y598500D01*
X1114150Y597917D01*
X1113983Y597417D01*
Y596917D01*
X1114150Y596417D01*
X1114567Y595917D01*
X1115067Y595583D01*
X1115650Y595500D01*
X1116233Y595667D01*
X1116817Y596167D01*
G01X1119750Y596083D02*
X1120167Y595750D01*
X1120750Y595500D01*
X1121250D01*
X1121750Y595667D01*
X1122083Y595917D01*
X1122250Y596250D01*
X1122167Y596750D01*
X1121833Y597000D01*
X1120333Y597500D01*
X1120000Y598083D01*
X1120167Y598500D01*
X1120500Y598750D01*
X1121000Y598833D01*
X1121500Y598750D01*
X1122000Y598500D01*
G01X1125350Y596083D02*
X1125767Y595750D01*
X1126350Y595500D01*
X1126850D01*
X1127350Y595667D01*
X1127683Y595917D01*
X1127850Y596250D01*
X1127767Y596750D01*
X1127433Y597000D01*
X1125933Y597500D01*
X1125600Y598083D01*
X1125767Y598500D01*
X1126100Y598750D01*
X1126600Y598833D01*
X1127100Y598750D01*
X1127600Y598500D01*
G01X1130533Y595500D02*
X1133867Y597167D01*
X1130533Y598833D01*
G01X1136717Y596417D02*
X1138883D01*
G01Y597917D02*
X1136717D01*
G01X1149000Y600500D02*
X1148333Y600333D01*
X1147833Y599917D01*
X1147500Y599417D01*
X1147250Y598750D01*
X1147167Y598000D01*
X1147250Y597250D01*
X1147500Y596583D01*
X1147833Y596083D01*
X1148333Y595667D01*
X1149000Y595500D01*
X1149667Y595667D01*
X1150167Y596083D01*
X1150500Y596583D01*
X1150750Y597250D01*
X1150833Y598000D01*
X1150750Y598750D01*
X1150500Y599417D01*
X1150167Y599917D01*
X1149667Y600333D01*
X1149000Y600500D01*
G01X1154600Y595333D02*
X1154433Y595417D01*
Y595583D01*
X1154600Y595667D01*
X1154767Y595583D01*
Y595417D01*
X1154600Y595333D01*
G01X1158783Y596083D02*
X1159367Y595667D01*
X1160033Y595500D01*
X1160700Y595667D01*
X1161283Y596167D01*
X1161700Y596917D01*
X1161867Y597667D01*
Y598583D01*
X1161700Y599333D01*
X1161283Y600000D01*
X1160783Y600333D01*
X1160200Y600500D01*
X1159533Y600333D01*
X1159033Y600000D01*
X1158700Y599500D01*
X1158533Y598833D01*
X1158700Y598250D01*
X1159117Y597667D01*
X1159617Y597333D01*
X1160200Y597250D01*
X1160867Y597417D01*
X1161367Y597833D01*
X1161867Y598583D01*
G01X1163300Y595500D02*
Y598833D01*
G01Y597917D02*
X1163550Y598333D01*
X1163967Y598667D01*
X1164550Y598833D01*
X1165133Y598667D01*
X1165550Y598333D01*
X1165800Y597917D01*
Y595500D01*
G01Y597917D02*
X1166050Y598333D01*
X1166467Y598667D01*
X1167050Y598833D01*
X1167633Y598667D01*
X1168050Y598333D01*
X1168300Y597833D01*
Y595500D01*
G01X1171400Y595333D02*
X1171233Y595417D01*
Y595583D01*
X1171400Y595667D01*
X1171567Y595583D01*
Y595417D01*
X1171400Y595333D01*
G01Y597583D02*
X1171233Y597667D01*
Y597833D01*
X1171400Y597917D01*
X1171567Y597833D01*
Y597667D01*
X1171400Y597583D01*
G01X1034250Y605500D02*
Y610500D01*
G01X1037750D02*
Y605500D01*
G01Y608000D02*
X1034250D01*
G01X1043100Y605500D02*
Y608833D01*
G01Y608250D02*
X1042767Y608583D01*
X1042267Y608750D01*
X1041683Y608833D01*
X1041100Y608667D01*
X1040600Y608333D01*
X1040267Y607833D01*
X1040100Y607167D01*
X1040267Y606500D01*
X1040600Y606000D01*
X1041100Y605667D01*
X1041683Y605500D01*
X1042267Y605583D01*
X1042767Y605833D01*
X1043100Y606167D01*
G01X1047200Y605500D02*
Y610500D01*
G01X1052300Y605500D02*
Y609750D01*
X1052467Y610167D01*
X1052800Y610417D01*
X1053300Y610500D01*
X1053800Y610333D01*
X1054050Y609917D01*
G01X1053050Y608500D02*
X1051383D01*
G01X1057317Y607167D02*
X1059483D01*
G01X1062500Y603833D02*
Y608833D01*
G01Y608083D02*
X1062917Y608500D01*
X1063333Y608750D01*
X1064000Y608833D01*
X1064583Y608750D01*
X1065167Y608333D01*
X1065417Y607750D01*
X1065500Y607167D01*
X1065417Y606583D01*
X1065167Y606000D01*
X1064667Y605667D01*
X1064000Y605500D01*
X1063417Y605583D01*
X1062833Y605833D01*
X1062500Y606167D01*
G01X1069600Y605500D02*
Y610500D01*
G01X1073783Y608833D02*
Y606500D01*
X1074117Y605917D01*
X1074617Y605583D01*
X1075200Y605500D01*
X1075783Y605583D01*
X1076283Y605917D01*
X1076617Y606500D01*
G01Y605500D02*
Y608833D01*
G01X1079633Y604250D02*
X1080217Y603917D01*
X1080883Y603833D01*
X1081467Y603917D01*
X1081967Y604333D01*
X1082300Y604917D01*
Y608833D01*
G01Y608167D02*
X1081967Y608500D01*
X1081467Y608750D01*
X1080883Y608833D01*
X1080217Y608667D01*
X1079800Y608333D01*
X1079467Y607750D01*
X1079300Y607167D01*
X1079383Y606667D01*
X1079717Y606083D01*
X1080217Y605667D01*
X1080883Y605500D01*
X1081383Y605583D01*
X1081967Y605917D01*
X1082300Y606250D01*
G01X1085233Y604250D02*
X1085817Y603917D01*
X1086483Y603833D01*
X1087067Y603917D01*
X1087567Y604333D01*
X1087900Y604917D01*
Y608833D01*
G01Y608167D02*
X1087567Y608500D01*
X1087067Y608750D01*
X1086483Y608833D01*
X1085817Y608667D01*
X1085400Y608333D01*
X1085067Y607750D01*
X1084900Y607167D01*
X1084983Y606667D01*
X1085317Y606083D01*
X1085817Y605667D01*
X1086483Y605500D01*
X1086983Y605583D01*
X1087567Y605917D01*
X1087900Y606250D01*
G01X1092000Y608833D02*
Y605500D01*
G01Y610167D02*
X1091833Y610250D01*
Y610417D01*
X1092000Y610500D01*
X1092167Y610417D01*
Y610250D01*
X1092000Y610167D01*
G01X1096183Y605500D02*
Y608833D01*
G01Y608000D02*
X1096517Y608417D01*
X1097017Y608750D01*
X1097683Y608833D01*
X1098267Y608750D01*
X1098767Y608417D01*
X1099017Y607833D01*
Y605500D01*
G01X1102033Y604250D02*
X1102617Y603917D01*
X1103283Y603833D01*
X1103867Y603917D01*
X1104367Y604333D01*
X1104700Y604917D01*
Y608833D01*
G01Y608167D02*
X1104367Y608500D01*
X1103867Y608750D01*
X1103283Y608833D01*
X1102617Y608667D01*
X1102200Y608333D01*
X1101867Y607750D01*
X1101700Y607167D01*
X1101783Y606667D01*
X1102117Y606083D01*
X1102617Y605667D01*
X1103283Y605500D01*
X1103783Y605583D01*
X1104367Y605917D01*
X1104700Y606250D01*
G01X1114400Y605333D02*
X1114233Y605417D01*
Y605583D01*
X1114400Y605667D01*
X1114567Y605583D01*
Y605417D01*
X1114400Y605333D01*
G01Y607583D02*
X1114233Y607667D01*
Y607833D01*
X1114400Y607917D01*
X1114567Y607833D01*
Y607667D01*
X1114400Y607583D01*
G01X1125600Y610500D02*
Y605500D01*
G01X1124433Y608833D02*
X1126767D01*
G01X1129783Y605500D02*
Y610500D01*
G01Y608083D02*
X1130200Y608500D01*
X1130617Y608750D01*
X1131283Y608833D01*
X1131783Y608750D01*
X1132367Y608417D01*
X1132617Y607917D01*
Y605500D01*
G01X1135550Y607750D02*
X1138217D01*
X1137967Y608333D01*
X1137550Y608667D01*
X1136967Y608833D01*
X1136383Y608750D01*
X1135883Y608500D01*
X1135550Y607917D01*
X1135383Y607417D01*
Y606917D01*
X1135550Y606417D01*
X1135967Y605917D01*
X1136467Y605583D01*
X1137050Y605500D01*
X1137633Y605667D01*
X1138217Y606167D01*
G01X1146500Y603833D02*
Y608833D01*
G01Y608083D02*
X1146917Y608500D01*
X1147333Y608750D01*
X1148000Y608833D01*
X1148583Y608750D01*
X1149167Y608333D01*
X1149417Y607750D01*
X1149500Y607167D01*
X1149417Y606583D01*
X1149167Y606000D01*
X1148667Y605667D01*
X1148000Y605500D01*
X1147417Y605583D01*
X1146833Y605833D01*
X1146500Y606167D01*
G01X1153600Y605500D02*
Y610500D01*
G01X1157783Y608833D02*
Y606500D01*
X1158117Y605917D01*
X1158617Y605583D01*
X1159200Y605500D01*
X1159783Y605583D01*
X1160283Y605917D01*
X1160617Y606500D01*
G01Y605500D02*
Y608833D01*
G01X1163633Y604250D02*
X1164217Y603917D01*
X1164883Y603833D01*
X1165467Y603917D01*
X1165967Y604333D01*
X1166300Y604917D01*
Y608833D01*
G01Y608167D02*
X1165967Y608500D01*
X1165467Y608750D01*
X1164883Y608833D01*
X1164217Y608667D01*
X1163800Y608333D01*
X1163467Y607750D01*
X1163300Y607167D01*
X1163383Y606667D01*
X1163717Y606083D01*
X1164217Y605667D01*
X1164883Y605500D01*
X1165383Y605583D01*
X1165967Y605917D01*
X1166300Y606250D01*
G01X1169233Y604250D02*
X1169817Y603917D01*
X1170483Y603833D01*
X1171067Y603917D01*
X1171567Y604333D01*
X1171900Y604917D01*
Y608833D01*
G01Y608167D02*
X1171567Y608500D01*
X1171067Y608750D01*
X1170483Y608833D01*
X1169817Y608667D01*
X1169400Y608333D01*
X1169067Y607750D01*
X1168900Y607167D01*
X1168983Y606667D01*
X1169317Y606083D01*
X1169817Y605667D01*
X1170483Y605500D01*
X1170983Y605583D01*
X1171567Y605917D01*
X1171900Y606250D01*
G01X1176000Y608833D02*
Y605500D01*
G01Y610167D02*
X1175833Y610250D01*
Y610417D01*
X1176000Y610500D01*
X1176167Y610417D01*
Y610250D01*
X1176000Y610167D01*
G01X1180183Y605500D02*
Y608833D01*
G01Y608000D02*
X1180517Y608417D01*
X1181017Y608750D01*
X1181683Y608833D01*
X1182267Y608750D01*
X1182767Y608417D01*
X1183017Y607833D01*
Y605500D01*
G01X1186033Y604250D02*
X1186617Y603917D01*
X1187283Y603833D01*
X1187867Y603917D01*
X1188367Y604333D01*
X1188700Y604917D01*
Y608833D01*
G01Y608167D02*
X1188367Y608500D01*
X1187867Y608750D01*
X1187283Y608833D01*
X1186617Y608667D01*
X1186200Y608333D01*
X1185867Y607750D01*
X1185700Y607167D01*
X1185783Y606667D01*
X1186117Y606083D01*
X1186617Y605667D01*
X1187283Y605500D01*
X1187783Y605583D01*
X1188367Y605917D01*
X1188700Y606250D01*
G01X1197233Y605500D02*
Y608833D01*
G01Y608167D02*
X1197650Y608500D01*
X1198067Y608750D01*
X1198650Y608833D01*
X1199067Y608750D01*
X1199567Y608500D01*
G01X1205500Y605500D02*
Y608833D01*
G01Y608250D02*
X1205167Y608583D01*
X1204667Y608750D01*
X1204083Y608833D01*
X1203500Y608667D01*
X1203000Y608333D01*
X1202667Y607833D01*
X1202500Y607167D01*
X1202667Y606500D01*
X1203000Y606000D01*
X1203500Y605667D01*
X1204083Y605500D01*
X1204667Y605583D01*
X1205167Y605833D01*
X1205500Y606167D01*
G01X1209600Y610500D02*
Y605500D01*
G01X1208433Y608833D02*
X1210767D01*
G01X1215200D02*
Y605500D01*
G01Y610167D02*
X1215033Y610250D01*
Y610417D01*
X1215200Y610500D01*
X1215367Y610417D01*
Y610250D01*
X1215200Y610167D01*
G01X1220800Y605500D02*
X1220300Y605583D01*
X1219800Y605917D01*
X1219467Y606500D01*
X1219300Y607167D01*
X1219467Y607833D01*
X1219800Y608417D01*
X1220300Y608750D01*
X1220800Y608833D01*
X1221300Y608750D01*
X1221800Y608417D01*
X1222133Y607833D01*
X1222217Y607167D01*
X1222133Y606500D01*
X1221800Y605917D01*
X1221300Y605583D01*
X1220800Y605500D01*
G01X1230500Y603833D02*
Y608833D01*
G01Y608083D02*
X1230917Y608500D01*
X1231333Y608750D01*
X1232000Y608833D01*
X1232583Y608750D01*
X1233167Y608333D01*
X1233417Y607750D01*
X1233500Y607167D01*
X1233417Y606583D01*
X1233167Y606000D01*
X1232667Y605667D01*
X1232000Y605500D01*
X1231417Y605583D01*
X1230833Y605833D01*
X1230500Y606167D01*
G01X1236350Y607750D02*
X1239017D01*
X1238767Y608333D01*
X1238350Y608667D01*
X1237767Y608833D01*
X1237183Y608750D01*
X1236683Y608500D01*
X1236350Y607917D01*
X1236183Y607417D01*
Y606917D01*
X1236350Y606417D01*
X1236767Y605917D01*
X1237267Y605583D01*
X1237850Y605500D01*
X1238433Y605667D01*
X1239017Y606167D01*
G01X1242033Y605500D02*
Y608833D01*
G01Y608167D02*
X1242450Y608500D01*
X1242867Y608750D01*
X1243450Y608833D01*
X1243867Y608750D01*
X1244367Y608500D01*
G01X1253900Y605500D02*
Y609750D01*
X1254067Y610167D01*
X1254400Y610417D01*
X1254900Y610500D01*
X1255400Y610333D01*
X1255650Y609917D01*
G01X1254650Y608500D02*
X1252983D01*
G01X1260000Y605500D02*
X1259500Y605583D01*
X1259000Y605917D01*
X1258667Y606500D01*
X1258500Y607167D01*
X1258667Y607833D01*
X1259000Y608417D01*
X1259500Y608750D01*
X1260000Y608833D01*
X1260500Y608750D01*
X1261000Y608417D01*
X1261333Y607833D01*
X1261417Y607167D01*
X1261333Y606500D01*
X1261000Y605917D01*
X1260500Y605583D01*
X1260000Y605500D01*
G01X1265600D02*
Y610500D01*
G01X1271200Y605500D02*
Y610500D01*
G01X1276800Y605500D02*
X1276300Y605583D01*
X1275800Y605917D01*
X1275467Y606500D01*
X1275300Y607167D01*
X1275467Y607833D01*
X1275800Y608417D01*
X1276300Y608750D01*
X1276800Y608833D01*
X1277300Y608750D01*
X1277800Y608417D01*
X1278133Y607833D01*
X1278217Y607167D01*
X1278133Y606500D01*
X1277800Y605917D01*
X1277300Y605583D01*
X1276800Y605500D01*
G01X1280317Y608833D02*
X1281317Y605500D01*
X1282400Y608833D01*
X1283483Y605500D01*
X1284483Y608833D01*
G01X1288000D02*
Y605500D01*
G01Y610167D02*
X1287833Y610250D01*
Y610417D01*
X1288000Y610500D01*
X1288167Y610417D01*
Y610250D01*
X1288000Y610167D01*
G01X1292183Y605500D02*
Y608833D01*
G01Y608000D02*
X1292517Y608417D01*
X1293017Y608750D01*
X1293683Y608833D01*
X1294267Y608750D01*
X1294767Y608417D01*
X1295017Y607833D01*
Y605500D01*
G01X1298033Y604250D02*
X1298617Y603917D01*
X1299283Y603833D01*
X1299867Y603917D01*
X1300367Y604333D01*
X1300700Y604917D01*
Y608833D01*
G01Y608167D02*
X1300367Y608500D01*
X1299867Y608750D01*
X1299283Y608833D01*
X1298617Y608667D01*
X1298200Y608333D01*
X1297867Y607750D01*
X1297700Y607167D01*
X1297783Y606667D01*
X1298117Y606083D01*
X1298617Y605667D01*
X1299283Y605500D01*
X1299783Y605583D01*
X1300367Y605917D01*
X1300700Y606250D01*
G01X1304800Y605333D02*
X1304633Y605417D01*
Y605583D01*
X1304800Y605667D01*
X1304967Y605583D01*
Y605417D01*
X1304800Y605333D01*
G01Y607583D02*
X1304633Y607667D01*
Y607833D01*
X1304800Y607917D01*
X1304967Y607833D01*
Y607667D01*
X1304800Y607583D01*
G01X1033500Y614500D02*
Y619500D01*
G01Y617000D02*
X1033917Y617500D01*
X1034417Y617750D01*
X1034917Y617833D01*
X1035667Y617667D01*
X1036167Y617333D01*
X1036500Y616750D01*
Y616083D01*
X1036333Y615417D01*
X1036000Y614917D01*
X1035417Y614583D01*
X1034917Y614500D01*
X1034417Y614583D01*
X1033917Y614833D01*
X1033500Y615250D01*
G01X1039350Y616750D02*
X1042017D01*
X1041767Y617333D01*
X1041350Y617667D01*
X1040767Y617833D01*
X1040183Y617750D01*
X1039683Y617500D01*
X1039350Y616917D01*
X1039183Y616417D01*
Y615917D01*
X1039350Y615417D01*
X1039767Y614917D01*
X1040267Y614583D01*
X1040850Y614500D01*
X1041433Y614667D01*
X1042017Y615167D01*
G01X1051300Y614500D02*
Y618750D01*
X1051467Y619167D01*
X1051800Y619417D01*
X1052300Y619500D01*
X1052800Y619333D01*
X1053050Y618917D01*
G01X1052050Y617500D02*
X1050383D01*
G01X1056233Y614500D02*
Y617833D01*
G01Y617167D02*
X1056650Y617500D01*
X1057067Y617750D01*
X1057650Y617833D01*
X1058067Y617750D01*
X1058567Y617500D01*
G01X1061750Y616750D02*
X1064417D01*
X1064167Y617333D01*
X1063750Y617667D01*
X1063167Y617833D01*
X1062583Y617750D01*
X1062083Y617500D01*
X1061750Y616917D01*
X1061583Y616417D01*
Y615917D01*
X1061750Y615417D01*
X1062167Y614917D01*
X1062667Y614583D01*
X1063250Y614500D01*
X1063833Y614667D01*
X1064417Y615167D01*
G01X1067350Y616750D02*
X1070017D01*
X1069767Y617333D01*
X1069350Y617667D01*
X1068767Y617833D01*
X1068183Y617750D01*
X1067683Y617500D01*
X1067350Y616917D01*
X1067183Y616417D01*
Y615917D01*
X1067350Y615417D01*
X1067767Y614917D01*
X1068267Y614583D01*
X1068850Y614500D01*
X1069433Y614667D01*
X1070017Y615167D01*
G01X1079300Y614500D02*
Y618750D01*
X1079467Y619167D01*
X1079800Y619417D01*
X1080300Y619500D01*
X1080800Y619333D01*
X1081050Y618917D01*
G01X1080050Y617500D02*
X1078383D01*
G01X1084233Y614500D02*
Y617833D01*
G01Y617167D02*
X1084650Y617500D01*
X1085067Y617750D01*
X1085650Y617833D01*
X1086067Y617750D01*
X1086567Y617500D01*
G01X1091000Y614500D02*
X1090500Y614583D01*
X1090000Y614917D01*
X1089667Y615500D01*
X1089500Y616167D01*
X1089667Y616833D01*
X1090000Y617417D01*
X1090500Y617750D01*
X1091000Y617833D01*
X1091500Y617750D01*
X1092000Y617417D01*
X1092333Y616833D01*
X1092417Y616167D01*
X1092333Y615500D01*
X1092000Y614917D01*
X1091500Y614583D01*
X1091000Y614500D01*
G01X1094100D02*
Y617833D01*
G01Y616917D02*
X1094350Y617333D01*
X1094767Y617667D01*
X1095350Y617833D01*
X1095933Y617667D01*
X1096350Y617333D01*
X1096600Y616917D01*
Y614500D01*
G01Y616917D02*
X1096850Y617333D01*
X1097267Y617667D01*
X1097850Y617833D01*
X1098433Y617667D01*
X1098850Y617333D01*
X1099100Y616833D01*
Y614500D01*
G01X1106550Y615083D02*
X1106967Y614750D01*
X1107550Y614500D01*
X1108050D01*
X1108550Y614667D01*
X1108883Y614917D01*
X1109050Y615250D01*
X1108967Y615750D01*
X1108633Y616000D01*
X1107133Y616500D01*
X1106800Y617083D01*
X1106967Y617500D01*
X1107300Y617750D01*
X1107800Y617833D01*
X1108300Y617750D01*
X1108800Y617500D01*
G01X1113400Y614500D02*
X1112900Y614583D01*
X1112400Y614917D01*
X1112067Y615500D01*
X1111900Y616167D01*
X1112067Y616833D01*
X1112400Y617417D01*
X1112900Y617750D01*
X1113400Y617833D01*
X1113900Y617750D01*
X1114400Y617417D01*
X1114733Y616833D01*
X1114817Y616167D01*
X1114733Y615500D01*
X1114400Y614917D01*
X1113900Y614583D01*
X1113400Y614500D01*
G01X1119000D02*
Y619500D01*
G01X1126100D02*
Y614500D01*
G01Y615250D02*
X1125767Y614833D01*
X1125267Y614583D01*
X1124683Y614500D01*
X1124017Y614667D01*
X1123517Y615083D01*
X1123183Y615583D01*
X1123100Y616167D01*
X1123183Y616750D01*
X1123517Y617250D01*
X1124017Y617667D01*
X1124683Y617833D01*
X1125267Y617750D01*
X1125683Y617583D01*
X1126100Y617250D01*
G01X1128950Y616750D02*
X1131617D01*
X1131367Y617333D01*
X1130950Y617667D01*
X1130367Y617833D01*
X1129783Y617750D01*
X1129283Y617500D01*
X1128950Y616917D01*
X1128783Y616417D01*
Y615917D01*
X1128950Y615417D01*
X1129367Y614917D01*
X1129867Y614583D01*
X1130450Y614500D01*
X1131033Y614667D01*
X1131617Y615167D01*
G01X1134633Y614500D02*
Y617833D01*
G01Y617167D02*
X1135050Y617500D01*
X1135467Y617750D01*
X1136050Y617833D01*
X1136467Y617750D01*
X1136967Y617500D01*
G01X1144500Y614500D02*
Y617833D01*
G01Y616917D02*
X1144750Y617333D01*
X1145167Y617667D01*
X1145750Y617833D01*
X1146333Y617667D01*
X1146750Y617333D01*
X1147000Y616917D01*
Y614500D01*
G01Y616917D02*
X1147250Y617333D01*
X1147667Y617667D01*
X1148250Y617833D01*
X1148833Y617667D01*
X1149250Y617333D01*
X1149500Y616833D01*
Y614500D01*
G01X1154100D02*
Y617833D01*
G01Y617250D02*
X1153767Y617583D01*
X1153267Y617750D01*
X1152683Y617833D01*
X1152100Y617667D01*
X1151600Y617333D01*
X1151267Y616833D01*
X1151100Y616167D01*
X1151267Y615500D01*
X1151600Y615000D01*
X1152100Y614667D01*
X1152683Y614500D01*
X1153267Y614583D01*
X1153767Y614833D01*
X1154100Y615167D01*
G01X1156950Y615083D02*
X1157367Y614750D01*
X1157950Y614500D01*
X1158450D01*
X1158950Y614667D01*
X1159283Y614917D01*
X1159450Y615250D01*
X1159367Y615750D01*
X1159033Y616000D01*
X1157533Y616500D01*
X1157200Y617083D01*
X1157367Y617500D01*
X1157700Y617750D01*
X1158200Y617833D01*
X1158700Y617750D01*
X1159200Y617500D01*
G01X1162383Y614500D02*
Y619500D01*
G01X1165050Y617833D02*
X1162383Y615917D01*
G01X1163467Y616667D02*
X1165217Y614500D01*
G01X1169400Y614333D02*
X1169233Y614417D01*
Y614583D01*
X1169400Y614667D01*
X1169567Y614583D01*
Y614417D01*
X1169400Y614333D01*
G01X1020417Y627667D02*
X1020917Y628167D01*
X1021500Y628417D01*
X1022167Y628500D01*
X1023000Y628333D01*
X1023583Y627917D01*
X1023750Y627417D01*
X1023667Y626917D01*
X1023333Y626500D01*
X1021667Y625667D01*
X1020917Y625083D01*
X1020417Y624250D01*
X1020250Y623500D01*
X1023750D01*
G01X1027600Y623333D02*
X1027433Y623417D01*
Y623583D01*
X1027600Y623667D01*
X1027767Y623583D01*
Y623417D01*
X1027600Y623333D01*
G01X1033200Y628500D02*
Y623500D01*
G01X1031283Y628500D02*
X1035117D01*
G01X1037383Y623500D02*
Y628500D01*
G01Y626083D02*
X1037800Y626500D01*
X1038217Y626750D01*
X1038883Y626833D01*
X1039383Y626750D01*
X1039967Y626417D01*
X1040217Y625917D01*
Y623500D01*
G01X1043150Y625750D02*
X1045817D01*
X1045567Y626333D01*
X1045150Y626667D01*
X1044567Y626833D01*
X1043983Y626750D01*
X1043483Y626500D01*
X1043150Y625917D01*
X1042983Y625417D01*
Y624917D01*
X1043150Y624417D01*
X1043567Y623917D01*
X1044067Y623583D01*
X1044650Y623500D01*
X1045233Y623667D01*
X1045817Y624167D01*
G01X1054350Y624083D02*
X1054767Y623750D01*
X1055350Y623500D01*
X1055850D01*
X1056350Y623667D01*
X1056683Y623917D01*
X1056850Y624250D01*
X1056767Y624750D01*
X1056433Y625000D01*
X1054933Y625500D01*
X1054600Y626083D01*
X1054767Y626500D01*
X1055100Y626750D01*
X1055600Y626833D01*
X1056100Y626750D01*
X1056600Y626500D01*
G01X1061200Y626833D02*
Y623500D01*
G01Y628167D02*
X1061033Y628250D01*
Y628417D01*
X1061200Y628500D01*
X1061367Y628417D01*
Y628250D01*
X1061200Y628167D01*
G01X1068300Y628500D02*
Y623500D01*
G01Y624250D02*
X1067967Y623833D01*
X1067467Y623583D01*
X1066883Y623500D01*
X1066217Y623667D01*
X1065717Y624083D01*
X1065383Y624583D01*
X1065300Y625167D01*
X1065383Y625750D01*
X1065717Y626250D01*
X1066217Y626667D01*
X1066883Y626833D01*
X1067467Y626750D01*
X1067883Y626583D01*
X1068300Y626250D01*
G01X1071150Y625750D02*
X1073817D01*
X1073567Y626333D01*
X1073150Y626667D01*
X1072567Y626833D01*
X1071983Y626750D01*
X1071483Y626500D01*
X1071150Y625917D01*
X1070983Y625417D01*
Y624917D01*
X1071150Y624417D01*
X1071567Y623917D01*
X1072067Y623583D01*
X1072650Y623500D01*
X1073233Y623667D01*
X1073817Y624167D01*
G01X1081517Y626833D02*
X1082517Y623500D01*
X1083600Y626833D01*
X1084683Y623500D01*
X1085683Y626833D01*
G01X1089200D02*
Y623500D01*
G01Y628167D02*
X1089033Y628250D01*
Y628417D01*
X1089200Y628500D01*
X1089367Y628417D01*
Y628250D01*
X1089200Y628167D01*
G01X1094800Y628500D02*
Y623500D01*
G01X1093633Y626833D02*
X1095967D01*
G01X1098983Y623500D02*
Y628500D01*
G01Y626083D02*
X1099400Y626500D01*
X1099817Y626750D01*
X1100483Y626833D01*
X1100983Y626750D01*
X1101567Y626417D01*
X1101817Y625917D01*
Y623500D01*
G01X1110350Y624083D02*
X1110767Y623750D01*
X1111350Y623500D01*
X1111850D01*
X1112350Y623667D01*
X1112683Y623917D01*
X1112850Y624250D01*
X1112767Y624750D01*
X1112433Y625000D01*
X1110933Y625500D01*
X1110600Y626083D01*
X1110767Y626500D01*
X1111100Y626750D01*
X1111600Y626833D01*
X1112100Y626750D01*
X1112600Y626500D01*
G01X1117200Y623500D02*
X1116700Y623583D01*
X1116200Y623917D01*
X1115867Y624500D01*
X1115700Y625167D01*
X1115867Y625833D01*
X1116200Y626417D01*
X1116700Y626750D01*
X1117200Y626833D01*
X1117700Y626750D01*
X1118200Y626417D01*
X1118533Y625833D01*
X1118617Y625167D01*
X1118533Y624500D01*
X1118200Y623917D01*
X1117700Y623583D01*
X1117200Y623500D01*
G01X1122800D02*
Y628500D01*
G01X1129900D02*
Y623500D01*
G01Y624250D02*
X1129567Y623833D01*
X1129067Y623583D01*
X1128483Y623500D01*
X1127817Y623667D01*
X1127317Y624083D01*
X1126983Y624583D01*
X1126900Y625167D01*
X1126983Y625750D01*
X1127317Y626250D01*
X1127817Y626667D01*
X1128483Y626833D01*
X1129067Y626750D01*
X1129483Y626583D01*
X1129900Y626250D01*
G01X1132750Y625750D02*
X1135417D01*
X1135167Y626333D01*
X1134750Y626667D01*
X1134167Y626833D01*
X1133583Y626750D01*
X1133083Y626500D01*
X1132750Y625917D01*
X1132583Y625417D01*
Y624917D01*
X1132750Y624417D01*
X1133167Y623917D01*
X1133667Y623583D01*
X1134250Y623500D01*
X1134833Y623667D01*
X1135417Y624167D01*
G01X1138433Y623500D02*
Y626833D01*
G01Y626167D02*
X1138850Y626500D01*
X1139267Y626750D01*
X1139850Y626833D01*
X1140267Y626750D01*
X1140767Y626500D01*
G01X1148300Y623500D02*
Y626833D01*
G01Y625917D02*
X1148550Y626333D01*
X1148967Y626667D01*
X1149550Y626833D01*
X1150133Y626667D01*
X1150550Y626333D01*
X1150800Y625917D01*
Y623500D01*
G01Y625917D02*
X1151050Y626333D01*
X1151467Y626667D01*
X1152050Y626833D01*
X1152633Y626667D01*
X1153050Y626333D01*
X1153300Y625833D01*
Y623500D01*
G01X1157900D02*
Y626833D01*
G01Y626250D02*
X1157567Y626583D01*
X1157067Y626750D01*
X1156483Y626833D01*
X1155900Y626667D01*
X1155400Y626333D01*
X1155067Y625833D01*
X1154900Y625167D01*
X1155067Y624500D01*
X1155400Y624000D01*
X1155900Y623667D01*
X1156483Y623500D01*
X1157067Y623583D01*
X1157567Y623833D01*
X1157900Y624167D01*
G01X1160750Y624083D02*
X1161167Y623750D01*
X1161750Y623500D01*
X1162250D01*
X1162750Y623667D01*
X1163083Y623917D01*
X1163250Y624250D01*
X1163167Y624750D01*
X1162833Y625000D01*
X1161333Y625500D01*
X1161000Y626083D01*
X1161167Y626500D01*
X1161500Y626750D01*
X1162000Y626833D01*
X1162500Y626750D01*
X1163000Y626500D01*
G01X1166183Y623500D02*
Y628500D01*
G01X1168850Y626833D02*
X1166183Y624917D01*
G01X1167267Y625667D02*
X1169017Y623500D01*
G01X1177300Y621833D02*
Y626833D01*
G01Y626083D02*
X1177717Y626500D01*
X1178133Y626750D01*
X1178800Y626833D01*
X1179383Y626750D01*
X1179967Y626333D01*
X1180217Y625750D01*
X1180300Y625167D01*
X1180217Y624583D01*
X1179967Y624000D01*
X1179467Y623667D01*
X1178800Y623500D01*
X1178217Y623583D01*
X1177633Y623833D01*
X1177300Y624167D01*
G01X1185900Y623500D02*
Y626833D01*
G01Y626250D02*
X1185567Y626583D01*
X1185067Y626750D01*
X1184483Y626833D01*
X1183900Y626667D01*
X1183400Y626333D01*
X1183067Y625833D01*
X1182900Y625167D01*
X1183067Y624500D01*
X1183400Y624000D01*
X1183900Y623667D01*
X1184483Y623500D01*
X1185067Y623583D01*
X1185567Y623833D01*
X1185900Y624167D01*
G01X1191500Y628500D02*
Y623500D01*
G01Y624250D02*
X1191167Y623833D01*
X1190667Y623583D01*
X1190083Y623500D01*
X1189417Y623667D01*
X1188917Y624083D01*
X1188583Y624583D01*
X1188500Y625167D01*
X1188583Y625750D01*
X1188917Y626250D01*
X1189417Y626667D01*
X1190083Y626833D01*
X1190667Y626750D01*
X1191083Y626583D01*
X1191500Y626250D01*
G01X1195433Y622583D02*
X1195767Y623667D01*
G01X1206800Y628500D02*
Y623500D01*
G01X1205633Y626833D02*
X1207967D01*
G01X1210983Y623500D02*
Y628500D01*
G01Y626083D02*
X1211400Y626500D01*
X1211817Y626750D01*
X1212483Y626833D01*
X1212983Y626750D01*
X1213567Y626417D01*
X1213817Y625917D01*
Y623500D01*
G01X1216750Y625750D02*
X1219417D01*
X1219167Y626333D01*
X1218750Y626667D01*
X1218167Y626833D01*
X1217583Y626750D01*
X1217083Y626500D01*
X1216750Y625917D01*
X1216583Y625417D01*
Y624917D01*
X1216750Y624417D01*
X1217167Y623917D01*
X1217667Y623583D01*
X1218250Y623500D01*
X1218833Y623667D01*
X1219417Y624167D01*
G01X1230700Y623500D02*
Y626833D01*
G01Y626250D02*
X1230367Y626583D01*
X1229867Y626750D01*
X1229283Y626833D01*
X1228700Y626667D01*
X1228200Y626333D01*
X1227867Y625833D01*
X1227700Y625167D01*
X1227867Y624500D01*
X1228200Y624000D01*
X1228700Y623667D01*
X1229283Y623500D01*
X1229867Y623583D01*
X1230367Y623833D01*
X1230700Y624167D01*
G01X1233383Y623500D02*
Y626833D01*
G01Y626000D02*
X1233717Y626417D01*
X1234217Y626750D01*
X1234883Y626833D01*
X1235467Y626750D01*
X1235967Y626417D01*
X1236217Y625833D01*
Y623500D01*
G01X1238983D02*
Y626833D01*
G01Y626000D02*
X1239317Y626417D01*
X1239817Y626750D01*
X1240483Y626833D01*
X1241067Y626750D01*
X1241567Y626417D01*
X1241817Y625833D01*
Y623500D01*
G01X1244583Y626833D02*
Y624500D01*
X1244917Y623917D01*
X1245417Y623583D01*
X1246000Y623500D01*
X1246583Y623583D01*
X1247083Y623917D01*
X1247417Y624500D01*
G01Y623500D02*
Y626833D01*
G01X1253100Y623500D02*
Y626833D01*
G01Y626250D02*
X1252767Y626583D01*
X1252267Y626750D01*
X1251683Y626833D01*
X1251100Y626667D01*
X1250600Y626333D01*
X1250267Y625833D01*
X1250100Y625167D01*
X1250267Y624500D01*
X1250600Y624000D01*
X1251100Y623667D01*
X1251683Y623500D01*
X1252267Y623583D01*
X1252767Y623833D01*
X1253100Y624167D01*
G01X1257200Y623500D02*
Y628500D01*
G01X1267233Y623500D02*
Y626833D01*
G01Y626167D02*
X1267650Y626500D01*
X1268067Y626750D01*
X1268650Y626833D01*
X1269067Y626750D01*
X1269567Y626500D01*
G01X1274000Y626833D02*
Y623500D01*
G01Y628167D02*
X1273833Y628250D01*
Y628417D01*
X1274000Y628500D01*
X1274167Y628417D01*
Y628250D01*
X1274000Y628167D01*
G01X1278183Y623500D02*
Y626833D01*
G01Y626000D02*
X1278517Y626417D01*
X1279017Y626750D01*
X1279683Y626833D01*
X1280267Y626750D01*
X1280767Y626417D01*
X1281017Y625833D01*
Y623500D01*
G01X1284033Y622250D02*
X1284617Y621917D01*
X1285283Y621833D01*
X1285867Y621917D01*
X1286367Y622333D01*
X1286700Y622917D01*
Y626833D01*
G01Y626167D02*
X1286367Y626500D01*
X1285867Y626750D01*
X1285283Y626833D01*
X1284617Y626667D01*
X1284200Y626333D01*
X1283867Y625750D01*
X1283700Y625167D01*
X1283783Y624667D01*
X1284117Y624083D01*
X1284617Y623667D01*
X1285283Y623500D01*
X1285783Y623583D01*
X1286367Y623917D01*
X1286700Y624250D01*
G01X1295150Y624083D02*
X1295567Y623750D01*
X1296150Y623500D01*
X1296650D01*
X1297150Y623667D01*
X1297483Y623917D01*
X1297650Y624250D01*
X1297567Y624750D01*
X1297233Y625000D01*
X1295733Y625500D01*
X1295400Y626083D01*
X1295567Y626500D01*
X1295900Y626750D01*
X1296400Y626833D01*
X1296900Y626750D01*
X1297400Y626500D01*
G01X1300583Y623500D02*
Y628500D01*
G01Y626083D02*
X1301000Y626500D01*
X1301417Y626750D01*
X1302083Y626833D01*
X1302583Y626750D01*
X1303167Y626417D01*
X1303417Y625917D01*
Y623500D01*
G01X1307600D02*
X1307100Y623583D01*
X1306600Y623917D01*
X1306267Y624500D01*
X1306100Y625167D01*
X1306267Y625833D01*
X1306600Y626417D01*
X1307100Y626750D01*
X1307600Y626833D01*
X1308100Y626750D01*
X1308600Y626417D01*
X1308933Y625833D01*
X1309017Y625167D01*
X1308933Y624500D01*
X1308600Y623917D01*
X1308100Y623583D01*
X1307600Y623500D01*
G01X1311783Y626833D02*
Y624500D01*
X1312117Y623917D01*
X1312617Y623583D01*
X1313200Y623500D01*
X1313783Y623583D01*
X1314283Y623917D01*
X1314617Y624500D01*
G01Y623500D02*
Y626833D01*
G01X1318800Y623500D02*
Y628500D01*
G01X1325900D02*
Y623500D01*
G01Y624250D02*
X1325567Y623833D01*
X1325067Y623583D01*
X1324483Y623500D01*
X1323817Y623667D01*
X1323317Y624083D01*
X1322983Y624583D01*
X1322900Y625167D01*
X1322983Y625750D01*
X1323317Y626250D01*
X1323817Y626667D01*
X1324483Y626833D01*
X1325067Y626750D01*
X1325483Y626583D01*
X1325900Y626250D01*
G01X1032500Y637500D02*
Y642500D01*
G01Y640000D02*
X1032917Y640500D01*
X1033417Y640750D01*
X1033917Y640833D01*
X1034667Y640667D01*
X1035167Y640333D01*
X1035500Y639750D01*
Y639083D01*
X1035333Y638417D01*
X1035000Y637917D01*
X1034417Y637583D01*
X1033917Y637500D01*
X1033417Y637583D01*
X1032917Y637833D01*
X1032500Y638250D01*
G01X1038350Y639750D02*
X1041017D01*
X1040767Y640333D01*
X1040350Y640667D01*
X1039767Y640833D01*
X1039183Y640750D01*
X1038683Y640500D01*
X1038350Y639917D01*
X1038183Y639417D01*
Y638917D01*
X1038350Y638417D01*
X1038767Y637917D01*
X1039267Y637583D01*
X1039850Y637500D01*
X1040433Y637667D01*
X1041017Y638167D01*
G01X1050800Y642500D02*
Y637500D01*
G01X1049633Y640833D02*
X1051967D01*
G01X1055150Y639750D02*
X1057817D01*
X1057567Y640333D01*
X1057150Y640667D01*
X1056567Y640833D01*
X1055983Y640750D01*
X1055483Y640500D01*
X1055150Y639917D01*
X1054983Y639417D01*
Y638917D01*
X1055150Y638417D01*
X1055567Y637917D01*
X1056067Y637583D01*
X1056650Y637500D01*
X1057233Y637667D01*
X1057817Y638167D01*
G01X1060583Y637500D02*
Y640833D01*
G01Y640000D02*
X1060917Y640417D01*
X1061417Y640750D01*
X1062083Y640833D01*
X1062667Y640750D01*
X1063167Y640417D01*
X1063417Y639833D01*
Y637500D01*
G01X1067600Y642500D02*
Y637500D01*
G01X1066433Y640833D02*
X1068767D01*
G01X1071950Y639750D02*
X1074617D01*
X1074367Y640333D01*
X1073950Y640667D01*
X1073367Y640833D01*
X1072783Y640750D01*
X1072283Y640500D01*
X1071950Y639917D01*
X1071783Y639417D01*
Y638917D01*
X1071950Y638417D01*
X1072367Y637917D01*
X1072867Y637583D01*
X1073450Y637500D01*
X1074033Y637667D01*
X1074617Y638167D01*
G01X1080300Y642500D02*
Y637500D01*
G01Y638250D02*
X1079967Y637833D01*
X1079467Y637583D01*
X1078883Y637500D01*
X1078217Y637667D01*
X1077717Y638083D01*
X1077383Y638583D01*
X1077300Y639167D01*
X1077383Y639750D01*
X1077717Y640250D01*
X1078217Y640667D01*
X1078883Y640833D01*
X1079467Y640750D01*
X1079883Y640583D01*
X1080300Y640250D01*
G01X1087917Y640833D02*
X1088917Y637500D01*
X1090000Y640833D01*
X1091083Y637500D01*
X1092083Y640833D01*
G01X1095600D02*
Y637500D01*
G01Y642167D02*
X1095433Y642250D01*
Y642417D01*
X1095600Y642500D01*
X1095767Y642417D01*
Y642250D01*
X1095600Y642167D01*
G01X1101200Y642500D02*
Y637500D01*
G01X1100033Y640833D02*
X1102367D01*
G01X1105383Y637500D02*
Y642500D01*
G01Y640083D02*
X1105800Y640500D01*
X1106217Y640750D01*
X1106883Y640833D01*
X1107383Y640750D01*
X1107967Y640417D01*
X1108217Y639917D01*
Y637500D01*
G01X1116750Y638083D02*
X1117167Y637750D01*
X1117750Y637500D01*
X1118250D01*
X1118750Y637667D01*
X1119083Y637917D01*
X1119250Y638250D01*
X1119167Y638750D01*
X1118833Y639000D01*
X1117333Y639500D01*
X1117000Y640083D01*
X1117167Y640500D01*
X1117500Y640750D01*
X1118000Y640833D01*
X1118500Y640750D01*
X1119000Y640500D01*
G01X1123600Y637500D02*
X1123100Y637583D01*
X1122600Y637917D01*
X1122267Y638500D01*
X1122100Y639167D01*
X1122267Y639833D01*
X1122600Y640417D01*
X1123100Y640750D01*
X1123600Y640833D01*
X1124100Y640750D01*
X1124600Y640417D01*
X1124933Y639833D01*
X1125017Y639167D01*
X1124933Y638500D01*
X1124600Y637917D01*
X1124100Y637583D01*
X1123600Y637500D01*
G01X1129200D02*
Y642500D01*
G01X1136300D02*
Y637500D01*
G01Y638250D02*
X1135967Y637833D01*
X1135467Y637583D01*
X1134883Y637500D01*
X1134217Y637667D01*
X1133717Y638083D01*
X1133383Y638583D01*
X1133300Y639167D01*
X1133383Y639750D01*
X1133717Y640250D01*
X1134217Y640667D01*
X1134883Y640833D01*
X1135467Y640750D01*
X1135883Y640583D01*
X1136300Y640250D01*
G01X1139150Y639750D02*
X1141817D01*
X1141567Y640333D01*
X1141150Y640667D01*
X1140567Y640833D01*
X1139983Y640750D01*
X1139483Y640500D01*
X1139150Y639917D01*
X1138983Y639417D01*
Y638917D01*
X1139150Y638417D01*
X1139567Y637917D01*
X1140067Y637583D01*
X1140650Y637500D01*
X1141233Y637667D01*
X1141817Y638167D01*
G01X1144833Y637500D02*
Y640833D01*
G01Y640167D02*
X1145250Y640500D01*
X1145667Y640750D01*
X1146250Y640833D01*
X1146667Y640750D01*
X1147167Y640500D01*
G01X1154700Y637500D02*
Y640833D01*
G01Y639917D02*
X1154950Y640333D01*
X1155367Y640667D01*
X1155950Y640833D01*
X1156533Y640667D01*
X1156950Y640333D01*
X1157200Y639917D01*
Y637500D01*
G01Y639917D02*
X1157450Y640333D01*
X1157867Y640667D01*
X1158450Y640833D01*
X1159033Y640667D01*
X1159450Y640333D01*
X1159700Y639833D01*
Y637500D01*
G01X1164300D02*
Y640833D01*
G01Y640250D02*
X1163967Y640583D01*
X1163467Y640750D01*
X1162883Y640833D01*
X1162300Y640667D01*
X1161800Y640333D01*
X1161467Y639833D01*
X1161300Y639167D01*
X1161467Y638500D01*
X1161800Y638000D01*
X1162300Y637667D01*
X1162883Y637500D01*
X1163467Y637583D01*
X1163967Y637833D01*
X1164300Y638167D01*
G01X1167150Y638083D02*
X1167567Y637750D01*
X1168150Y637500D01*
X1168650D01*
X1169150Y637667D01*
X1169483Y637917D01*
X1169650Y638250D01*
X1169567Y638750D01*
X1169233Y639000D01*
X1167733Y639500D01*
X1167400Y640083D01*
X1167567Y640500D01*
X1167900Y640750D01*
X1168400Y640833D01*
X1168900Y640750D01*
X1169400Y640500D01*
G01X1172583Y637500D02*
Y642500D01*
G01X1175250Y640833D02*
X1172583Y638917D01*
G01X1173667Y639667D02*
X1175417Y637500D01*
G01X1179600Y637333D02*
X1179433Y637417D01*
Y637583D01*
X1179600Y637667D01*
X1179767Y637583D01*
Y637417D01*
X1179600Y637333D01*
G01X1034000Y651500D02*
Y646500D01*
G01X1032833Y649833D02*
X1035167D01*
G01X1039600Y646500D02*
X1039100Y646583D01*
X1038600Y646917D01*
X1038267Y647500D01*
X1038100Y648167D01*
X1038267Y648833D01*
X1038600Y649417D01*
X1039100Y649750D01*
X1039600Y649833D01*
X1040100Y649750D01*
X1040600Y649417D01*
X1040933Y648833D01*
X1041017Y648167D01*
X1040933Y647500D01*
X1040600Y646917D01*
X1040100Y646583D01*
X1039600Y646500D01*
G01X1049300D02*
Y651500D01*
G01Y649000D02*
X1049717Y649500D01*
X1050217Y649750D01*
X1050717Y649833D01*
X1051467Y649667D01*
X1051967Y649333D01*
X1052300Y648750D01*
Y648083D01*
X1052133Y647417D01*
X1051800Y646917D01*
X1051217Y646583D01*
X1050717Y646500D01*
X1050217Y646583D01*
X1049717Y646833D01*
X1049300Y647250D01*
G01X1055150Y648750D02*
X1057817D01*
X1057567Y649333D01*
X1057150Y649667D01*
X1056567Y649833D01*
X1055983Y649750D01*
X1055483Y649500D01*
X1055150Y648917D01*
X1054983Y648417D01*
Y647917D01*
X1055150Y647417D01*
X1055567Y646917D01*
X1056067Y646583D01*
X1056650Y646500D01*
X1057233Y646667D01*
X1057817Y647167D01*
G01X1068933Y649417D02*
X1068350Y649750D01*
X1067850Y649833D01*
X1067183Y649667D01*
X1066683Y649333D01*
X1066350Y648750D01*
X1066267Y648167D01*
X1066350Y647583D01*
X1066683Y647083D01*
X1067183Y646667D01*
X1067850Y646500D01*
X1068433Y646667D01*
X1068933Y647000D01*
G01X1073200Y646500D02*
X1072700Y646583D01*
X1072200Y646917D01*
X1071867Y647500D01*
X1071700Y648167D01*
X1071867Y648833D01*
X1072200Y649417D01*
X1072700Y649750D01*
X1073200Y649833D01*
X1073700Y649750D01*
X1074200Y649417D01*
X1074533Y648833D01*
X1074617Y648167D01*
X1074533Y647500D01*
X1074200Y646917D01*
X1073700Y646583D01*
X1073200Y646500D01*
G01X1077300Y649833D02*
X1078800Y646500D01*
X1080300Y649833D01*
G01X1083150Y648750D02*
X1085817D01*
X1085567Y649333D01*
X1085150Y649667D01*
X1084567Y649833D01*
X1083983Y649750D01*
X1083483Y649500D01*
X1083150Y648917D01*
X1082983Y648417D01*
Y647917D01*
X1083150Y647417D01*
X1083567Y646917D01*
X1084067Y646583D01*
X1084650Y646500D01*
X1085233Y646667D01*
X1085817Y647167D01*
G01X1088833Y646500D02*
Y649833D01*
G01Y649167D02*
X1089250Y649500D01*
X1089667Y649750D01*
X1090250Y649833D01*
X1090667Y649750D01*
X1091167Y649500D01*
G01X1094350Y648750D02*
X1097017D01*
X1096767Y649333D01*
X1096350Y649667D01*
X1095767Y649833D01*
X1095183Y649750D01*
X1094683Y649500D01*
X1094350Y648917D01*
X1094183Y648417D01*
Y647917D01*
X1094350Y647417D01*
X1094767Y646917D01*
X1095267Y646583D01*
X1095850Y646500D01*
X1096433Y646667D01*
X1097017Y647167D01*
G01X1102700Y651500D02*
Y646500D01*
G01Y647250D02*
X1102367Y646833D01*
X1101867Y646583D01*
X1101283Y646500D01*
X1100617Y646667D01*
X1100117Y647083D01*
X1099783Y647583D01*
X1099700Y648167D01*
X1099783Y648750D01*
X1100117Y649250D01*
X1100617Y649667D01*
X1101283Y649833D01*
X1101867Y649750D01*
X1102283Y649583D01*
X1102700Y649250D01*
G01X1110900Y646500D02*
Y651500D01*
G01Y649000D02*
X1111317Y649500D01*
X1111817Y649750D01*
X1112317Y649833D01*
X1113067Y649667D01*
X1113567Y649333D01*
X1113900Y648750D01*
Y648083D01*
X1113733Y647417D01*
X1113400Y646917D01*
X1112817Y646583D01*
X1112317Y646500D01*
X1111817Y646583D01*
X1111317Y646833D01*
X1110900Y647250D01*
G01X1116250Y645000D02*
X1116750Y644833D01*
X1117417Y645000D01*
X1117833Y645333D01*
X1118167Y645750D01*
X1118667Y647083D01*
X1119750Y649833D01*
G01X1117083D02*
X1118667Y647083D01*
G01X1127950D02*
X1128367Y646750D01*
X1128950Y646500D01*
X1129450D01*
X1129950Y646667D01*
X1130283Y646917D01*
X1130450Y647250D01*
X1130367Y647750D01*
X1130033Y648000D01*
X1128533Y648500D01*
X1128200Y649083D01*
X1128367Y649500D01*
X1128700Y649750D01*
X1129200Y649833D01*
X1129700Y649750D01*
X1130200Y649500D01*
G01X1134800Y646500D02*
X1134300Y646583D01*
X1133800Y646917D01*
X1133467Y647500D01*
X1133300Y648167D01*
X1133467Y648833D01*
X1133800Y649417D01*
X1134300Y649750D01*
X1134800Y649833D01*
X1135300Y649750D01*
X1135800Y649417D01*
X1136133Y648833D01*
X1136217Y648167D01*
X1136133Y647500D01*
X1135800Y646917D01*
X1135300Y646583D01*
X1134800Y646500D01*
G01X1140400D02*
Y651500D01*
G01X1147500D02*
Y646500D01*
G01Y647250D02*
X1147167Y646833D01*
X1146667Y646583D01*
X1146083Y646500D01*
X1145417Y646667D01*
X1144917Y647083D01*
X1144583Y647583D01*
X1144500Y648167D01*
X1144583Y648750D01*
X1144917Y649250D01*
X1145417Y649667D01*
X1146083Y649833D01*
X1146667Y649750D01*
X1147083Y649583D01*
X1147500Y649250D01*
G01X1150350Y648750D02*
X1153017D01*
X1152767Y649333D01*
X1152350Y649667D01*
X1151767Y649833D01*
X1151183Y649750D01*
X1150683Y649500D01*
X1150350Y648917D01*
X1150183Y648417D01*
Y647917D01*
X1150350Y647417D01*
X1150767Y646917D01*
X1151267Y646583D01*
X1151850Y646500D01*
X1152433Y646667D01*
X1153017Y647167D01*
G01X1156033Y646500D02*
Y649833D01*
G01Y649167D02*
X1156450Y649500D01*
X1156867Y649750D01*
X1157450Y649833D01*
X1157867Y649750D01*
X1158367Y649500D01*
G01X1165900Y646500D02*
Y649833D01*
G01Y648917D02*
X1166150Y649333D01*
X1166567Y649667D01*
X1167150Y649833D01*
X1167733Y649667D01*
X1168150Y649333D01*
X1168400Y648917D01*
Y646500D01*
G01Y648917D02*
X1168650Y649333D01*
X1169067Y649667D01*
X1169650Y649833D01*
X1170233Y649667D01*
X1170650Y649333D01*
X1170900Y648833D01*
Y646500D01*
G01X1175500D02*
Y649833D01*
G01Y649250D02*
X1175167Y649583D01*
X1174667Y649750D01*
X1174083Y649833D01*
X1173500Y649667D01*
X1173000Y649333D01*
X1172667Y648833D01*
X1172500Y648167D01*
X1172667Y647500D01*
X1173000Y647000D01*
X1173500Y646667D01*
X1174083Y646500D01*
X1174667Y646583D01*
X1175167Y646833D01*
X1175500Y647167D01*
G01X1178350Y647083D02*
X1178767Y646750D01*
X1179350Y646500D01*
X1179850D01*
X1180350Y646667D01*
X1180683Y646917D01*
X1180850Y647250D01*
X1180767Y647750D01*
X1180433Y648000D01*
X1178933Y648500D01*
X1178600Y649083D01*
X1178767Y649500D01*
X1179100Y649750D01*
X1179600Y649833D01*
X1180100Y649750D01*
X1180600Y649500D01*
G01X1183783Y646500D02*
Y651500D01*
G01X1186450Y649833D02*
X1183783Y647917D01*
G01X1184867Y648667D02*
X1186617Y646500D01*
G01X1197900D02*
Y649833D01*
G01Y649250D02*
X1197567Y649583D01*
X1197067Y649750D01*
X1196483Y649833D01*
X1195900Y649667D01*
X1195400Y649333D01*
X1195067Y648833D01*
X1194900Y648167D01*
X1195067Y647500D01*
X1195400Y647000D01*
X1195900Y646667D01*
X1196483Y646500D01*
X1197067Y646583D01*
X1197567Y646833D01*
X1197900Y647167D01*
G01X1200583Y646500D02*
Y649833D01*
G01Y649000D02*
X1200917Y649417D01*
X1201417Y649750D01*
X1202083Y649833D01*
X1202667Y649750D01*
X1203167Y649417D01*
X1203417Y648833D01*
Y646500D01*
G01X1209100Y651500D02*
Y646500D01*
G01Y647250D02*
X1208767Y646833D01*
X1208267Y646583D01*
X1207683Y646500D01*
X1207017Y646667D01*
X1206517Y647083D01*
X1206183Y647583D01*
X1206100Y648167D01*
X1206183Y648750D01*
X1206517Y649250D01*
X1207017Y649667D01*
X1207683Y649833D01*
X1208267Y649750D01*
X1208683Y649583D01*
X1209100Y649250D01*
G01X1217383Y646500D02*
Y651500D01*
G01Y649083D02*
X1217800Y649500D01*
X1218217Y649750D01*
X1218883Y649833D01*
X1219383Y649750D01*
X1219967Y649417D01*
X1220217Y648917D01*
Y646500D01*
G01X1224400D02*
X1223900Y646583D01*
X1223400Y646917D01*
X1223067Y647500D01*
X1222900Y648167D01*
X1223067Y648833D01*
X1223400Y649417D01*
X1223900Y649750D01*
X1224400Y649833D01*
X1224900Y649750D01*
X1225400Y649417D01*
X1225733Y648833D01*
X1225817Y648167D01*
X1225733Y647500D01*
X1225400Y646917D01*
X1224900Y646583D01*
X1224400Y646500D01*
G01X1230000D02*
Y651500D01*
G01X1234350Y648750D02*
X1237017D01*
X1236767Y649333D01*
X1236350Y649667D01*
X1235767Y649833D01*
X1235183Y649750D01*
X1234683Y649500D01*
X1234350Y648917D01*
X1234183Y648417D01*
Y647917D01*
X1234350Y647417D01*
X1234767Y646917D01*
X1235267Y646583D01*
X1235850Y646500D01*
X1236433Y646667D01*
X1237017Y647167D01*
G01X1248300Y646500D02*
Y649833D01*
G01Y649250D02*
X1247967Y649583D01*
X1247467Y649750D01*
X1246883Y649833D01*
X1246300Y649667D01*
X1245800Y649333D01*
X1245467Y648833D01*
X1245300Y648167D01*
X1245467Y647500D01*
X1245800Y647000D01*
X1246300Y646667D01*
X1246883Y646500D01*
X1247467Y646583D01*
X1247967Y646833D01*
X1248300Y647167D01*
G01X1252400Y646500D02*
Y651500D01*
G01X1256750Y647083D02*
X1257167Y646750D01*
X1257750Y646500D01*
X1258250D01*
X1258750Y646667D01*
X1259083Y646917D01*
X1259250Y647250D01*
X1259167Y647750D01*
X1258833Y648000D01*
X1257333Y648500D01*
X1257000Y649083D01*
X1257167Y649500D01*
X1257500Y649750D01*
X1258000Y649833D01*
X1258500Y649750D01*
X1259000Y649500D01*
G01X1263600Y646500D02*
X1263100Y646583D01*
X1262600Y646917D01*
X1262267Y647500D01*
X1262100Y648167D01*
X1262267Y648833D01*
X1262600Y649417D01*
X1263100Y649750D01*
X1263600Y649833D01*
X1264100Y649750D01*
X1264600Y649417D01*
X1264933Y648833D01*
X1265017Y648167D01*
X1264933Y647500D01*
X1264600Y646917D01*
X1264100Y646583D01*
X1263600Y646500D01*
G01X1273383D02*
Y649833D01*
G01Y649000D02*
X1273717Y649417D01*
X1274217Y649750D01*
X1274883Y649833D01*
X1275467Y649750D01*
X1275967Y649417D01*
X1276217Y648833D01*
Y646500D01*
G01X1279150Y648750D02*
X1281817D01*
X1281567Y649333D01*
X1281150Y649667D01*
X1280567Y649833D01*
X1279983Y649750D01*
X1279483Y649500D01*
X1279150Y648917D01*
X1278983Y648417D01*
Y647917D01*
X1279150Y647417D01*
X1279567Y646917D01*
X1280067Y646583D01*
X1280650Y646500D01*
X1281233Y646667D01*
X1281817Y647167D01*
G01X1284750Y648750D02*
X1287417D01*
X1287167Y649333D01*
X1286750Y649667D01*
X1286167Y649833D01*
X1285583Y649750D01*
X1285083Y649500D01*
X1284750Y648917D01*
X1284583Y648417D01*
Y647917D01*
X1284750Y647417D01*
X1285167Y646917D01*
X1285667Y646583D01*
X1286250Y646500D01*
X1286833Y646667D01*
X1287417Y647167D01*
G01X1293100Y651500D02*
Y646500D01*
G01Y647250D02*
X1292767Y646833D01*
X1292267Y646583D01*
X1291683Y646500D01*
X1291017Y646667D01*
X1290517Y647083D01*
X1290183Y647583D01*
X1290100Y648167D01*
X1290183Y648750D01*
X1290517Y649250D01*
X1291017Y649667D01*
X1291683Y649833D01*
X1292267Y649750D01*
X1292683Y649583D01*
X1293100Y649250D01*
G01X1302800Y651500D02*
Y646500D01*
G01X1301633Y649833D02*
X1303967D01*
G01X1308400Y646500D02*
X1307900Y646583D01*
X1307400Y646917D01*
X1307067Y647500D01*
X1306900Y648167D01*
X1307067Y648833D01*
X1307400Y649417D01*
X1307900Y649750D01*
X1308400Y649833D01*
X1308900Y649750D01*
X1309400Y649417D01*
X1309733Y648833D01*
X1309817Y648167D01*
X1309733Y647500D01*
X1309400Y646917D01*
X1308900Y646583D01*
X1308400Y646500D01*
G01X1022000Y654500D02*
Y659500D01*
X1021000Y658500D01*
G01Y654500D02*
X1023000D01*
G01X1027600Y654333D02*
X1027433Y654417D01*
Y654583D01*
X1027600Y654667D01*
X1027767Y654583D01*
Y654417D01*
X1027600Y654333D01*
G01X1033200Y659500D02*
Y654500D01*
G01X1031283Y659500D02*
X1035117D01*
G01X1037383Y654500D02*
Y659500D01*
G01Y657083D02*
X1037800Y657500D01*
X1038217Y657750D01*
X1038883Y657833D01*
X1039383Y657750D01*
X1039967Y657417D01*
X1040217Y656917D01*
Y654500D01*
G01X1043150Y656750D02*
X1045817D01*
X1045567Y657333D01*
X1045150Y657667D01*
X1044567Y657833D01*
X1043983Y657750D01*
X1043483Y657500D01*
X1043150Y656917D01*
X1042983Y656417D01*
Y655917D01*
X1043150Y655417D01*
X1043567Y654917D01*
X1044067Y654583D01*
X1044650Y654500D01*
X1045233Y654667D01*
X1045817Y655167D01*
G01X1054350Y655083D02*
X1054767Y654750D01*
X1055350Y654500D01*
X1055850D01*
X1056350Y654667D01*
X1056683Y654917D01*
X1056850Y655250D01*
X1056767Y655750D01*
X1056433Y656000D01*
X1054933Y656500D01*
X1054600Y657083D01*
X1054767Y657500D01*
X1055100Y657750D01*
X1055600Y657833D01*
X1056100Y657750D01*
X1056600Y657500D01*
G01X1061200Y657833D02*
Y654500D01*
G01Y659167D02*
X1061033Y659250D01*
Y659417D01*
X1061200Y659500D01*
X1061367Y659417D01*
Y659250D01*
X1061200Y659167D01*
G01X1068300Y659500D02*
Y654500D01*
G01Y655250D02*
X1067967Y654833D01*
X1067467Y654583D01*
X1066883Y654500D01*
X1066217Y654667D01*
X1065717Y655083D01*
X1065383Y655583D01*
X1065300Y656167D01*
X1065383Y656750D01*
X1065717Y657250D01*
X1066217Y657667D01*
X1066883Y657833D01*
X1067467Y657750D01*
X1067883Y657583D01*
X1068300Y657250D01*
G01X1071150Y656750D02*
X1073817D01*
X1073567Y657333D01*
X1073150Y657667D01*
X1072567Y657833D01*
X1071983Y657750D01*
X1071483Y657500D01*
X1071150Y656917D01*
X1070983Y656417D01*
Y655917D01*
X1071150Y655417D01*
X1071567Y654917D01*
X1072067Y654583D01*
X1072650Y654500D01*
X1073233Y654667D01*
X1073817Y655167D01*
G01X1081517Y657833D02*
X1082517Y654500D01*
X1083600Y657833D01*
X1084683Y654500D01*
X1085683Y657833D01*
G01X1089200D02*
Y654500D01*
G01Y659167D02*
X1089033Y659250D01*
Y659417D01*
X1089200Y659500D01*
X1089367Y659417D01*
Y659250D01*
X1089200Y659167D01*
G01X1094800Y659500D02*
Y654500D01*
G01X1093633Y657833D02*
X1095967D01*
G01X1098983Y654500D02*
Y659500D01*
G01Y657083D02*
X1099400Y657500D01*
X1099817Y657750D01*
X1100483Y657833D01*
X1100983Y657750D01*
X1101567Y657417D01*
X1101817Y656917D01*
Y654500D01*
G01X1106000D02*
X1105500Y654583D01*
X1105000Y654917D01*
X1104667Y655500D01*
X1104500Y656167D01*
X1104667Y656833D01*
X1105000Y657417D01*
X1105500Y657750D01*
X1106000Y657833D01*
X1106500Y657750D01*
X1107000Y657417D01*
X1107333Y656833D01*
X1107417Y656167D01*
X1107333Y655500D01*
X1107000Y654917D01*
X1106500Y654583D01*
X1106000Y654500D01*
G01X1110183Y657833D02*
Y655500D01*
X1110517Y654917D01*
X1111017Y654583D01*
X1111600Y654500D01*
X1112183Y654583D01*
X1112683Y654917D01*
X1113017Y655500D01*
G01Y654500D02*
Y657833D01*
G01X1117200Y659500D02*
Y654500D01*
G01X1116033Y657833D02*
X1118367D01*
G01X1127150Y655083D02*
X1127567Y654750D01*
X1128150Y654500D01*
X1128650D01*
X1129150Y654667D01*
X1129483Y654917D01*
X1129650Y655250D01*
X1129567Y655750D01*
X1129233Y656000D01*
X1127733Y656500D01*
X1127400Y657083D01*
X1127567Y657500D01*
X1127900Y657750D01*
X1128400Y657833D01*
X1128900Y657750D01*
X1129400Y657500D01*
G01X1134000Y654500D02*
X1133500Y654583D01*
X1133000Y654917D01*
X1132667Y655500D01*
X1132500Y656167D01*
X1132667Y656833D01*
X1133000Y657417D01*
X1133500Y657750D01*
X1134000Y657833D01*
X1134500Y657750D01*
X1135000Y657417D01*
X1135333Y656833D01*
X1135417Y656167D01*
X1135333Y655500D01*
X1135000Y654917D01*
X1134500Y654583D01*
X1134000Y654500D01*
G01X1139600D02*
Y659500D01*
G01X1146700D02*
Y654500D01*
G01Y655250D02*
X1146367Y654833D01*
X1145867Y654583D01*
X1145283Y654500D01*
X1144617Y654667D01*
X1144117Y655083D01*
X1143783Y655583D01*
X1143700Y656167D01*
X1143783Y656750D01*
X1144117Y657250D01*
X1144617Y657667D01*
X1145283Y657833D01*
X1145867Y657750D01*
X1146283Y657583D01*
X1146700Y657250D01*
G01X1149550Y656750D02*
X1152217D01*
X1151967Y657333D01*
X1151550Y657667D01*
X1150967Y657833D01*
X1150383Y657750D01*
X1149883Y657500D01*
X1149550Y656917D01*
X1149383Y656417D01*
Y655917D01*
X1149550Y655417D01*
X1149967Y654917D01*
X1150467Y654583D01*
X1151050Y654500D01*
X1151633Y654667D01*
X1152217Y655167D01*
G01X1155233Y654500D02*
Y657833D01*
G01Y657167D02*
X1155650Y657500D01*
X1156067Y657750D01*
X1156650Y657833D01*
X1157067Y657750D01*
X1157567Y657500D01*
G01X1165100Y654500D02*
Y657833D01*
G01Y656917D02*
X1165350Y657333D01*
X1165767Y657667D01*
X1166350Y657833D01*
X1166933Y657667D01*
X1167350Y657333D01*
X1167600Y656917D01*
Y654500D01*
G01Y656917D02*
X1167850Y657333D01*
X1168267Y657667D01*
X1168850Y657833D01*
X1169433Y657667D01*
X1169850Y657333D01*
X1170100Y656833D01*
Y654500D01*
G01X1174700D02*
Y657833D01*
G01Y657250D02*
X1174367Y657583D01*
X1173867Y657750D01*
X1173283Y657833D01*
X1172700Y657667D01*
X1172200Y657333D01*
X1171867Y656833D01*
X1171700Y656167D01*
X1171867Y655500D01*
X1172200Y655000D01*
X1172700Y654667D01*
X1173283Y654500D01*
X1173867Y654583D01*
X1174367Y654833D01*
X1174700Y655167D01*
G01X1177550Y655083D02*
X1177967Y654750D01*
X1178550Y654500D01*
X1179050D01*
X1179550Y654667D01*
X1179883Y654917D01*
X1180050Y655250D01*
X1179967Y655750D01*
X1179633Y656000D01*
X1178133Y656500D01*
X1177800Y657083D01*
X1177967Y657500D01*
X1178300Y657750D01*
X1178800Y657833D01*
X1179300Y657750D01*
X1179800Y657500D01*
G01X1182983Y654500D02*
Y659500D01*
G01X1185650Y657833D02*
X1182983Y655917D01*
G01X1184067Y656667D02*
X1185817Y654500D01*
G01X1194100Y652833D02*
Y657833D01*
G01Y657083D02*
X1194517Y657500D01*
X1194933Y657750D01*
X1195600Y657833D01*
X1196183Y657750D01*
X1196767Y657333D01*
X1197017Y656750D01*
X1197100Y656167D01*
X1197017Y655583D01*
X1196767Y655000D01*
X1196267Y654667D01*
X1195600Y654500D01*
X1195017Y654583D01*
X1194433Y654833D01*
X1194100Y655167D01*
G01X1202700Y654500D02*
Y657833D01*
G01Y657250D02*
X1202367Y657583D01*
X1201867Y657750D01*
X1201283Y657833D01*
X1200700Y657667D01*
X1200200Y657333D01*
X1199867Y656833D01*
X1199700Y656167D01*
X1199867Y655500D01*
X1200200Y655000D01*
X1200700Y654667D01*
X1201283Y654500D01*
X1201867Y654583D01*
X1202367Y654833D01*
X1202700Y655167D01*
G01X1208300Y659500D02*
Y654500D01*
G01Y655250D02*
X1207967Y654833D01*
X1207467Y654583D01*
X1206883Y654500D01*
X1206217Y654667D01*
X1205717Y655083D01*
X1205383Y655583D01*
X1205300Y656167D01*
X1205383Y656750D01*
X1205717Y657250D01*
X1206217Y657667D01*
X1206883Y657833D01*
X1207467Y657750D01*
X1207883Y657583D01*
X1208300Y657250D01*
G01X1217833Y653583D02*
X1218167Y654667D01*
G01X1230700Y654500D02*
Y657833D01*
G01Y657250D02*
X1230367Y657583D01*
X1229867Y657750D01*
X1229283Y657833D01*
X1228700Y657667D01*
X1228200Y657333D01*
X1227867Y656833D01*
X1227700Y656167D01*
X1227867Y655500D01*
X1228200Y655000D01*
X1228700Y654667D01*
X1229283Y654500D01*
X1229867Y654583D01*
X1230367Y654833D01*
X1230700Y655167D01*
G01X1233383Y654500D02*
Y657833D01*
G01Y657000D02*
X1233717Y657417D01*
X1234217Y657750D01*
X1234883Y657833D01*
X1235467Y657750D01*
X1235967Y657417D01*
X1236217Y656833D01*
Y654500D01*
G01X1238983D02*
Y657833D01*
G01Y657000D02*
X1239317Y657417D01*
X1239817Y657750D01*
X1240483Y657833D01*
X1241067Y657750D01*
X1241567Y657417D01*
X1241817Y656833D01*
Y654500D01*
G01X1244583Y657833D02*
Y655500D01*
X1244917Y654917D01*
X1245417Y654583D01*
X1246000Y654500D01*
X1246583Y654583D01*
X1247083Y654917D01*
X1247417Y655500D01*
G01Y654500D02*
Y657833D01*
G01X1253100Y654500D02*
Y657833D01*
G01Y657250D02*
X1252767Y657583D01*
X1252267Y657750D01*
X1251683Y657833D01*
X1251100Y657667D01*
X1250600Y657333D01*
X1250267Y656833D01*
X1250100Y656167D01*
X1250267Y655500D01*
X1250600Y655000D01*
X1251100Y654667D01*
X1251683Y654500D01*
X1252267Y654583D01*
X1252767Y654833D01*
X1253100Y655167D01*
G01X1257200Y654500D02*
Y659500D01*
G01X1267233Y654500D02*
Y657833D01*
G01Y657167D02*
X1267650Y657500D01*
X1268067Y657750D01*
X1268650Y657833D01*
X1269067Y657750D01*
X1269567Y657500D01*
G01X1274000Y657833D02*
Y654500D01*
G01Y659167D02*
X1273833Y659250D01*
Y659417D01*
X1274000Y659500D01*
X1274167Y659417D01*
Y659250D01*
X1274000Y659167D01*
G01X1278183Y654500D02*
Y657833D01*
G01Y657000D02*
X1278517Y657417D01*
X1279017Y657750D01*
X1279683Y657833D01*
X1280267Y657750D01*
X1280767Y657417D01*
X1281017Y656833D01*
Y654500D01*
G01X1284033Y653250D02*
X1284617Y652917D01*
X1285283Y652833D01*
X1285867Y652917D01*
X1286367Y653333D01*
X1286700Y653917D01*
Y657833D01*
G01Y657167D02*
X1286367Y657500D01*
X1285867Y657750D01*
X1285283Y657833D01*
X1284617Y657667D01*
X1284200Y657333D01*
X1283867Y656750D01*
X1283700Y656167D01*
X1283783Y655667D01*
X1284117Y655083D01*
X1284617Y654667D01*
X1285283Y654500D01*
X1285783Y654583D01*
X1286367Y654917D01*
X1286700Y655250D01*
G01X1294983Y654500D02*
Y657833D01*
G01Y657000D02*
X1295317Y657417D01*
X1295817Y657750D01*
X1296483Y657833D01*
X1297067Y657750D01*
X1297567Y657417D01*
X1297817Y656833D01*
Y654500D01*
G01X1300750Y656750D02*
X1303417D01*
X1303167Y657333D01*
X1302750Y657667D01*
X1302167Y657833D01*
X1301583Y657750D01*
X1301083Y657500D01*
X1300750Y656917D01*
X1300583Y656417D01*
Y655917D01*
X1300750Y655417D01*
X1301167Y654917D01*
X1301667Y654583D01*
X1302250Y654500D01*
X1302833Y654667D01*
X1303417Y655167D01*
G01X1306350Y656750D02*
X1309017D01*
X1308767Y657333D01*
X1308350Y657667D01*
X1307767Y657833D01*
X1307183Y657750D01*
X1306683Y657500D01*
X1306350Y656917D01*
X1306183Y656417D01*
Y655917D01*
X1306350Y655417D01*
X1306767Y654917D01*
X1307267Y654583D01*
X1307850Y654500D01*
X1308433Y654667D01*
X1309017Y655167D01*
G01X1314700Y659500D02*
Y654500D01*
G01Y655250D02*
X1314367Y654833D01*
X1313867Y654583D01*
X1313283Y654500D01*
X1312617Y654667D01*
X1312117Y655083D01*
X1311783Y655583D01*
X1311700Y656167D01*
X1311783Y656750D01*
X1312117Y657250D01*
X1312617Y657667D01*
X1313283Y657833D01*
X1313867Y657750D01*
X1314283Y657583D01*
X1314700Y657250D01*
G01X1012083Y800500D02*
Y803833D01*
G01Y803000D02*
X1012417Y803417D01*
X1012917Y803750D01*
X1013583Y803833D01*
X1014167Y803750D01*
X1014667Y803417D01*
X1014917Y802833D01*
Y800500D01*
G01X1019100D02*
X1018600Y800583D01*
X1018100Y800917D01*
X1017767Y801500D01*
X1017600Y802167D01*
X1017767Y802833D01*
X1018100Y803417D01*
X1018600Y803750D01*
X1019100Y803833D01*
X1019600Y803750D01*
X1020100Y803417D01*
X1020433Y802833D01*
X1020517Y802167D01*
X1020433Y801500D01*
X1020100Y800917D01*
X1019600Y800583D01*
X1019100Y800500D01*
G01X1028800Y798833D02*
Y803833D01*
G01Y803083D02*
X1029217Y803500D01*
X1029633Y803750D01*
X1030300Y803833D01*
X1030883Y803750D01*
X1031467Y803333D01*
X1031717Y802750D01*
X1031800Y802167D01*
X1031717Y801583D01*
X1031467Y801000D01*
X1030967Y800667D01*
X1030300Y800500D01*
X1029717Y800583D01*
X1029133Y800833D01*
X1028800Y801167D01*
G01X1035900Y800500D02*
Y805500D01*
G01X1040083Y803833D02*
Y801500D01*
X1040417Y800917D01*
X1040917Y800583D01*
X1041500Y800500D01*
X1042083Y800583D01*
X1042583Y800917D01*
X1042917Y801500D01*
G01Y800500D02*
Y803833D01*
G01X1045933Y799250D02*
X1046517Y798917D01*
X1047183Y798833D01*
X1047767Y798917D01*
X1048267Y799333D01*
X1048600Y799917D01*
Y803833D01*
G01Y803167D02*
X1048267Y803500D01*
X1047767Y803750D01*
X1047183Y803833D01*
X1046517Y803667D01*
X1046100Y803333D01*
X1045767Y802750D01*
X1045600Y802167D01*
X1045683Y801667D01*
X1046017Y801083D01*
X1046517Y800667D01*
X1047183Y800500D01*
X1047683Y800583D01*
X1048267Y800917D01*
X1048600Y801250D01*
G01X1051533Y799250D02*
X1052117Y798917D01*
X1052783Y798833D01*
X1053367Y798917D01*
X1053867Y799333D01*
X1054200Y799917D01*
Y803833D01*
G01Y803167D02*
X1053867Y803500D01*
X1053367Y803750D01*
X1052783Y803833D01*
X1052117Y803667D01*
X1051700Y803333D01*
X1051367Y802750D01*
X1051200Y802167D01*
X1051283Y801667D01*
X1051617Y801083D01*
X1052117Y800667D01*
X1052783Y800500D01*
X1053283Y800583D01*
X1053867Y800917D01*
X1054200Y801250D01*
G01X1058300Y803833D02*
Y800500D01*
G01Y805167D02*
X1058133Y805250D01*
Y805417D01*
X1058300Y805500D01*
X1058467Y805417D01*
Y805250D01*
X1058300Y805167D01*
G01X1062483Y800500D02*
Y803833D01*
G01Y803000D02*
X1062817Y803417D01*
X1063317Y803750D01*
X1063983Y803833D01*
X1064567Y803750D01*
X1065067Y803417D01*
X1065317Y802833D01*
Y800500D01*
G01X1068333Y799250D02*
X1068917Y798917D01*
X1069583Y798833D01*
X1070167Y798917D01*
X1070667Y799333D01*
X1071000Y799917D01*
Y803833D01*
G01Y803167D02*
X1070667Y803500D01*
X1070167Y803750D01*
X1069583Y803833D01*
X1068917Y803667D01*
X1068500Y803333D01*
X1068167Y802750D01*
X1068000Y802167D01*
X1068083Y801667D01*
X1068417Y801083D01*
X1068917Y800667D01*
X1069583Y800500D01*
X1070083Y800583D01*
X1070667Y800917D01*
X1071000Y801250D01*
G01X1136167Y230700D02*
Y235700D01*
X1137833D01*
X1138500Y235450D01*
X1139000Y235117D01*
X1139417Y234617D01*
X1139750Y234033D01*
X1139833Y233200D01*
X1139750Y232367D01*
X1139417Y231783D01*
X1139000Y231283D01*
X1138500Y230950D01*
X1137833Y230700D01*
X1136167D01*
G01X1142017Y234867D02*
X1142517Y235367D01*
X1143100Y235617D01*
X1143767Y235700D01*
X1144600Y235533D01*
X1145183Y235117D01*
X1145350Y234617D01*
X1145267Y234117D01*
X1144933Y233700D01*
X1143267Y232867D01*
X1142517Y232283D01*
X1142017Y231450D01*
X1141850Y230700D01*
X1145350D01*
G01X1090833Y167000D02*
Y162000D01*
X1094167D01*
G01X1096850Y165333D02*
X1099350Y162000D01*
G01Y165333D02*
X1096850Y162000D01*
G01X1103700Y161833D02*
X1103533Y161917D01*
Y162083D01*
X1103700Y162167D01*
X1103867Y162083D01*
Y161917D01*
X1103700Y161833D01*
G01Y164083D02*
X1103533Y164167D01*
Y164333D01*
X1103700Y164417D01*
X1103867Y164333D01*
Y164167D01*
X1103700Y164083D01*
G01X1112400Y162000D02*
Y165333D01*
G01Y164417D02*
X1112650Y164833D01*
X1113067Y165167D01*
X1113650Y165333D01*
X1114233Y165167D01*
X1114650Y164833D01*
X1114900Y164417D01*
Y162000D01*
G01Y164417D02*
X1115150Y164833D01*
X1115567Y165167D01*
X1116150Y165333D01*
X1116733Y165167D01*
X1117150Y164833D01*
X1117400Y164333D01*
Y162000D01*
G01X1119083Y165333D02*
Y163000D01*
X1119417Y162417D01*
X1119917Y162083D01*
X1120500Y162000D01*
X1121083Y162083D01*
X1121583Y162417D01*
X1121917Y163000D01*
G01Y162000D02*
Y165333D01*
G01X1124850Y162583D02*
X1125267Y162250D01*
X1125850Y162000D01*
X1126350D01*
X1126850Y162167D01*
X1127183Y162417D01*
X1127350Y162750D01*
X1127267Y163250D01*
X1126933Y163500D01*
X1125433Y164000D01*
X1125100Y164583D01*
X1125267Y165000D01*
X1125600Y165250D01*
X1126100Y165333D01*
X1126600Y165250D01*
X1127100Y165000D01*
G01X1131700Y167000D02*
Y162000D01*
G01X1130533Y165333D02*
X1132867D01*
G01X1141400Y162000D02*
Y167000D01*
G01Y164500D02*
X1141817Y165000D01*
X1142317Y165250D01*
X1142817Y165333D01*
X1143567Y165167D01*
X1144067Y164833D01*
X1144400Y164250D01*
Y163583D01*
X1144233Y162917D01*
X1143900Y162417D01*
X1143317Y162083D01*
X1142817Y162000D01*
X1142317Y162083D01*
X1141817Y162333D01*
X1141400Y162750D01*
G01X1147250Y164250D02*
X1149917D01*
X1149667Y164833D01*
X1149250Y165167D01*
X1148667Y165333D01*
X1148083Y165250D01*
X1147583Y165000D01*
X1147250Y164417D01*
X1147083Y163917D01*
Y163417D01*
X1147250Y162917D01*
X1147667Y162417D01*
X1148167Y162083D01*
X1148750Y162000D01*
X1149333Y162167D01*
X1149917Y162667D01*
G01X1158200Y162000D02*
Y167000D01*
G01Y164500D02*
X1158617Y165000D01*
X1159117Y165250D01*
X1159617Y165333D01*
X1160367Y165167D01*
X1160867Y164833D01*
X1161200Y164250D01*
Y163583D01*
X1161033Y162917D01*
X1160700Y162417D01*
X1160117Y162083D01*
X1159617Y162000D01*
X1159117Y162083D01*
X1158617Y162333D01*
X1158200Y162750D01*
G01X1164133Y162000D02*
Y165333D01*
G01Y164667D02*
X1164550Y165000D01*
X1164967Y165250D01*
X1165550Y165333D01*
X1165967Y165250D01*
X1166467Y165000D01*
G01X1170900Y162000D02*
X1170400Y162083D01*
X1169900Y162417D01*
X1169567Y163000D01*
X1169400Y163667D01*
X1169567Y164333D01*
X1169900Y164917D01*
X1170400Y165250D01*
X1170900Y165333D01*
X1171400Y165250D01*
X1171900Y164917D01*
X1172233Y164333D01*
X1172317Y163667D01*
X1172233Y163000D01*
X1171900Y162417D01*
X1171400Y162083D01*
X1170900Y162000D01*
G01X1175083D02*
Y167000D01*
G01X1177750Y165333D02*
X1175083Y163417D01*
G01X1176167Y164167D02*
X1177917Y162000D01*
G01X1180850Y164250D02*
X1183517D01*
X1183267Y164833D01*
X1182850Y165167D01*
X1182267Y165333D01*
X1181683Y165250D01*
X1181183Y165000D01*
X1180850Y164417D01*
X1180683Y163917D01*
Y163417D01*
X1180850Y162917D01*
X1181267Y162417D01*
X1181767Y162083D01*
X1182350Y162000D01*
X1182933Y162167D01*
X1183517Y162667D01*
G01X1186283Y162000D02*
Y165333D01*
G01Y164500D02*
X1186617Y164917D01*
X1187117Y165250D01*
X1187783Y165333D01*
X1188367Y165250D01*
X1188867Y164917D01*
X1189117Y164333D01*
Y162000D01*
G01X1198900D02*
Y167000D01*
G01X1206000Y162000D02*
Y165333D01*
G01Y164750D02*
X1205667Y165083D01*
X1205167Y165250D01*
X1204583Y165333D01*
X1204000Y165167D01*
X1203500Y164833D01*
X1203167Y164333D01*
X1203000Y163667D01*
X1203167Y163000D01*
X1203500Y162500D01*
X1204000Y162167D01*
X1204583Y162000D01*
X1205167Y162083D01*
X1205667Y162333D01*
X1206000Y162667D01*
G01X1208350Y160500D02*
X1208850Y160333D01*
X1209517Y160500D01*
X1209933Y160833D01*
X1210267Y161250D01*
X1210767Y162583D01*
X1211850Y165333D01*
G01X1209183D02*
X1210767Y162583D01*
G01X1214450Y164250D02*
X1217117D01*
X1216867Y164833D01*
X1216450Y165167D01*
X1215867Y165333D01*
X1215283Y165250D01*
X1214783Y165000D01*
X1214450Y164417D01*
X1214283Y163917D01*
Y163417D01*
X1214450Y162917D01*
X1214867Y162417D01*
X1215367Y162083D01*
X1215950Y162000D01*
X1216533Y162167D01*
X1217117Y162667D01*
G01X1220133Y162000D02*
Y165333D01*
G01Y164667D02*
X1220550Y165000D01*
X1220967Y165250D01*
X1221550Y165333D01*
X1221967Y165250D01*
X1222467Y165000D01*
G01X1090833Y184000D02*
Y179000D01*
X1094167D01*
G01X1096683D02*
Y182333D01*
G01Y181500D02*
X1097017Y181917D01*
X1097517Y182250D01*
X1098183Y182333D01*
X1098767Y182250D01*
X1099267Y181917D01*
X1099517Y181333D01*
Y179000D01*
G01X1103700Y178833D02*
X1103533Y178917D01*
Y179083D01*
X1103700Y179167D01*
X1103867Y179083D01*
Y178917D01*
X1103700Y178833D01*
G01Y181083D02*
X1103533Y181167D01*
Y181333D01*
X1103700Y181417D01*
X1103867Y181333D01*
Y181167D01*
X1103700Y181083D01*
G01X1116233Y181917D02*
X1115650Y182250D01*
X1115150Y182333D01*
X1114483Y182167D01*
X1113983Y181833D01*
X1113650Y181250D01*
X1113567Y180667D01*
X1113650Y180083D01*
X1113983Y179583D01*
X1114483Y179167D01*
X1115150Y179000D01*
X1115733Y179167D01*
X1116233Y179500D01*
G01X1122000Y179000D02*
Y182333D01*
G01Y181750D02*
X1121667Y182083D01*
X1121167Y182250D01*
X1120583Y182333D01*
X1120000Y182167D01*
X1119500Y181833D01*
X1119167Y181333D01*
X1119000Y180667D01*
X1119167Y180000D01*
X1119500Y179500D01*
X1120000Y179167D01*
X1120583Y179000D01*
X1121167Y179083D01*
X1121667Y179333D01*
X1122000Y179667D01*
G01X1124683Y179000D02*
Y182333D01*
G01Y181500D02*
X1125017Y181917D01*
X1125517Y182250D01*
X1126183Y182333D01*
X1126767Y182250D01*
X1127267Y181917D01*
X1127517Y181333D01*
Y179000D01*
G01X1131700Y182333D02*
X1132533Y183375D01*
Y184000D01*
X1131908D01*
Y183375D01*
X1132533D01*
G01X1137300Y184000D02*
Y179000D01*
G01X1136133Y182333D02*
X1138467D01*
G01X1147000Y179000D02*
Y184000D01*
G01Y181500D02*
X1147417Y182000D01*
X1147917Y182250D01*
X1148417Y182333D01*
X1149167Y182167D01*
X1149667Y181833D01*
X1150000Y181250D01*
Y180583D01*
X1149833Y179917D01*
X1149500Y179417D01*
X1148917Y179083D01*
X1148417Y179000D01*
X1147917Y179083D01*
X1147417Y179333D01*
X1147000Y179750D01*
G01X1152850Y181250D02*
X1155517D01*
X1155267Y181833D01*
X1154850Y182167D01*
X1154267Y182333D01*
X1153683Y182250D01*
X1153183Y182000D01*
X1152850Y181417D01*
X1152683Y180917D01*
Y180417D01*
X1152850Y179917D01*
X1153267Y179417D01*
X1153767Y179083D01*
X1154350Y179000D01*
X1154933Y179167D01*
X1155517Y179667D01*
G01X1163800Y179000D02*
Y184000D01*
G01Y181500D02*
X1164217Y182000D01*
X1164717Y182250D01*
X1165217Y182333D01*
X1165967Y182167D01*
X1166467Y181833D01*
X1166800Y181250D01*
Y180583D01*
X1166633Y179917D01*
X1166300Y179417D01*
X1165717Y179083D01*
X1165217Y179000D01*
X1164717Y179083D01*
X1164217Y179333D01*
X1163800Y179750D01*
G01X1169733Y179000D02*
Y182333D01*
G01Y181667D02*
X1170150Y182000D01*
X1170567Y182250D01*
X1171150Y182333D01*
X1171567Y182250D01*
X1172067Y182000D01*
G01X1176500Y179000D02*
X1176000Y179083D01*
X1175500Y179417D01*
X1175167Y180000D01*
X1175000Y180667D01*
X1175167Y181333D01*
X1175500Y181917D01*
X1176000Y182250D01*
X1176500Y182333D01*
X1177000Y182250D01*
X1177500Y181917D01*
X1177833Y181333D01*
X1177917Y180667D01*
X1177833Y180000D01*
X1177500Y179417D01*
X1177000Y179083D01*
X1176500Y179000D01*
G01X1180683D02*
Y184000D01*
G01X1183350Y182333D02*
X1180683Y180417D01*
G01X1181767Y181167D02*
X1183517Y179000D01*
G01X1186450Y181250D02*
X1189117D01*
X1188867Y181833D01*
X1188450Y182167D01*
X1187867Y182333D01*
X1187283Y182250D01*
X1186783Y182000D01*
X1186450Y181417D01*
X1186283Y180917D01*
Y180417D01*
X1186450Y179917D01*
X1186867Y179417D01*
X1187367Y179083D01*
X1187950Y179000D01*
X1188533Y179167D01*
X1189117Y179667D01*
G01X1191883Y179000D02*
Y182333D01*
G01Y181500D02*
X1192217Y181917D01*
X1192717Y182250D01*
X1193383Y182333D01*
X1193967Y182250D01*
X1194467Y181917D01*
X1194717Y181333D01*
Y179000D01*
G01X1204500D02*
Y184000D01*
G01X1211600Y179000D02*
Y182333D01*
G01Y181750D02*
X1211267Y182083D01*
X1210767Y182250D01*
X1210183Y182333D01*
X1209600Y182167D01*
X1209100Y181833D01*
X1208767Y181333D01*
X1208600Y180667D01*
X1208767Y180000D01*
X1209100Y179500D01*
X1209600Y179167D01*
X1210183Y179000D01*
X1210767Y179083D01*
X1211267Y179333D01*
X1211600Y179667D01*
G01X1213950Y177500D02*
X1214450Y177333D01*
X1215117Y177500D01*
X1215533Y177833D01*
X1215867Y178250D01*
X1216367Y179583D01*
X1217450Y182333D01*
G01X1214783D02*
X1216367Y179583D01*
G01X1220050Y181250D02*
X1222717D01*
X1222467Y181833D01*
X1222050Y182167D01*
X1221467Y182333D01*
X1220883Y182250D01*
X1220383Y182000D01*
X1220050Y181417D01*
X1219883Y180917D01*
Y180417D01*
X1220050Y179917D01*
X1220467Y179417D01*
X1220967Y179083D01*
X1221550Y179000D01*
X1222133Y179167D01*
X1222717Y179667D01*
G01X1225733Y179000D02*
Y182333D01*
G01Y181667D02*
X1226150Y182000D01*
X1226567Y182250D01*
X1227150Y182333D01*
X1227567Y182250D01*
X1228067Y182000D01*
G01X1135167Y388700D02*
Y393700D01*
X1136833D01*
X1137500Y393450D01*
X1138000Y393117D01*
X1138417Y392617D01*
X1138750Y392033D01*
X1138833Y391200D01*
X1138750Y390367D01*
X1138417Y389783D01*
X1138000Y389283D01*
X1137500Y388950D01*
X1136833Y388700D01*
X1135167D01*
G01X1142600D02*
Y393700D01*
X1141600Y392700D01*
G01Y388700D02*
X1143600D01*
G01X1136833Y689917D02*
X1136250Y690250D01*
X1135750Y690333D01*
X1135083Y690167D01*
X1134583Y689833D01*
X1134250Y689250D01*
X1134167Y688667D01*
X1134250Y688083D01*
X1134583Y687583D01*
X1135083Y687167D01*
X1135750Y687000D01*
X1136333Y687167D01*
X1136833Y687500D01*
G01X1141100Y687000D02*
X1140600Y687083D01*
X1140100Y687417D01*
X1139767Y688000D01*
X1139600Y688667D01*
X1139767Y689333D01*
X1140100Y689917D01*
X1140600Y690250D01*
X1141100Y690333D01*
X1141600Y690250D01*
X1142100Y689917D01*
X1142433Y689333D01*
X1142517Y688667D01*
X1142433Y688000D01*
X1142100Y687417D01*
X1141600Y687083D01*
X1141100Y687000D01*
G01X1145200Y685333D02*
Y690333D01*
G01Y689583D02*
X1145617Y690000D01*
X1146033Y690250D01*
X1146700Y690333D01*
X1147283Y690250D01*
X1147867Y689833D01*
X1148117Y689250D01*
X1148200Y688667D01*
X1148117Y688083D01*
X1147867Y687500D01*
X1147367Y687167D01*
X1146700Y687000D01*
X1146117Y687083D01*
X1145533Y687333D01*
X1145200Y687667D01*
G01X1150800Y685333D02*
Y690333D01*
G01Y689583D02*
X1151217Y690000D01*
X1151633Y690250D01*
X1152300Y690333D01*
X1152883Y690250D01*
X1153467Y689833D01*
X1153717Y689250D01*
X1153800Y688667D01*
X1153717Y688083D01*
X1153467Y687500D01*
X1152967Y687167D01*
X1152300Y687000D01*
X1151717Y687083D01*
X1151133Y687333D01*
X1150800Y687667D01*
G01X1156650Y689250D02*
X1159317D01*
X1159067Y689833D01*
X1158650Y690167D01*
X1158067Y690333D01*
X1157483Y690250D01*
X1156983Y690000D01*
X1156650Y689417D01*
X1156483Y688917D01*
Y688417D01*
X1156650Y687917D01*
X1157067Y687417D01*
X1157567Y687083D01*
X1158150Y687000D01*
X1158733Y687167D01*
X1159317Y687667D01*
G01X1162333Y687000D02*
Y690333D01*
G01Y689667D02*
X1162750Y690000D01*
X1163167Y690250D01*
X1163750Y690333D01*
X1164167Y690250D01*
X1164667Y690000D01*
G01X1109833Y670500D02*
Y675500D01*
X1111833D01*
X1112500Y675250D01*
X1113000Y674667D01*
X1113167Y674000D01*
X1113000Y673333D01*
X1112583Y672833D01*
X1111833Y672583D01*
X1109833D01*
G01X1117100Y670500D02*
Y675500D01*
G01X1121283Y673833D02*
Y671500D01*
X1121617Y670917D01*
X1122117Y670583D01*
X1122700Y670500D01*
X1123283Y670583D01*
X1123783Y670917D01*
X1124117Y671500D01*
G01Y670500D02*
Y673833D01*
G01X1127133Y669250D02*
X1127717Y668917D01*
X1128383Y668833D01*
X1128967Y668917D01*
X1129467Y669333D01*
X1129800Y669917D01*
Y673833D01*
G01Y673167D02*
X1129467Y673500D01*
X1128967Y673750D01*
X1128383Y673833D01*
X1127717Y673667D01*
X1127300Y673333D01*
X1126967Y672750D01*
X1126800Y672167D01*
X1126883Y671667D01*
X1127217Y671083D01*
X1127717Y670667D01*
X1128383Y670500D01*
X1128883Y670583D01*
X1129467Y670917D01*
X1129800Y671250D01*
G01X1132733Y669250D02*
X1133317Y668917D01*
X1133983Y668833D01*
X1134567Y668917D01*
X1135067Y669333D01*
X1135400Y669917D01*
Y673833D01*
G01Y673167D02*
X1135067Y673500D01*
X1134567Y673750D01*
X1133983Y673833D01*
X1133317Y673667D01*
X1132900Y673333D01*
X1132567Y672750D01*
X1132400Y672167D01*
X1132483Y671667D01*
X1132817Y671083D01*
X1133317Y670667D01*
X1133983Y670500D01*
X1134483Y670583D01*
X1135067Y670917D01*
X1135400Y671250D01*
G01X1139500Y673833D02*
Y670500D01*
G01Y675167D02*
X1139333Y675250D01*
Y675417D01*
X1139500Y675500D01*
X1139667Y675417D01*
Y675250D01*
X1139500Y675167D01*
G01X1143683Y670500D02*
Y673833D01*
G01Y673000D02*
X1144017Y673417D01*
X1144517Y673750D01*
X1145183Y673833D01*
X1145767Y673750D01*
X1146267Y673417D01*
X1146517Y672833D01*
Y670500D01*
G01X1149533Y669250D02*
X1150117Y668917D01*
X1150783Y668833D01*
X1151367Y668917D01*
X1151867Y669333D01*
X1152200Y669917D01*
Y673833D01*
G01Y673167D02*
X1151867Y673500D01*
X1151367Y673750D01*
X1150783Y673833D01*
X1150117Y673667D01*
X1149700Y673333D01*
X1149367Y672750D01*
X1149200Y672167D01*
X1149283Y671667D01*
X1149617Y671083D01*
X1150117Y670667D01*
X1150783Y670500D01*
X1151283Y670583D01*
X1151867Y670917D01*
X1152200Y671250D01*
G01X1163233Y673417D02*
X1162650Y673750D01*
X1162150Y673833D01*
X1161483Y673667D01*
X1160983Y673333D01*
X1160650Y672750D01*
X1160567Y672167D01*
X1160650Y671583D01*
X1160983Y671083D01*
X1161483Y670667D01*
X1162150Y670500D01*
X1162733Y670667D01*
X1163233Y671000D01*
G01X1166333Y670500D02*
Y673833D01*
G01Y673167D02*
X1166750Y673500D01*
X1167167Y673750D01*
X1167750Y673833D01*
X1168167Y673750D01*
X1168667Y673500D01*
G01X1173100Y673833D02*
Y670500D01*
G01Y675167D02*
X1172933Y675250D01*
Y675417D01*
X1173100Y675500D01*
X1173267Y675417D01*
Y675250D01*
X1173100Y675167D01*
G01X1178700Y675500D02*
Y670500D01*
G01X1177533Y673833D02*
X1179867D01*
G01X1183050Y672750D02*
X1185717D01*
X1185467Y673333D01*
X1185050Y673667D01*
X1184467Y673833D01*
X1183883Y673750D01*
X1183383Y673500D01*
X1183050Y672917D01*
X1182883Y672417D01*
Y671917D01*
X1183050Y671417D01*
X1183467Y670917D01*
X1183967Y670583D01*
X1184550Y670500D01*
X1185133Y670667D01*
X1185717Y671167D01*
G01X1188733Y670500D02*
Y673833D01*
G01Y673167D02*
X1189150Y673500D01*
X1189567Y673750D01*
X1190150Y673833D01*
X1190567Y673750D01*
X1191067Y673500D01*
G01X1195500Y673833D02*
Y670500D01*
G01Y675167D02*
X1195333Y675250D01*
Y675417D01*
X1195500Y675500D01*
X1195667Y675417D01*
Y675250D01*
X1195500Y675167D01*
G01X1202600Y670500D02*
Y673833D01*
G01Y673250D02*
X1202267Y673583D01*
X1201767Y673750D01*
X1201183Y673833D01*
X1200600Y673667D01*
X1200100Y673333D01*
X1199767Y672833D01*
X1199600Y672167D01*
X1199767Y671500D01*
X1200100Y671000D01*
X1200600Y670667D01*
X1201183Y670500D01*
X1201767Y670583D01*
X1202267Y670833D01*
X1202600Y671167D01*
G01X1106417Y805500D02*
X1108500Y800500D01*
X1110583Y805500D01*
G01X1113100D02*
X1115100D01*
G01X1114100D02*
Y800500D01*
G01X1113100D02*
X1115100D01*
G01X1118033D02*
Y805500D01*
X1120033D01*
X1120700Y805250D01*
X1121200Y804667D01*
X1121367Y804000D01*
X1121200Y803333D01*
X1120783Y802833D01*
X1120033Y802583D01*
X1118033D01*
G01X1184667Y223367D02*
X1185000Y223617D01*
X1185250Y224033D01*
X1185417Y224617D01*
X1185250Y225117D01*
X1184917Y225450D01*
X1184333Y225700D01*
X1182083D01*
Y220700D01*
X1184833D01*
X1185417Y221033D01*
X1185750Y221533D01*
X1185917Y222117D01*
X1185750Y222700D01*
X1185250Y223200D01*
X1184667Y223367D01*
X1182083D01*
G01X1187517Y220700D02*
X1189600Y225700D01*
X1191683Y220700D01*
G01X1190933Y222450D02*
X1188267D01*
G01X1197033Y225283D02*
X1196533Y225533D01*
X1195950Y225700D01*
X1195283D01*
X1194533Y225450D01*
X1193950Y225033D01*
X1193533Y224533D01*
X1193200Y223700D01*
X1193117Y222950D01*
X1193283Y222200D01*
X1193533Y221700D01*
X1194033Y221200D01*
X1194617Y220867D01*
X1195200Y220700D01*
X1195783D01*
X1196367Y220867D01*
X1196867Y221117D01*
X1197283Y221450D01*
G01X1198967Y220700D02*
Y225700D01*
G01X1202133D02*
X1198967Y222617D01*
G01X1202633Y220700D02*
X1200383Y224033D01*
G01X1210167Y220700D02*
Y225700D01*
X1211833D01*
X1212500Y225450D01*
X1213000Y225117D01*
X1213417Y224617D01*
X1213750Y224033D01*
X1213833Y223200D01*
X1213750Y222367D01*
X1213417Y221783D01*
X1213000Y221283D01*
X1212500Y220950D01*
X1211833Y220700D01*
X1210167D01*
G01X1215933D02*
Y225700D01*
X1218017D01*
X1218683Y225450D01*
X1219100Y225117D01*
X1219267Y224450D01*
X1219100Y223783D01*
X1218600Y223367D01*
X1218017Y223117D01*
X1215933D01*
G01X1218017D02*
X1219267Y220700D01*
G01X1222200Y225700D02*
X1224200D01*
G01X1223200D02*
Y220700D01*
G01X1222200D02*
X1224200D01*
G01X1227133Y225700D02*
Y220700D01*
X1230467D01*
G01X1232733Y225700D02*
Y220700D01*
X1236067D01*
G01X1259900D02*
Y224033D01*
G01Y223117D02*
X1260150Y223533D01*
X1260567Y223867D01*
X1261150Y224033D01*
X1261733Y223867D01*
X1262150Y223533D01*
X1262400Y223117D01*
Y220700D01*
G01Y223117D02*
X1262650Y223533D01*
X1263067Y223867D01*
X1263650Y224033D01*
X1264233Y223867D01*
X1264650Y223533D01*
X1264900Y223033D01*
Y220700D01*
G01X1268000Y224033D02*
Y220700D01*
G01Y225367D02*
X1267833Y225450D01*
Y225617D01*
X1268000Y225700D01*
X1268167Y225617D01*
Y225450D01*
X1268000Y225367D01*
G01X1273600Y220700D02*
Y225700D01*
G01X1277950Y221283D02*
X1278367Y220950D01*
X1278950Y220700D01*
X1279450D01*
X1279950Y220867D01*
X1280283Y221117D01*
X1280450Y221450D01*
X1280367Y221950D01*
X1280033Y222200D01*
X1278533Y222700D01*
X1278200Y223283D01*
X1278367Y223700D01*
X1278700Y223950D01*
X1279200Y224033D01*
X1279700Y223950D01*
X1280200Y223700D01*
G01X1284383Y219033D02*
X1283550Y219867D01*
X1283133Y220700D01*
Y224033D01*
X1283550Y224867D01*
X1284383Y225700D01*
G01X1288483Y220700D02*
Y225700D01*
X1292317Y220700D01*
Y225700D01*
G01X1294333Y220700D02*
Y225700D01*
X1296333D01*
X1297000Y225450D01*
X1297500Y224867D01*
X1297667Y224200D01*
X1297500Y223533D01*
X1297083Y223033D01*
X1296333Y222783D01*
X1294333D01*
G01X1301600Y225700D02*
Y220700D01*
G01X1299683Y225700D02*
X1303517D01*
G01X1305450Y220700D02*
Y225700D01*
G01X1308950D02*
Y220700D01*
G01Y223200D02*
X1305450D01*
G01X1313217Y219033D02*
X1314050Y219867D01*
X1314467Y220700D01*
Y224033D01*
X1314050Y224867D01*
X1313217Y225700D01*
G01X1210333Y291700D02*
Y286700D01*
X1213667D01*
G01X1216350Y290033D02*
X1218850Y286700D01*
G01Y290033D02*
X1216350Y286700D01*
G01X1218250Y354583D02*
X1218667Y354250D01*
X1219250Y354000D01*
X1219750D01*
X1220250Y354167D01*
X1220583Y354417D01*
X1220750Y354750D01*
X1220667Y355250D01*
X1220333Y355500D01*
X1218833Y356000D01*
X1218500Y356583D01*
X1218667Y357000D01*
X1219000Y357250D01*
X1219500Y357333D01*
X1220000Y357250D01*
X1220500Y357000D01*
G01X1225100Y359000D02*
Y354000D01*
G01X1223933Y357333D02*
X1226267D01*
G01X1229283D02*
Y355000D01*
X1229617Y354417D01*
X1230117Y354083D01*
X1230700Y354000D01*
X1231283Y354083D01*
X1231783Y354417D01*
X1232117Y355000D01*
G01Y354000D02*
Y357333D01*
G01X1234800Y354000D02*
Y359000D01*
G01Y356500D02*
X1235217Y357000D01*
X1235717Y357250D01*
X1236217Y357333D01*
X1236967Y357167D01*
X1237467Y356833D01*
X1237800Y356250D01*
Y355583D01*
X1237633Y354917D01*
X1237300Y354417D01*
X1236717Y354083D01*
X1236217Y354000D01*
X1235717Y354083D01*
X1235217Y354333D01*
X1234800Y354750D01*
G01X1247500Y354000D02*
Y359000D01*
G01X1251850Y356250D02*
X1254517D01*
X1254267Y356833D01*
X1253850Y357167D01*
X1253267Y357333D01*
X1252683Y357250D01*
X1252183Y357000D01*
X1251850Y356417D01*
X1251683Y355917D01*
Y355417D01*
X1251850Y354917D01*
X1252267Y354417D01*
X1252767Y354083D01*
X1253350Y354000D01*
X1253933Y354167D01*
X1254517Y354667D01*
G01X1257283Y354000D02*
Y357333D01*
G01Y356500D02*
X1257617Y356917D01*
X1258117Y357250D01*
X1258783Y357333D01*
X1259367Y357250D01*
X1259867Y356917D01*
X1260117Y356333D01*
Y354000D01*
G01X1263133Y352750D02*
X1263717Y352417D01*
X1264383Y352333D01*
X1264967Y352417D01*
X1265467Y352833D01*
X1265800Y353417D01*
Y357333D01*
G01Y356667D02*
X1265467Y357000D01*
X1264967Y357250D01*
X1264383Y357333D01*
X1263717Y357167D01*
X1263300Y356833D01*
X1262967Y356250D01*
X1262800Y355667D01*
X1262883Y355167D01*
X1263217Y354583D01*
X1263717Y354167D01*
X1264383Y354000D01*
X1264883Y354083D01*
X1265467Y354417D01*
X1265800Y354750D01*
G01X1269900Y359000D02*
Y354000D01*
G01X1268733Y357333D02*
X1271067D01*
G01X1274083Y354000D02*
Y359000D01*
G01Y356583D02*
X1274500Y357000D01*
X1274917Y357250D01*
X1275583Y357333D01*
X1276083Y357250D01*
X1276667Y356917D01*
X1276917Y356417D01*
Y354000D01*
G01X1280017Y354917D02*
X1282183D01*
G01Y356417D02*
X1280017D01*
G01X1285117Y356083D02*
X1285700Y356667D01*
X1286200Y357000D01*
X1286867Y357167D01*
X1287450Y357000D01*
X1287867Y356667D01*
X1288200Y356167D01*
X1288283Y355583D01*
X1288200Y355083D01*
X1287867Y354583D01*
X1287367Y354167D01*
X1286783Y354000D01*
X1286117Y354167D01*
X1285533Y354667D01*
X1285200Y355417D01*
X1285117Y356250D01*
X1285283Y357333D01*
X1285533Y357917D01*
X1285950Y358500D01*
X1286533Y358917D01*
X1287117Y359000D01*
X1287700Y358833D01*
X1288117Y358417D01*
G01X1291383Y355667D02*
X1293383D01*
G01X1292300Y356750D02*
Y354583D01*
G01X1296400Y353833D02*
X1299400Y359000D01*
G01X1302417Y355667D02*
X1304583D01*
G01X1307267Y354750D02*
X1307767Y354333D01*
X1308350Y354083D01*
X1309100Y354000D01*
X1309850Y354167D01*
X1310433Y354500D01*
X1310850Y355083D01*
X1310933Y355750D01*
X1310767Y356417D01*
X1310350Y356833D01*
X1309767Y357167D01*
X1309183Y357250D01*
X1308600Y357167D01*
X1307850Y356833D01*
X1308100Y359000D01*
X1310350D01*
G01X1312200Y354000D02*
Y357333D01*
G01Y356417D02*
X1312450Y356833D01*
X1312867Y357167D01*
X1313450Y357333D01*
X1314033Y357167D01*
X1314450Y356833D01*
X1314700Y356417D01*
Y354000D01*
G01Y356417D02*
X1314950Y356833D01*
X1315367Y357167D01*
X1315950Y357333D01*
X1316533Y357167D01*
X1316950Y356833D01*
X1317200Y356333D01*
Y354000D01*
G01X1320300Y357333D02*
Y354000D01*
G01Y358667D02*
X1320133Y358750D01*
Y358917D01*
X1320300Y359000D01*
X1320467Y358917D01*
Y358750D01*
X1320300Y358667D01*
G01X1325900Y354000D02*
Y359000D01*
G01X1207333Y333500D02*
Y328500D01*
X1210667D01*
G01X1213183D02*
Y331833D01*
G01Y331000D02*
X1213517Y331417D01*
X1214017Y331750D01*
X1214683Y331833D01*
X1215267Y331750D01*
X1215767Y331417D01*
X1216017Y330833D01*
Y328500D01*
G01X1178750Y388500D02*
Y393500D01*
G01X1182250D02*
Y388500D01*
G01Y391000D02*
X1178750D01*
G01X1186100Y388500D02*
X1185433Y388583D01*
X1184850Y388917D01*
X1184350Y389417D01*
X1184017Y390000D01*
X1183850Y390667D01*
Y391333D01*
X1184017Y392000D01*
X1184350Y392583D01*
X1184850Y393083D01*
X1185433Y393417D01*
X1186100Y393500D01*
X1186767Y393417D01*
X1187350Y393083D01*
X1187850Y392583D01*
X1188183Y392000D01*
X1188350Y391333D01*
Y390667D01*
X1188183Y390000D01*
X1187850Y389417D01*
X1187350Y388917D01*
X1186767Y388583D01*
X1186100Y388500D01*
G01X1190033Y393500D02*
Y388500D01*
X1193367D01*
G01X1198967D02*
X1195633D01*
Y393500D01*
X1198967D01*
G01X1197633Y391083D02*
X1195633D01*
G01X1222800Y388500D02*
Y391833D01*
G01Y390917D02*
X1223050Y391333D01*
X1223467Y391667D01*
X1224050Y391833D01*
X1224633Y391667D01*
X1225050Y391333D01*
X1225300Y390917D01*
Y388500D01*
G01Y390917D02*
X1225550Y391333D01*
X1225967Y391667D01*
X1226550Y391833D01*
X1227133Y391667D01*
X1227550Y391333D01*
X1227800Y390833D01*
Y388500D01*
G01X1230900Y391833D02*
Y388500D01*
G01Y393167D02*
X1230733Y393250D01*
Y393417D01*
X1230900Y393500D01*
X1231067Y393417D01*
Y393250D01*
X1230900Y393167D01*
G01X1236500Y388500D02*
Y393500D01*
G01X1240850Y389083D02*
X1241267Y388750D01*
X1241850Y388500D01*
X1242350D01*
X1242850Y388667D01*
X1243183Y388917D01*
X1243350Y389250D01*
X1243267Y389750D01*
X1242933Y390000D01*
X1241433Y390500D01*
X1241100Y391083D01*
X1241267Y391500D01*
X1241600Y391750D01*
X1242100Y391833D01*
X1242600Y391750D01*
X1243100Y391500D01*
G01X1247283Y386833D02*
X1246450Y387667D01*
X1246033Y388500D01*
Y391833D01*
X1246450Y392667D01*
X1247283Y393500D01*
G01X1251633Y388500D02*
Y393500D01*
X1253633D01*
X1254300Y393250D01*
X1254800Y392667D01*
X1254967Y392000D01*
X1254800Y391333D01*
X1254383Y390833D01*
X1253633Y390583D01*
X1251633D01*
G01X1258900Y393500D02*
Y388500D01*
G01X1256983Y393500D02*
X1260817D01*
G01X1262750Y388500D02*
Y393500D01*
G01X1266250D02*
Y388500D01*
G01Y391000D02*
X1262750D01*
G01X1270517Y386833D02*
X1271350Y387667D01*
X1271767Y388500D01*
Y391833D01*
X1271350Y392667D01*
X1270517Y393500D01*
G01X1180417Y804500D02*
X1182500Y799500D01*
X1184583Y804500D01*
G01X1188100Y799500D02*
X1187433Y799583D01*
X1186850Y799917D01*
X1186350Y800417D01*
X1186017Y801000D01*
X1185850Y801667D01*
Y802333D01*
X1186017Y803000D01*
X1186350Y803583D01*
X1186850Y804083D01*
X1187433Y804417D01*
X1188100Y804500D01*
X1188767Y804417D01*
X1189350Y804083D01*
X1189850Y803583D01*
X1190183Y803000D01*
X1190350Y802333D01*
Y801667D01*
X1190183Y801000D01*
X1189850Y800417D01*
X1189350Y799917D01*
X1188767Y799583D01*
X1188100Y799500D01*
G01X1192033D02*
Y804500D01*
X1194033D01*
X1194700Y804250D01*
X1195200Y803667D01*
X1195367Y803000D01*
X1195200Y802333D01*
X1194783Y801833D01*
X1194033Y801583D01*
X1192033D01*
G54D12*
G01X898852Y782354D02*
Y705354D01*
G01D02*
X942852D01*
G01X907102Y698479D02*
Y705354D01*
G01X891977Y698479D02*
X907102D01*
G01X891977Y791979D02*
Y698479D01*
G01X865852Y782354D02*
Y705354D01*
G01X872727Y698479D02*
Y791979D01*
G01X857602Y698479D02*
X872727D01*
G01X857602Y705354D02*
Y698479D01*
G01X865852Y705354D02*
X843852D01*
G01D02*
Y782354D01*
G01X942852D02*
X898852D01*
G01X907102Y785104D02*
Y791979D01*
G01D02*
X891977D01*
G01X857602D02*
Y785104D01*
G01X872727Y791979D02*
X857602D01*
G01X843852Y782354D02*
X865852D01*
G01X984102Y698479D02*
Y705354D01*
G01X975852Y782354D02*
Y705354D01*
G01D02*
X1019852D01*
G01X968977Y698479D02*
X984102D01*
G01X968977Y791979D02*
Y698479D01*
G01X949727D02*
Y791979D01*
G01X934602Y698479D02*
X949727D01*
G01X934602Y705354D02*
Y698479D01*
G01X942852Y705354D02*
Y782354D01*
G01X984102Y785104D02*
Y791979D01*
G01X1019852Y782354D02*
X975852D01*
G01X984102Y791979D02*
X968977D01*
G01X934602D02*
Y785104D01*
G01X949727Y791979D02*
X934602D01*
G01X1061102Y698479D02*
Y705354D01*
G01X1045977Y698479D02*
X1061102D01*
G01X1045977Y789229D02*
Y698479D01*
G01X1052852Y782354D02*
Y705354D01*
G01D02*
X1096852D01*
G01X1026727Y698479D02*
Y789229D01*
G01X1019852Y705354D02*
Y782354D01*
G01X1011602Y698479D02*
X1026727D01*
G01X1011602Y705354D02*
Y698479D01*
G01X1061102Y789229D02*
X1045977D01*
G01X1061102Y782354D02*
Y789229D01*
G01X1096852Y782354D02*
X1052852D01*
G01X1011602Y789229D02*
Y782354D01*
G01X1026727Y789229D02*
X1011602D01*
G01X1165602Y698479D02*
X1180727D01*
G01X1165602Y705354D02*
Y698479D01*
G01X1129852Y782354D02*
Y705354D01*
G01D02*
X1173852D01*
G01X1138102Y698479D02*
Y705354D01*
G01X1122977Y698479D02*
X1138102D01*
G01X1096852Y705354D02*
Y782354D01*
G01X1088602Y698479D02*
X1122977D01*
G01X1088602Y705354D02*
Y698479D01*
G01X1165602Y789229D02*
Y782354D01*
G01X1180727Y789229D02*
X1165602D01*
G01X1173852Y782354D02*
X1129852D01*
G01X1138102D02*
Y789229D01*
G01D02*
X1103727D01*
G01X1088602D02*
Y782354D01*
G01X1103727Y789229D02*
X1088602D01*
G01X1250852Y705354D02*
Y782354D01*
G01X1215102Y698479D02*
Y705354D01*
G01X1206852Y782354D02*
Y705354D01*
G01D02*
X1250852D01*
G01X1199977Y698479D02*
X1215102D01*
G01X1199977Y789229D02*
Y698479D01*
G01X1180727D02*
Y789229D01*
G01X1173852Y705354D02*
Y782354D01*
G01X1215102D02*
Y789229D01*
G01X1250852Y782354D02*
X1206852D01*
G01X1215102Y789229D02*
X1199977D01*
G54D13*
G01X934327Y784390D02*
X922888Y795829D01*
G01X933755Y782629D02*
X920555Y795829D01*
G01X931422Y782629D02*
X918222Y795829D01*
G01X929088Y782629D02*
X915888Y795829D01*
G01X926754Y782629D02*
X913554Y795829D01*
G01X922727Y782629D02*
X935927Y795829D01*
G01X920394Y782629D02*
X933594Y795829D01*
G01X918061Y782629D02*
X931260Y795829D01*
G01X915727Y782629D02*
X928927Y795829D01*
G01X913394Y782629D02*
X926593Y795828D01*
G01X924420Y782629D02*
X911221Y795829D01*
G01X891779D02*
X949925D01*
G01X922087Y782629D02*
X908887Y795829D01*
G01X919754Y782629D02*
X906554Y795829D01*
G01X917420Y782629D02*
X904221Y795829D01*
G01X915087Y782629D02*
X901887Y795829D01*
G01X912754Y782629D02*
X907377Y788006D01*
G01X905840Y789543D02*
X899554Y795829D01*
G01X910421Y782629D02*
X907377Y785673D01*
G01X903507Y789543D02*
X897221Y795829D01*
G01X908086Y782629D02*
X907377Y783339D01*
G01X901173Y789543D02*
X894886Y795829D01*
G01X898840Y789543D02*
X892553Y795829D01*
G01X896507Y789543D02*
X891342Y794707D01*
G01X894172Y789543D02*
X890494Y793221D01*
G01X891927Y789455D02*
X889440Y791942D01*
G01X891702Y787347D02*
X888191Y790857D01*
G01X891702Y785014D02*
X886738Y789977D01*
G01X891702Y782680D02*
X885053Y789328D01*
G01X891702Y780347D02*
X883070Y788978D01*
G01X891702Y778014D02*
X880607Y789107D01*
G01X911061Y782629D02*
X924260Y795829D01*
G01X908727Y782629D02*
X921927Y795829D01*
G01X907377Y783613D02*
X919592Y795828D01*
G01X907377Y785946D02*
X917259Y795829D01*
G01X907377Y788280D02*
X914926Y795829D01*
G01X906307Y789543D02*
X912592Y795828D01*
G01X903972Y789543D02*
X910259Y795829D01*
G01X901639Y789543D02*
X907926Y795829D01*
G01X899306Y789543D02*
X905593Y795829D01*
G01X896972Y789543D02*
X903258Y795829D01*
G01X894639Y789543D02*
X900925Y795829D01*
G01X892306Y789543D02*
X898592Y795829D01*
G01X892015Y789543D02*
X891702Y789229D01*
G01X907157Y789543D02*
X892015D01*
G01X907377Y789504D02*
X907157Y789543D01*
G01X907377Y782629D02*
Y789504D01*
G01X934327Y782629D02*
X907377D01*
G01X891702Y745345D02*
X891096Y745951D01*
G01X890957Y746193D02*
X891702Y746936D01*
G01X889988Y747557D02*
X891702Y749270D01*
G01X888823Y748725D02*
X891702Y751604D01*
G01X887462Y749697D02*
X891702Y753937D01*
G01X885887Y750455D02*
X891702Y756270D01*
G01X884054Y750956D02*
X891702Y758604D01*
G01X881854Y751089D02*
X891702Y760937D01*
G01Y744644D02*
X891701Y744645D01*
G01X891702Y789229D02*
Y744644D01*
G01X856340Y795829D02*
X872925D01*
G01X891702Y775679D02*
X876553Y790829D01*
G01X874327Y793054D02*
X871552Y795829D01*
G01X891702Y773346D02*
X869219Y795829D01*
G01X891702Y771013D02*
X866886Y795829D01*
G01X891702Y768679D02*
X873002Y787379D01*
G01X871152Y789229D02*
X864552Y795829D01*
G01X891702Y766346D02*
X873002Y785046D01*
G01X868819Y789229D02*
X862219Y795829D01*
G01X891702Y764013D02*
X873002Y782712D01*
G01X866485Y789229D02*
X859885Y795829D01*
G01X891702Y761679D02*
X873002Y780379D01*
G01X864151Y789229D02*
X857551Y795829D01*
G01X891702Y759346D02*
X873002Y778046D01*
G01X861818Y789229D02*
X855779Y795267D01*
G01X891702Y757012D02*
X873002Y775711D01*
G01X859485Y789229D02*
X854613Y794101D01*
G01X891702Y754678D02*
X873002Y773378D01*
G01X857327Y789053D02*
X853752Y792628D01*
G01X891702Y752345D02*
X873002Y771045D01*
G01X857327Y786720D02*
X853752Y790295D01*
G01X891702Y750012D02*
X873002Y768711D01*
G01X857327Y784387D02*
X853752Y787961D01*
G01X856750Y782629D02*
X853752Y785628D01*
G01X854417Y782629D02*
X853752Y783295D01*
G01X873002Y760905D02*
X891702Y779604D01*
G01X873002Y763238D02*
X891702Y781938D01*
G01X873002Y765572D02*
X891702Y784272D01*
G01X873002Y767906D02*
X891702Y786605D01*
G01X873002Y770239D02*
X891702Y788939D01*
G01X873002Y772572D02*
X896258Y795829D01*
G01X873002Y774906D02*
X893925Y795829D01*
G01X873002Y777239D02*
X885106Y789344D01*
G01X873002Y779572D02*
X882382Y788952D01*
G01X873002Y781907D02*
X880270Y789174D01*
G01X873002Y784240D02*
X878496Y789734D01*
G01X873002Y786573D02*
X876971Y790542D01*
G01X873002Y788907D02*
X875655Y791560D01*
G01X870991Y789229D02*
X874536Y792775D01*
G01X868658Y789229D02*
X873618Y794189D01*
G01X866324Y789229D02*
X872924Y795829D01*
G01X863991Y789229D02*
X870591Y795829D01*
G01X855058Y782629D02*
X857327Y784899D01*
G01X861658Y789229D02*
X868258Y795829D01*
G01X853752Y783657D02*
X857327Y787232D01*
G01X859323Y789229D02*
X865923Y795829D01*
G01X853752Y785991D02*
X863590Y795829D01*
G01X853752Y788324D02*
X861257Y795829D01*
G01X853752Y790657D02*
X858923Y795829D01*
G01X853752Y792991D02*
X856590Y795829D01*
G01X872925D02*
G03X891779I9427J3024D01*
G01X853752Y793240D02*
X856340Y795829D01*
G01X853752Y782629D02*
Y793240D01*
G01X857327Y782629D02*
X853752D01*
G01X857327Y789504D02*
Y782629D01*
G01X857602Y789229D02*
X857327Y789504D01*
G01X873002Y789229D02*
X857602D01*
G01X891702Y747678D02*
X873002Y766378D01*
G01X887198Y749848D02*
X873002Y764045D01*
G01X883703Y751010D02*
X873002Y761711D01*
G01X881330Y751049D02*
X873002Y759377D01*
G01X879392Y750653D02*
X873002Y757044D01*
G01X877738Y749974D02*
X873002Y754711D01*
G01X876310Y749069D02*
X873002Y752377D01*
G01X875080Y747966D02*
X873002Y750044D01*
G01X874045Y746668D02*
X873002Y747711D01*
G01X873215Y745163D02*
X873002Y745377D01*
G01X878929Y750497D02*
X891702Y763270D01*
G01X873002Y746905D02*
X891702Y765603D01*
G01X873002Y749238D02*
X891702Y767938D01*
G01X873002Y751571D02*
X891702Y770271D01*
G01X873002Y753905D02*
X891702Y772604D01*
G01X873002Y756238D02*
X891702Y774938D01*
G01X873002Y758571D02*
X891702Y777271D01*
G01X873002Y744644D02*
Y789229D01*
G01Y744645D02*
Y744644D01*
G01X891701Y744645D02*
G03X873003I-9349J-3541D01*
G01X987952Y702764D02*
X985637Y705078D01*
G01X987952Y700431D02*
X984377Y704006D01*
G01X987952Y698098D02*
X984377Y701673D01*
G01X987225Y696490D02*
X984377Y699338D01*
G01X986058Y695324D02*
X983178Y698204D01*
G01X984377Y699605D02*
X987952Y703180D01*
G01X984377Y701938D02*
X987517Y705079D01*
G01X984377Y704272D02*
X985184Y705079D01*
G01X987952D02*
Y697218D01*
G01X984377Y705079D02*
X987952D01*
G01X984377Y698204D02*
Y705079D01*
G01X984420Y694629D02*
X980845Y698204D01*
G01X984069Y694629D02*
X987952Y698512D01*
G01X981735Y694629D02*
X987952Y700845D01*
G01X979402Y694629D02*
X982977Y698204D01*
G01X987952Y697218D02*
X985362Y694629D01*
G01X968702Y729014D02*
X950002Y747714D01*
G01Y728233D02*
X968702Y746932D01*
G01Y726681D02*
X950002Y745381D01*
G01X968702Y724348D02*
X950002Y743048D01*
G01X968702Y722014D02*
X950002Y740714D01*
G01X968702Y719681D02*
X950002Y738381D01*
G01X968702Y717348D02*
X950002Y736048D01*
G01X968702Y715013D02*
X950002Y733713D01*
G01X968702Y712680D02*
X950002Y731380D01*
G01X968702Y710347D02*
X950002Y729047D01*
G01X982086Y694629D02*
X978512Y698204D01*
G01X968702Y708014D02*
X950002Y726713D01*
G01X979752Y694629D02*
X976177Y698204D01*
G01X968702Y705680D02*
X950002Y724380D01*
G01X968702Y703347D02*
X950002Y722047D01*
G01X968702Y701014D02*
X950002Y719713D01*
G01X968702Y698679D02*
X950002Y717379D01*
G01Y700232D02*
X968702Y718932D01*
G01X950002Y702565D02*
X968702Y721265D01*
G01X950002Y704898D02*
X968702Y723598D01*
G01X950002Y707232D02*
X968702Y725931D01*
G01X950002Y709565D02*
X968702Y728265D01*
G01X950002Y711898D02*
X968702Y730598D01*
G01X950002Y714232D02*
X968702Y732931D01*
G01X950002Y716565D02*
X968702Y735265D01*
G01X950002Y718899D02*
X968702Y737599D01*
G01X950002Y721233D02*
X968702Y739932D01*
G01X950002Y723566D02*
X968702Y742266D01*
G01X950002Y725899D02*
X968702Y744599D01*
G01Y698204D02*
X984377D01*
G01X968702Y789504D02*
Y698204D01*
G01X950002D02*
Y789504D01*
G01X977419Y694629D02*
X973844Y698204D01*
G01X975085Y694629D02*
X971511Y698204D01*
G01X972752Y694629D02*
X969177Y698204D01*
G01X970419Y694629D02*
X950002Y715046D01*
G01X968086Y694629D02*
X950002Y712712D01*
G01X965752Y694629D02*
X950002Y710379D01*
G01X963419Y694629D02*
X950002Y708046D01*
G01X961085Y694629D02*
X950002Y705712D01*
G01X958751Y694629D02*
X950002Y703379D01*
G01X956418Y694629D02*
X950002Y701046D01*
G01X954085Y694629D02*
X950002Y698711D01*
G01X951751Y694629D02*
X948176Y698204D01*
G01X977068Y694629D02*
X980642Y698204D01*
G01X974734Y694629D02*
X978309Y698204D01*
G01X972401Y694629D02*
X975976Y698204D01*
G01X970068Y694629D02*
X973643Y698204D01*
G01X967734Y694629D02*
X971309Y698204D01*
G01X965401Y694629D02*
X968976Y698204D01*
G01X963068Y694629D02*
X968702Y700263D01*
G01X960733Y694629D02*
X968702Y702597D01*
G01X958400Y694629D02*
X968702Y704931D01*
G01X956067Y694629D02*
X968702Y707264D01*
G01X953733Y694629D02*
X968702Y709597D01*
G01X951400Y694629D02*
X968702Y711931D01*
G01X949067Y694629D02*
X968702Y714264D01*
G01X946733Y694629D02*
X968702Y716597D01*
G01X949418Y694629D02*
X945843Y698204D01*
G01X947085Y694629D02*
X943510Y698204D01*
G01X934327Y705053D02*
X934300Y705079D01*
G01X934327Y702720D02*
X931967Y705079D01*
G01X934327Y700387D02*
X930752Y703961D01*
G01X933037Y694933D02*
X936307Y698204D01*
G01X931869Y696100D02*
X934327Y698556D01*
G01X930752Y697315D02*
X934327Y700890D01*
G01X930752Y699649D02*
X934327Y703224D01*
G01X930752Y701983D02*
X933848Y705079D01*
G01X930752Y704316D02*
X931515Y705079D01*
G01X934327Y698204D02*
X950002D01*
G01X934327Y705079D02*
Y698204D01*
G01X930752Y705079D02*
X934327D01*
G01X930752Y697218D02*
Y705079D01*
G01X944750Y694629D02*
X941175Y698204D01*
G01X942417Y694629D02*
X938842Y698204D01*
G01X940084Y694629D02*
X936509Y698204D01*
G01X937750Y694629D02*
X930752Y701627D01*
G01X935417Y694629D02*
X930752Y699294D01*
G01X944400Y694629D02*
X947975Y698204D01*
G01X942066Y694629D02*
X945640Y698203D01*
G01X939733Y694629D02*
X943307Y698204D01*
G01X937399Y694629D02*
X940974Y698203D01*
G01X935066Y694629D02*
X938640Y698203D01*
G01X985362Y694629D02*
X933340D01*
G01D02*
X930752Y697218D01*
G01X987952Y791436D02*
X983558Y795829D01*
G01X987952Y789102D02*
X981224Y795829D01*
G01X987952Y784435D02*
X984377Y788009D01*
G01X987424Y782629D02*
X984377Y785676D01*
G01X985091Y782629D02*
X984377Y783343D01*
G01X985731Y782629D02*
X987952Y784850D01*
G01X984377Y783608D02*
X987952Y787183D01*
G01X984377Y785942D02*
X987952Y789517D01*
G01X984377Y788276D02*
X987952Y791851D01*
G01X983271Y789504D02*
X987480Y793712D01*
G01X980938Y789504D02*
X986313Y794879D01*
G01X984377Y782629D02*
Y789504D01*
G01X987952Y782629D02*
X984377D01*
G01X987952Y793240D02*
Y782629D01*
G01X985362Y795829D02*
X987952Y793240D01*
G01Y786769D02*
X978891Y795829D01*
G01X968779D02*
X985362D01*
G01X982883Y789504D02*
X976558Y795829D01*
G01X980549Y789504D02*
X974224Y795829D01*
G01X978216Y789504D02*
X971891Y795829D01*
G01X975883Y789504D02*
X969558Y795829D01*
G01X973548Y789504D02*
X968343Y794709D01*
G01X971215Y789504D02*
X967496Y793223D01*
G01X968882Y789504D02*
X966442Y791943D01*
G01X968702Y787350D02*
X965193Y790859D01*
G01X968702Y785017D02*
X963741Y789978D01*
G01X968702Y782684D02*
X962057Y789329D01*
G01X968702Y780350D02*
X960073Y788978D01*
G01X968702Y778017D02*
X957613Y789106D01*
G01X968702Y775684D02*
X953567Y790819D01*
G01X951317Y793067D02*
X948556Y795829D01*
G01X968702Y768683D02*
X950002Y787383D01*
G01X968702Y766350D02*
X950002Y785049D01*
G01X968702Y764016D02*
X950002Y782716D01*
G01X968702Y761683D02*
X950002Y780383D01*
G01Y760901D02*
X968702Y779601D01*
G01X978605Y789504D02*
X984930Y795829D01*
G01X950002Y763234D02*
X968702Y781934D01*
G01X976271Y789504D02*
X982596Y795829D01*
G01X950002Y765568D02*
X968702Y784267D01*
G01X973938Y789504D02*
X980263Y795829D01*
G01X950002Y767901D02*
X968702Y786601D01*
G01X971605Y789504D02*
X977930Y795829D01*
G01X950002Y770234D02*
X968702Y788934D01*
G01X969271Y789504D02*
X975596Y795829D01*
G01X950002Y772569D02*
X973262Y795828D01*
G01X950002Y774902D02*
X970929Y795829D01*
G01X950002Y777235D02*
X962112Y789345D01*
G01X950002Y779569D02*
X959386Y788952D01*
G01X950002Y781902D02*
X957273Y789173D01*
G01X950002Y784235D02*
X955499Y789733D01*
G01X950002Y786569D02*
X953974Y790540D01*
G01X950002Y788903D02*
X952657Y791558D01*
G01X948269Y789504D02*
X951539Y792772D01*
G01X984377Y789504D02*
X968702D01*
G01X949925Y795829D02*
G03X968779I9427J3024D01*
G01X968702Y759350D02*
X950002Y778049D01*
G01X968702Y757016D02*
X950002Y775716D01*
G01X968702Y754683D02*
X950002Y773383D01*
G01X968702Y752350D02*
X950002Y771048D01*
G01X968702Y750015D02*
X950002Y768715D01*
G01X968702Y747682D02*
X950002Y766382D01*
G01X968702Y745349D02*
X950002Y764048D01*
G01X968702Y743015D02*
X950002Y761715D01*
G01X968702Y740682D02*
X950002Y759382D01*
G01X968702Y738349D02*
X950002Y757048D01*
G01X968702Y736015D02*
X950002Y754715D01*
G01X968702Y733681D02*
X950002Y752381D01*
G01X968702Y731348D02*
X950002Y750047D01*
G01Y730566D02*
X968702Y749266D01*
G01X950002Y732899D02*
X968702Y751599D01*
G01X950002Y735234D02*
X968702Y753932D01*
G01X950002Y737567D02*
X968702Y756267D01*
G01X950002Y739900D02*
X968702Y758600D01*
G01X950002Y742234D02*
X968702Y760933D01*
G01X950002Y744567D02*
X968702Y763267D01*
G01X950002Y746900D02*
X968702Y765600D01*
G01X950002Y749233D02*
X968702Y767933D01*
G01X950002Y751567D02*
X968702Y770267D01*
G01X950002Y753901D02*
X968702Y772601D01*
G01X950002Y756234D02*
X968702Y774934D01*
G01X950002Y758568D02*
X968702Y777268D01*
G01Y773350D02*
X946222Y795829D01*
G01X968702Y771017D02*
X943889Y795829D01*
G01X947881Y789504D02*
X941556Y795829D01*
G01X945548Y789504D02*
X939223Y795829D01*
G01X943214Y789504D02*
X936889Y795829D01*
G01X940881Y789504D02*
X934556Y795829D01*
G01X938546Y789504D02*
X932223Y795829D01*
G01X936213Y789504D02*
X929888Y795829D01*
G01X934327Y789058D02*
X927555Y795829D01*
G01X934327Y786725D02*
X925222Y795829D01*
G01X945936Y789504D02*
X950619Y794187D01*
G01X943603Y789504D02*
X949925Y795826D01*
G01X941270Y789504D02*
X947595Y795829D01*
G01X932061Y782629D02*
X934327Y784894D01*
G01X938936Y789504D02*
X945261Y795829D01*
G01X929728Y782629D02*
X934327Y787228D01*
G01X936603Y789504D02*
X942928Y795829D01*
G01X927395Y782629D02*
X940595Y795829D01*
G01X925062Y782629D02*
X938260Y795829D01*
G01X934327Y789504D02*
Y782629D01*
G01X950002Y789504D02*
X934327D01*
G01X1120658Y702879D02*
X1122702Y704922D01*
G01X1118325Y702879D02*
X1122702Y707256D01*
G01X1115991Y702879D02*
X1122702Y709589D01*
G01X1113658Y702879D02*
X1122702Y711922D01*
G01X1111325Y702879D02*
X1122702Y714257D01*
G01Y784829D02*
Y702879D01*
G01X1104002Y728224D02*
X1122702Y746924D01*
G01Y729023D02*
X1104002Y747722D01*
G01X1122702Y726689D02*
X1104002Y745389D01*
G01X1122702Y724356D02*
X1104002Y743056D01*
G01X1122702Y722023D02*
X1104002Y740721D01*
G01X1122702Y719688D02*
X1104002Y738388D01*
G01X1122702Y717355D02*
X1104002Y736055D01*
G01X1108990Y702879D02*
X1122702Y716590D01*
G01X1106657Y702879D02*
X1122702Y718923D01*
G01X1104324Y702879D02*
X1122702Y721257D01*
G01X1104002Y704890D02*
X1122702Y723590D01*
G01X1104002Y707224D02*
X1122702Y725923D01*
G01X1104002Y709557D02*
X1122702Y728257D01*
G01X1104002Y711890D02*
X1122702Y730590D01*
G01X1104002Y714225D02*
X1122702Y732924D01*
G01X1104002Y716558D02*
X1122702Y735258D01*
G01X1104002Y718891D02*
X1122702Y737591D01*
G01X1104002Y721225D02*
X1122702Y739924D01*
G01X1104002Y723558D02*
X1122702Y742258D01*
G01X1104002Y725891D02*
X1122702Y744591D01*
G01Y715022D02*
X1104002Y733721D01*
G01X1122702Y712688D02*
X1104002Y731388D01*
G01X1122702Y710355D02*
X1104002Y729055D01*
G01X1122702Y708022D02*
X1104002Y726721D01*
G01X1122702Y705688D02*
X1104002Y724388D01*
G01X1122702Y703354D02*
X1104002Y722054D01*
G01X1120844Y702879D02*
X1104002Y719720D01*
G01X1118510Y702879D02*
X1104002Y717387D01*
G01X1116177Y702879D02*
X1104002Y715054D01*
G01X1113844Y702879D02*
X1104002Y712720D01*
G01X1111509Y702879D02*
X1104002Y710387D01*
G01X1109176Y702879D02*
X1104002Y708054D01*
G01X1106843Y702879D02*
X1104002Y705721D01*
G01X1104509Y702879D02*
X1104002Y703386D01*
G01X1122702Y702879D02*
X1104002D01*
G01D02*
Y784829D01*
G01X1122702Y782692D02*
X1120565Y784829D01*
G01X1122702Y780359D02*
X1118231Y784829D01*
G01X1122702Y778025D02*
X1115897Y784829D01*
G01X1122702Y775692D02*
X1113564Y784829D01*
G01X1104002Y760893D02*
X1122702Y779593D01*
G01X1104002Y763226D02*
X1122702Y781926D01*
G01X1104002Y765561D02*
X1122702Y784259D01*
G01X1104002Y767894D02*
X1120937Y784829D01*
G01X1104002Y770227D02*
X1118604Y784829D01*
G01X1104002Y772561D02*
X1116270Y784829D01*
G01X1104002Y774894D02*
X1113937Y784829D01*
G01X1104002Y777227D02*
X1111604Y784829D01*
G01X1104002Y779561D02*
X1109270Y784829D01*
G01X1104002Y781894D02*
X1106937Y784829D01*
G01X1104002Y784228D02*
X1104604Y784829D01*
G01X1122702Y773358D02*
X1111231Y784829D01*
G01X1122702Y771024D02*
X1108897Y784829D01*
G01X1122702Y768691D02*
X1106564Y784829D01*
G01X1122702Y766358D02*
X1104231Y784829D01*
G01X1122702Y764024D02*
X1104002Y782724D01*
G01X1122702Y761691D02*
X1104002Y780391D01*
G01X1122702Y759358D02*
X1104002Y778057D01*
G01X1122702Y757023D02*
X1104002Y775723D01*
G01X1122702Y754690D02*
X1104002Y773390D01*
G01X1122702Y752357D02*
X1104002Y771056D01*
G01X1122702Y750023D02*
X1104002Y768723D01*
G01Y784829D02*
X1122702D01*
G01X1104002Y730559D02*
X1122702Y749259D01*
G01X1104002Y732892D02*
X1122702Y751592D01*
G01X1104002Y735225D02*
X1122702Y753925D01*
G01X1104002Y737559D02*
X1122702Y756258D01*
G01X1104002Y739892D02*
X1122702Y758592D01*
G01X1104002Y742225D02*
X1122702Y760925D01*
G01X1104002Y744559D02*
X1122702Y763258D01*
G01X1104002Y746892D02*
X1122702Y765592D01*
G01X1104002Y749226D02*
X1122702Y767926D01*
G01X1104002Y751560D02*
X1122702Y770259D01*
G01X1104002Y753893D02*
X1122702Y772593D01*
G01X1104002Y756226D02*
X1122702Y774926D01*
G01X1104002Y758560D02*
X1122702Y777259D01*
G01Y747690D02*
X1104002Y766390D01*
G01X1122702Y745357D02*
X1104002Y764057D01*
G01X1122702Y743023D02*
X1104002Y761723D01*
G01X1122702Y740690D02*
X1104002Y759390D01*
G01X1122702Y738356D02*
X1104002Y757056D01*
G01X1122702Y736022D02*
X1104002Y754722D01*
G01X1122702Y733689D02*
X1104002Y752389D01*
G01X1122702Y731356D02*
X1104002Y750056D01*
G01X1181002Y728221D02*
X1199702Y746921D01*
G01Y729026D02*
X1181002Y747726D01*
G01X1197662Y702879D02*
X1199702Y704919D01*
G01X1195328Y702879D02*
X1199702Y707252D01*
G01X1192995Y702879D02*
X1199702Y709586D01*
G01X1190662Y702879D02*
X1199702Y711919D01*
G01X1188328Y702879D02*
X1199702Y714252D01*
G01X1185995Y702879D02*
X1199702Y716585D01*
G01X1183662Y702879D02*
X1199702Y718919D01*
G01X1181327Y702879D02*
X1199702Y721253D01*
G01X1181002Y704887D02*
X1199702Y723586D01*
G01X1181002Y707220D02*
X1199702Y725920D01*
G01X1181002Y709553D02*
X1199702Y728253D01*
G01X1181002Y711887D02*
X1199702Y730586D01*
G01X1181002Y714220D02*
X1199702Y732920D01*
G01X1181002Y716553D02*
X1199702Y735253D01*
G01X1181002Y718888D02*
X1199702Y737586D01*
G01X1181002Y721221D02*
X1199702Y739921D01*
G01X1181002Y723554D02*
X1199702Y742254D01*
G01X1181002Y725888D02*
X1199702Y744587D01*
G01Y726693D02*
X1181002Y745393D01*
G01X1199702Y724359D02*
X1181002Y743059D01*
G01X1199702Y722026D02*
X1181002Y740726D01*
G01X1199702Y719693D02*
X1181002Y738393D01*
G01X1199702Y717360D02*
X1181002Y736059D01*
G01X1199702Y715025D02*
X1181002Y733725D01*
G01X1199702Y712692D02*
X1181002Y731392D01*
G01X1199702Y710359D02*
X1181002Y729058D01*
G01X1199702Y708025D02*
X1181002Y726725D01*
G01X1199702Y705692D02*
X1181002Y724392D01*
G01X1199702Y703359D02*
X1181002Y722058D01*
G01X1197847Y702879D02*
X1181002Y719725D01*
G01X1195514Y702879D02*
X1181002Y717392D01*
G01X1193181Y702879D02*
X1181002Y715057D01*
G01X1190847Y702879D02*
X1181002Y712724D01*
G01X1188514Y702879D02*
X1181002Y710391D01*
G01X1186181Y702879D02*
X1181002Y708057D01*
G01X1183846Y702879D02*
X1181002Y705724D01*
G01X1181513Y702879D02*
X1181002Y703391D01*
G01X1199702Y702879D02*
X1181002D01*
G01X1199702Y784829D02*
Y702879D01*
G01X1181002D02*
Y784829D01*
G01Y760889D02*
X1199702Y779589D01*
G01X1181002Y763223D02*
X1199702Y781922D01*
G01X1181002Y765556D02*
X1199702Y784256D01*
G01X1181002Y767889D02*
X1197941Y784829D01*
G01X1181002Y770223D02*
X1195608Y784829D01*
G01X1181002Y772557D02*
X1193275Y784829D01*
G01X1181002Y774890D02*
X1190940Y784829D01*
G01X1181002Y777224D02*
X1188607Y784829D01*
G01X1181002Y779557D02*
X1186274Y784829D01*
G01X1181002Y781890D02*
X1183940Y784829D01*
G01X1181002Y784224D02*
X1181607Y784829D01*
G01X1199702Y782695D02*
X1197568Y784829D01*
G01X1199702Y780362D02*
X1195235Y784829D01*
G01X1199702Y778029D02*
X1192902Y784829D01*
G01X1199702Y775696D02*
X1190569Y784829D01*
G01X1199702Y773362D02*
X1188234Y784829D01*
G01X1199702Y771029D02*
X1185901Y784829D01*
G01X1199702Y768696D02*
X1183568Y784829D01*
G01X1199702Y766361D02*
X1181234Y784829D01*
G01X1199702Y764028D02*
X1181002Y782728D01*
G01X1199702Y761695D02*
X1181002Y780394D01*
G01Y784829D02*
X1199702D01*
G01X1181002Y730554D02*
X1199702Y749254D01*
G01X1181002Y732888D02*
X1199702Y751587D01*
G01X1181002Y735221D02*
X1199702Y753921D01*
G01X1181002Y737555D02*
X1199702Y756255D01*
G01X1181002Y739888D02*
X1199702Y758588D01*
G01X1181002Y742222D02*
X1199702Y760922D01*
G01X1181002Y744555D02*
X1199702Y763255D01*
G01X1181002Y746888D02*
X1199702Y765588D01*
G01X1181002Y749222D02*
X1199702Y767922D01*
G01X1181002Y751555D02*
X1199702Y770255D01*
G01X1181002Y753888D02*
X1199702Y772588D01*
G01X1181002Y756223D02*
X1199702Y774922D01*
G01X1181002Y758556D02*
X1199702Y777256D01*
G01Y759361D02*
X1181002Y778061D01*
G01X1199702Y757028D02*
X1181002Y775728D01*
G01X1199702Y754695D02*
X1181002Y773394D01*
G01X1199702Y752361D02*
X1181002Y771061D01*
G01X1199702Y750027D02*
X1181002Y768727D01*
G01X1199702Y747694D02*
X1181002Y766393D01*
G01X1199702Y745360D02*
X1181002Y764060D01*
G01X1199702Y743027D02*
X1181002Y761727D01*
G01X1199702Y740694D02*
X1181002Y759393D01*
G01X1199702Y738360D02*
X1181002Y757060D01*
G01X1199702Y736027D02*
X1181002Y754727D01*
G01X1199702Y733694D02*
X1181002Y752392D01*
G01X1199702Y731359D02*
X1181002Y750059D01*
M02*
